(kicad_pcb
	(version 20260206)
	(generator "pcbnew")
	(generator_version "10.0")
	(general
		(thickness 1.6)
		(legacy_teardrops no)
	)
	(paper "A4")
	(layers
		(0 "F.Cu" signal "TOP")
		(4 "In1.Cu" signal "L2GND")
		(6 "In2.Cu" signal "L3")
		(8 "In3.Cu" signal "L4VCC")
		(10 "In4.Cu" signal "L5VCC")
		(12 "In5.Cu" signal "L6")
		(14 "In6.Cu" signal "L7GND")
		(2 "B.Cu" signal "BOTTOM")
		(9 "F.Adhes" user "F.Adhesive")
		(11 "B.Adhes" user "B.Adhesive")
		(13 "F.Paste" user "Package Geometry/Pastemask Top")
		(15 "B.Paste" user "Package Geometry/Pastemask Bottom")
		(5 "F.SilkS" user "Ref Des/Silkscreen Top")
		(7 "B.SilkS" user "Ref Des/Silkscreen Bottom")
		(1 "F.Mask" user "Board Geometry/Soldermask Top")
		(3 "B.Mask" user "Board Geometry/Soldermask Bottom")
		(17 "Dwgs.User" user "User.Drawings")
		(19 "Cmts.User" user "User.Comments")
		(21 "Eco1.User" user "User.Eco1")
		(23 "Eco2.User" user "User.Eco2")
		(25 "Edge.Cuts" user "Board Geometry/Outline")
		(27 "Margin" user)
		(31 "F.CrtYd" user "Package Geometry/Place Bound Top")
		(29 "B.CrtYd" user "Package Geometry/Place Bound Bottom")
		(35 "F.Fab" user "Ref Des/Assembly Top")
		(33 "B.Fab" user "Ref Des/Assembly Bottom")
	)
	(setup
		(pad_to_mask_clearance 0)
		(allow_soldermask_bridges_in_footprints no)
		(tenting
			(front yes)
			(back yes)
		)
		(covering
			(front no)
			(back no)
		)
		(plugging
			(front no)
			(back no)
		)
		(capping no)
		(filling no)
		(pcbplotparams
			(layerselection 0x00000000_00000000_55555555_5755f5ff)
			(plot_on_all_layers_selection 0x00000000_00000000_00000000_00000000)
			(disableapertmacros no)
			(usegerberextensions no)
			(usegerberattributes yes)
			(usegerberadvancedattributes yes)
			(creategerberjobfile yes)
			(dashed_line_dash_ratio 12)
			(dashed_line_gap_ratio 3)
			(svgprecision 4)
			(plotframeref no)
			(mode 1)
			(useauxorigin no)
			(pdf_front_fp_property_popups yes)
			(pdf_back_fp_property_popups yes)
			(pdf_metadata yes)
			(pdf_single_document no)
			(dxfpolygonmode yes)
			(dxfimperialunits yes)
			(dxfusepcbnewfont yes)
			(psnegative no)
			(psa4output no)
			(plot_black_and_white yes)
			(sketchpadsonfab no)
			(plotpadnumbers no)
			(hidednponfab no)
			(sketchdnponfab yes)
			(crossoutdnponfab yes)
			(subtractmaskfromsilk no)
			(outputformat 1)
			(mirror no)
			(drillshape 1)
			(scaleselection 1)
			(outputdirectory "")
		)
	)
	(footprint ""
		(layer "F.Cu")
		(at 214.757 -88.9 -90)
		(property "Reference" "U13"
			(at 0 0 270)
			(layer "F.SilkS")
			(hide yes)
			(effects
				(font
					(size 1.27 1.27)
				)
			)
		)
		(property "Value" "P2003EVG-GP"
			(at 0 -11.1252 270)
			(unlocked yes)
			(layer "F.Fab")
			(hide yes)
			(effects
				(font
					(size 1.016 1.016)
					(thickness 0.1524)
				)
			)
		)
		(property "Device Type" "SOIC8H79"
			(at 0 -12.6492 270)
			(unlocked yes)
			(layer "F.Fab")
			(hide yes)
			(effects
				(font
					(size 1.016 1.016)
					(thickness 0.1524)
				)
			)
		)
		(duplicate_pad_numbers_are_jumpers no)
		(fp_line
			(start -2.6162 3.429)
			(end -2.6162 1.4732)
			(stroke
				(width 0.4064)
				(type default)
			)
			(layer "F.SilkS")
		)
		(fp_line
			(start -2.7432 1.4224)
			(end 2.1336 1.4224)
			(stroke
				(width 0.1524)
				(type default)
			)
			(layer "F.SilkS")
		)
		(fp_line
			(start 2.1336 1.4224)
			(end 2.1336 -1.4224)
			(stroke
				(width 0.1524)
				(type default)
			)
			(layer "F.SilkS")
		)
		(fp_line
			(start -2.2352 0)
			(end -2.7432 0.508)
			(stroke
				(width 0.1524)
				(type default)
			)
			(layer "F.SilkS")
		)
		(fp_line
			(start -2.7432 -0.508)
			(end -2.2352 0)
			(stroke
				(width 0.1524)
				(type default)
			)
			(layer "F.SilkS")
		)
		(fp_line
			(start -2.7432 -1.4224)
			(end -2.7432 1.4224)
			(stroke
				(width 0.1524)
				(type default)
			)
			(layer "F.SilkS")
		)
		(fp_line
			(start 2.1336 -1.4224)
			(end -2.7432 -1.4224)
			(stroke
				(width 0.1524)
				(type default)
			)
			(layer "F.SilkS")
		)
		(fp_poly
			(pts
				(xy 2.2098 -1.4224) (xy 2.2098 1.4224) (xy -2.2225 1.4224) (xy -2.2225 -1.4224)
			)
			(stroke
				(width 0)
				(type default)
			)
			(fill yes)
			(layer "F.SilkS")
		)
		(fp_rect
			(start -2.4511 2.9972)
			(end 2.4511 -2.9972)
			(stroke
				(width 0)
				(type default)
			)
			(fill no)
			(layer "F.CrtYd")
		)
		(fp_poly
			(pts
				(xy -2.8194 3.6322) (xy -2.8194 -3.6322) (xy 2.8194 -3.6322) (xy 2.8194 -2.2987) (xy 2.4511 -2.2987)
				(xy 2.4511 -2.9972) (xy -2.4511 -2.9972) (xy -2.4511 2.9972) (xy 2.4511 2.9972) (xy 2.4511 -2.286)
				(xy 2.8194 -2.286) (xy 2.8194 3.6322)
			)
			(stroke
				(width 0)
				(type default)
			)
			(fill no)
			(layer "F.CrtYd")
		)
		(fp_rect
			(start -2.8194 3.6322)
			(end 2.8194 -3.6322)
			(stroke
				(width 0)
				(type default)
			)
			(fill no)
			(layer "F.Fab")
		)
		(pad "1" smd rect
			(at -1.905 2.54 270)
			(size 0.635 1.651)
			(layers "F.Cu" "F.Mask" "F.Paste")
			(net "P12V")
		)
		(pad "2" smd rect
			(at -0.635 2.54 270)
			(size 0.635 1.651)
			(layers "F.Cu" "F.Mask" "F.Paste")
			(net "P12V")
		)
		(pad "3" smd rect
			(at 0.635 2.54 270)
			(size 0.635 1.651)
			(layers "F.Cu" "F.Mask" "F.Paste")
			(net "P12V")
		)
		(pad "4" smd rect
			(at 1.905 2.54 270)
			(size 0.635 1.651)
			(layers "F.Cu" "F.Mask" "F.Paste")
			(net "SW_SSD4_N")
		)
		(pad "5" smd rect
			(at 1.905 -2.54 270)
			(size 0.635 1.651)
			(layers "F.Cu" "F.Mask" "F.Paste")
			(net "P12V_SSD4")
		)
		(pad "6" smd rect
			(at 0.635 -2.54 270)
			(size 0.635 1.651)
			(layers "F.Cu" "F.Mask" "F.Paste")
			(net "P12V_SSD4")
		)
		(pad "7" smd rect
			(at -0.635 -2.54 270)
			(size 0.635 1.651)
			(layers "F.Cu" "F.Mask" "F.Paste")
			(net "P12V_SSD4")
		)
		(pad "8" smd rect
			(at -1.905 -2.54 270)
			(size 0.635 1.651)
			(layers "F.Cu" "F.Mask" "F.Paste")
			(net "P12V_SSD4")
		)
	)
	(footprint ""
		(layer "F.Cu")
		(at 16.129 -61.33211)
		(property "Reference" "Q98"
			(at 0 0 0)
			(layer "F.SilkS")
			(hide yes)
			(effects
				(font
					(size 1.27 1.27)
				)
			)
		)
		(property "Value" "2N7002A-7-GP"
			(at 0.127 -8.9662 0)
			(unlocked yes)
			(layer "F.Fab")
			(hide yes)
			(effects
				(font
					(size 1.016 1.016)
					(thickness 0.1524)
				)
			)
		)
		(property "Device Type" "SOT23DGS2D4H48"
			(at 0.127 -10.4902 0)
			(unlocked yes)
			(layer "F.Fab")
			(hide yes)
			(effects
				(font
					(size 1.016 1.016)
					(thickness 0.1524)
				)
			)
		)
		(duplicate_pad_numbers_are_jumpers no)
		(fp_line
			(start -1.651 -1.778)
			(end -1.651 1.778)
			(stroke
				(width 0.1524)
				(type default)
			)
			(layer "F.SilkS")
		)
		(fp_line
			(start -1.651 1.778)
			(end 1.651 1.778)
			(stroke
				(width 0.1524)
				(type default)
			)
			(layer "F.SilkS")
		)
		(fp_line
			(start 1.651 -1.778)
			(end -1.651 -1.778)
			(stroke
				(width 0.1524)
				(type default)
			)
			(layer "F.SilkS")
		)
		(fp_line
			(start 1.651 1.778)
			(end 1.651 -1.778)
			(stroke
				(width 0.1524)
				(type default)
			)
			(layer "F.SilkS")
		)
		(fp_poly
			(pts
				(xy -1.778 1.8796) (xy -1.778 -1.8796) (xy 1.778 -1.8796) (xy 1.778 1.8796)
			)
			(stroke
				(width 0)
				(type default)
			)
			(fill no)
			(layer "F.CrtYd")
		)
		(fp_poly
			(pts
				(xy -1.778 1.8796) (xy -1.778 -1.8796) (xy 1.778 -1.8796) (xy 1.778 1.8796)
			)
			(stroke
				(width 0)
				(type default)
			)
			(fill no)
			(layer "F.Fab")
		)
		(pad "D" smd custom
			(at 0 -0.9525)
			(size 0.1905 0.1905)
			(layers "F.Cu" "F.Mask" "F.Paste")
			(net "SSD_ACT_DR14_MOS_N")
			(options
				(clearance outline)
				(anchor circle)
			)
			(primitives
				(gr_poly
					(pts
						(arc
							(start -0.1778 0.5715)
							(mid -0.321484 0.511984)
							(end -0.381 0.3683)
						)
						(arc
							(start -0.381 -0.3683)
							(mid -0.321484 -0.511984)
							(end -0.1778 -0.5715)
						)
						(arc
							(start 0.1778 -0.5715)
							(mid 0.321484 -0.511984)
							(end 0.381 -0.3683)
						)
						(arc
							(start 0.381 0.3683)
							(mid 0.321484 0.511984)
							(end 0.1778 0.5715)
						)
					)
					(width 0)
					(fill yes)
				)
			)
		)
		(pad "G" smd custom
			(at -0.98425 0.9525)
			(size 0.1905 0.1905)
			(layers "F.Cu" "F.Mask" "F.Paste")
			(net "ATTN_LED_DR14_AND_R")
			(options
				(clearance outline)
				(anchor circle)
			)
			(primitives
				(gr_poly
					(pts
						(arc
							(start -0.1778 0.5715)
							(mid -0.321484 0.511984)
							(end -0.381 0.3683)
						)
						(arc
							(start -0.381 -0.3683)
							(mid -0.321484 -0.511984)
							(end -0.1778 -0.5715)
						)
						(arc
							(start 0.1778 -0.5715)
							(mid 0.321484 -0.511984)
							(end 0.381 -0.3683)
						)
						(arc
							(start 0.381 0.3683)
							(mid 0.321484 0.511984)
							(end 0.1778 0.5715)
						)
					)
					(width 0)
					(fill yes)
				)
			)
		)
		(pad "S" smd custom
			(at 0.98425 0.9525)
			(size 0.1905 0.1905)
			(layers "F.Cu" "F.Mask" "F.Paste")
			(net "SSD_ACT_DR14_R")
			(options
				(clearance outline)
				(anchor circle)
			)
			(primitives
				(gr_poly
					(pts
						(arc
							(start -0.1778 0.5715)
							(mid -0.321484 0.511984)
							(end -0.381 0.3683)
						)
						(arc
							(start -0.381 -0.3683)
							(mid -0.321484 -0.511984)
							(end -0.1778 -0.5715)
						)
						(arc
							(start 0.1778 -0.5715)
							(mid 0.321484 -0.511984)
							(end 0.381 -0.3683)
						)
						(arc
							(start 0.381 0.3683)
							(mid 0.321484 0.511984)
							(end 0.1778 0.5715)
						)
					)
					(width 0)
					(fill yes)
				)
			)
		)
	)
	(footprint ""
		(layer "F.Cu")
		(at 82.931 -105.918 90)
		(property "Reference" "SR955"
			(at 0 0 90)
			(layer "F.SilkS")
			(hide yes)
			(effects
				(font
					(size 1.27 1.27)
				)
			)
		)
		(property "Value" "4K7R2F-GP"
			(at 0.064008 -3.993896 90)
			(unlocked yes)
			(layer "F.Fab")
			(hide yes)
			(effects
				(font
					(size 1.016 1.016)
					(thickness 0.1524)
				)
			)
		)
		(property "Device Type" "R402H16"
			(at 0.064008 -5.517896 90)
			(unlocked yes)
			(layer "F.Fab")
			(hide yes)
			(effects
				(font
					(size 1.016 1.016)
					(thickness 0.1524)
				)
			)
		)
		(duplicate_pad_numbers_are_jumpers no)
		(fp_line
			(start 0.508 -0.9398)
			(end -0.508 -0.9398)
			(stroke
				(width 0.1524)
				(type default)
			)
			(layer "F.SilkS")
		)
		(fp_line
			(start -0.508 -0.9398)
			(end -0.508 0.9398)
			(stroke
				(width 0.1524)
				(type default)
			)
			(layer "F.SilkS")
		)
		(fp_rect
			(start -0.508 0.9398)
			(end 0.508 -0.9398)
			(stroke
				(width 0)
				(type default)
			)
			(fill no)
			(layer "F.CrtYd")
		)
		(fp_rect
			(start -0.508 0.9398)
			(end 0.508 -0.9398)
			(stroke
				(width 0)
				(type default)
			)
			(fill no)
			(layer "F.Fab")
		)
		(pad "1" smd custom
			(at 0 -0.4445 90)
			(size 0.1397 0.1397)
			(layers "F.Cu" "F.Mask" "F.Paste")
			(net "VDD_DIFF_4")
			(options
				(clearance outline)
				(anchor circle)
			)
			(primitives
				(gr_poly
					(pts
						(arc
							(start -0.1778 -0.2794)
							(mid -0.249642 -0.249642)
							(end -0.2794 -0.1778)
						)
						(arc
							(start -0.2794 0.1778)
							(mid -0.249642 0.249642)
							(end -0.1778 0.2794)
						)
						(arc
							(start 0.1778 0.2794)
							(mid 0.249642 0.249642)
							(end 0.2794 0.1778)
						)
						(arc
							(start 0.2794 -0.1778)
							(mid 0.249642 -0.249642)
							(end 0.1778 -0.2794)
						)
					)
					(width 0)
					(fill yes)
				)
			)
		)
		(pad "2" smd custom
			(at 0 0.4445 90)
			(size 0.1397 0.1397)
			(layers "F.Cu" "F.Mask" "F.Paste")
			(net "CLK_BUF_EU4_HIBW_BYPM_LOBW#")
			(options
				(clearance outline)
				(anchor circle)
			)
			(primitives
				(gr_poly
					(pts
						(arc
							(start -0.1778 -0.2794)
							(mid -0.249642 -0.249642)
							(end -0.2794 -0.1778)
						)
						(arc
							(start -0.2794 0.1778)
							(mid -0.249642 0.249642)
							(end -0.1778 0.2794)
						)
						(arc
							(start 0.1778 0.2794)
							(mid 0.249642 0.249642)
							(end 0.2794 0.1778)
						)
						(arc
							(start 0.2794 -0.1778)
							(mid 0.249642 -0.249642)
							(end 0.1778 -0.2794)
						)
					)
					(width 0)
					(fill yes)
				)
			)
		)
	)
	(footprint ""
		(layer "F.Cu")
		(at 227.450396 -245.341902 90)
		(property "Reference" "R9932"
			(at 0 0 90)
			(layer "F.SilkS")
			(hide yes)
			(effects
				(font
					(size 1.27 1.27)
				)
			)
		)
		(property "Value" "4K7R2J-2-GP"
			(at 0.064008 -3.993896 90)
			(unlocked yes)
			(layer "F.Fab")
			(hide yes)
			(effects
				(font
					(size 1.016 1.016)
					(thickness 0.1524)
				)
			)
		)
		(property "Device Type" "R402H16"
			(at 0.064008 -5.517896 90)
			(unlocked yes)
			(layer "F.Fab")
			(hide yes)
			(effects
				(font
					(size 1.016 1.016)
					(thickness 0.1524)
				)
			)
		)
		(duplicate_pad_numbers_are_jumpers no)
		(fp_line
			(start 0.508 -0.9398)
			(end -0.508 -0.9398)
			(stroke
				(width 0.1524)
				(type default)
			)
			(layer "F.SilkS")
		)
		(fp_line
			(start -0.508 -0.9398)
			(end -0.508 0.9398)
			(stroke
				(width 0.1524)
				(type default)
			)
			(layer "F.SilkS")
		)
		(fp_rect
			(start -0.508 0.9398)
			(end 0.508 -0.9398)
			(stroke
				(width 0)
				(type default)
			)
			(fill no)
			(layer "F.CrtYd")
		)
		(fp_rect
			(start -0.508 0.9398)
			(end 0.508 -0.9398)
			(stroke
				(width 0)
				(type default)
			)
			(fill no)
			(layer "F.Fab")
		)
		(pad "1" smd custom
			(at 0 -0.4445 90)
			(size 0.1397 0.1397)
			(layers "F.Cu" "F.Mask" "F.Paste")
			(net "P3V3")
			(options
				(clearance outline)
				(anchor circle)
			)
			(primitives
				(gr_poly
					(pts
						(arc
							(start -0.1778 -0.2794)
							(mid -0.249642 -0.249642)
							(end -0.2794 -0.1778)
						)
						(arc
							(start -0.2794 0.1778)
							(mid -0.249642 0.249642)
							(end -0.1778 0.2794)
						)
						(arc
							(start 0.1778 0.2794)
							(mid 0.249642 0.249642)
							(end 0.2794 0.1778)
						)
						(arc
							(start 0.2794 -0.1778)
							(mid 0.249642 -0.249642)
							(end 0.1778 -0.2794)
						)
					)
					(width 0)
					(fill yes)
				)
			)
		)
		(pad "2" smd custom
			(at 0 0.4445 90)
			(size 0.1397 0.1397)
			(layers "F.Cu" "F.Mask" "F.Paste")
			(net "SSD_ACT_DR2_MOS_N")
			(options
				(clearance outline)
				(anchor circle)
			)
			(primitives
				(gr_poly
					(pts
						(arc
							(start -0.1778 -0.2794)
							(mid -0.249642 -0.249642)
							(end -0.2794 -0.1778)
						)
						(arc
							(start -0.2794 0.1778)
							(mid -0.249642 0.249642)
							(end -0.1778 0.2794)
						)
						(arc
							(start 0.1778 0.2794)
							(mid 0.249642 0.249642)
							(end 0.2794 0.1778)
						)
						(arc
							(start 0.2794 -0.1778)
							(mid 0.249642 -0.249642)
							(end 0.1778 -0.2794)
						)
					)
					(width 0)
					(fill yes)
				)
			)
		)
	)
	(footprint ""
		(layer "F.Cu")
		(at 43.20032 -450.907912)
		(property "Reference" "R9938"
			(at 0 0 0)
			(layer "F.SilkS")
			(hide yes)
			(effects
				(font
					(size 1.27 1.27)
				)
			)
		)
		(property "Value" "4K7R2J-2-GP"
			(at 0.064008 -3.993896 0)
			(unlocked yes)
			(layer "F.Fab")
			(hide yes)
			(effects
				(font
					(size 1.016 1.016)
					(thickness 0.1524)
				)
			)
		)
		(property "Device Type" "R402H16"
			(at 0.064008 -5.517896 0)
			(unlocked yes)
			(layer "F.Fab")
			(hide yes)
			(effects
				(font
					(size 1.016 1.016)
					(thickness 0.1524)
				)
			)
		)
		(duplicate_pad_numbers_are_jumpers no)
		(fp_line
			(start -0.508 -0.9398)
			(end -0.508 0.9398)
			(stroke
				(width 0.1524)
				(type default)
			)
			(layer "F.SilkS")
		)
		(fp_line
			(start 0.508 -0.9398)
			(end -0.508 -0.9398)
			(stroke
				(width 0.1524)
				(type default)
			)
			(layer "F.SilkS")
		)
		(fp_rect
			(start -0.508 0.9398)
			(end 0.508 -0.9398)
			(stroke
				(width 0)
				(type default)
			)
			(fill no)
			(layer "F.CrtYd")
		)
		(fp_rect
			(start -0.508 0.9398)
			(end 0.508 -0.9398)
			(stroke
				(width 0)
				(type default)
			)
			(fill no)
			(layer "F.Fab")
		)
		(pad "1" smd custom
			(at 0 -0.4445)
			(size 0.1397 0.1397)
			(layers "F.Cu" "F.Mask" "F.Paste")
			(net "P3V3")
			(options
				(clearance outline)
				(anchor circle)
			)
			(primitives
				(gr_poly
					(pts
						(arc
							(start -0.1778 -0.2794)
							(mid -0.249642 -0.249642)
							(end -0.2794 -0.1778)
						)
						(arc
							(start -0.2794 0.1778)
							(mid -0.249642 0.249642)
							(end -0.1778 0.2794)
						)
						(arc
							(start 0.1778 0.2794)
							(mid 0.249642 0.249642)
							(end 0.2794 0.1778)
						)
						(arc
							(start 0.2794 -0.1778)
							(mid 0.249642 -0.249642)
							(end 0.1778 -0.2794)
						)
					)
					(width 0)
					(fill yes)
				)
			)
		)
		(pad "2" smd custom
			(at 0 0.4445)
			(size 0.1397 0.1397)
			(layers "F.Cu" "F.Mask" "F.Paste")
			(net "SSD_ACT_DR5_MOS_N")
			(options
				(clearance outline)
				(anchor circle)
			)
			(primitives
				(gr_poly
					(pts
						(arc
							(start -0.1778 -0.2794)
							(mid -0.249642 -0.249642)
							(end -0.2794 -0.1778)
						)
						(arc
							(start -0.2794 0.1778)
							(mid -0.249642 0.249642)
							(end -0.1778 0.2794)
						)
						(arc
							(start 0.1778 0.2794)
							(mid 0.249642 0.249642)
							(end 0.2794 0.1778)
						)
						(arc
							(start 0.2794 -0.1778)
							(mid 0.249642 -0.249642)
							(end 0.1778 -0.2794)
						)
					)
					(width 0)
					(fill yes)
				)
			)
		)
	)
	(footprint ""
		(layer "F.Cu")
		(at 219.837 -91.44 180)
		(property "Reference" "PC1202"
			(at 0 0 180)
			(layer "F.SilkS")
			(hide yes)
			(effects
				(font
					(size 1.27 1.27)
				)
			)
		)
		(property "Value" "SCD1U50V3KX-GP"
			(at 0 -2.8194 180)
			(unlocked yes)
			(layer "F.Fab")
			(hide yes)
			(effects
				(font
					(size 1.016 1.016)
					(thickness 0.1524)
				)
			)
		)
		(property "Device Type" "C603H36"
			(at 0 -4.3434 180)
			(unlocked yes)
			(layer "F.Fab")
			(hide yes)
			(effects
				(font
					(size 1.016 1.016)
					(thickness 0.1524)
				)
			)
		)
		(duplicate_pad_numbers_are_jumpers no)
		(fp_line
			(start 0.508 0)
			(end -0.508 0)
			(stroke
				(width 0.2032)
				(type default)
			)
			(layer "F.SilkS")
		)
		(fp_rect
			(start -0.5842 1.3335)
			(end 0.5842 -1.3335)
			(stroke
				(width 0)
				(type default)
			)
			(fill no)
			(layer "F.CrtYd")
		)
		(fp_rect
			(start -0.5842 1.3335)
			(end 0.5842 -1.3335)
			(stroke
				(width 0)
				(type default)
			)
			(fill no)
			(layer "F.Fab")
		)
		(pad "1" smd custom
			(at 0 -0.762 180)
			(size 0.2159 0.2159)
			(layers "F.Cu" "F.Mask" "F.Paste")
			(net "P12V_SSD4")
			(options
				(clearance outline)
				(anchor circle)
			)
			(primitives
				(gr_poly
					(pts
						(arc
							(start -0.3302 -0.4318)
							(mid -0.402042 -0.402042)
							(end -0.4318 -0.3302)
						)
						(arc
							(start -0.4318 0.3302)
							(mid -0.402042 0.402042)
							(end -0.3302 0.4318)
						)
						(arc
							(start 0.3302 0.4318)
							(mid 0.402042 0.402042)
							(end 0.4318 0.3302)
						)
						(arc
							(start 0.4318 -0.3302)
							(mid 0.402042 -0.402042)
							(end 0.3302 -0.4318)
						)
					)
					(width 0)
					(fill yes)
				)
			)
		)
		(pad "2" smd custom
			(at 0 0.762 180)
			(size 0.2159 0.2159)
			(layers "F.Cu" "F.Mask" "F.Paste")
			(net "GND")
			(options
				(clearance outline)
				(anchor circle)
			)
			(primitives
				(gr_poly
					(pts
						(arc
							(start -0.3302 -0.4318)
							(mid -0.402042 -0.402042)
							(end -0.4318 -0.3302)
						)
						(arc
							(start -0.4318 0.3302)
							(mid -0.402042 0.402042)
							(end -0.3302 0.4318)
						)
						(arc
							(start 0.3302 0.4318)
							(mid 0.402042 0.402042)
							(end 0.4318 0.3302)
						)
						(arc
							(start 0.4318 -0.3302)
							(mid 0.402042 -0.402042)
							(end 0.3302 -0.4318)
						)
					)
					(width 0)
					(fill yes)
				)
			)
		)
	)
	(footprint ""
		(layer "F.Cu")
		(at 74.422 -444.246)
		(property "Reference" "C347"
			(at 0 0 0)
			(layer "F.SilkS")
			(hide yes)
			(effects
				(font
					(size 1.27 1.27)
				)
			)
		)
		(property "Value" "SCD1U50V3KX-GP"
			(at 0 -2.8194 0)
			(unlocked yes)
			(layer "F.Fab")
			(hide yes)
			(effects
				(font
					(size 1.016 1.016)
					(thickness 0.1524)
				)
			)
		)
		(property "Device Type" "C603H36"
			(at 0 -4.3434 0)
			(unlocked yes)
			(layer "F.Fab")
			(hide yes)
			(effects
				(font
					(size 1.016 1.016)
					(thickness 0.1524)
				)
			)
		)
		(duplicate_pad_numbers_are_jumpers no)
		(fp_line
			(start 0.508 0)
			(end -0.508 0)
			(stroke
				(width 0.2032)
				(type default)
			)
			(layer "F.SilkS")
		)
		(fp_rect
			(start -0.5842 1.3335)
			(end 0.5842 -1.3335)
			(stroke
				(width 0)
				(type default)
			)
			(fill no)
			(layer "F.CrtYd")
		)
		(fp_rect
			(start -0.5842 1.3335)
			(end 0.5842 -1.3335)
			(stroke
				(width 0)
				(type default)
			)
			(fill no)
			(layer "F.Fab")
		)
		(pad "1" smd custom
			(at 0 -0.762)
			(size 0.2159 0.2159)
			(layers "F.Cu" "F.Mask" "F.Paste")
			(net "P3V3")
			(options
				(clearance outline)
				(anchor circle)
			)
			(primitives
				(gr_poly
					(pts
						(arc
							(start -0.3302 -0.4318)
							(mid -0.402042 -0.402042)
							(end -0.4318 -0.3302)
						)
						(arc
							(start -0.4318 0.3302)
							(mid -0.402042 0.402042)
							(end -0.3302 0.4318)
						)
						(arc
							(start 0.3302 0.4318)
							(mid 0.402042 0.402042)
							(end 0.4318 0.3302)
						)
						(arc
							(start 0.4318 -0.3302)
							(mid 0.402042 -0.402042)
							(end 0.3302 -0.4318)
						)
					)
					(width 0)
					(fill yes)
				)
			)
		)
		(pad "2" smd custom
			(at 0 0.762)
			(size 0.2159 0.2159)
			(layers "F.Cu" "F.Mask" "F.Paste")
			(net "GND")
			(options
				(clearance outline)
				(anchor circle)
			)
			(primitives
				(gr_poly
					(pts
						(arc
							(start -0.3302 -0.4318)
							(mid -0.402042 -0.402042)
							(end -0.4318 -0.3302)
						)
						(arc
							(start -0.4318 0.3302)
							(mid -0.402042 0.402042)
							(end -0.3302 0.4318)
						)
						(arc
							(start 0.3302 0.4318)
							(mid 0.402042 0.402042)
							(end 0.4318 0.3302)
						)
						(arc
							(start 0.4318 -0.3302)
							(mid 0.402042 -0.402042)
							(end 0.3302 -0.4318)
						)
					)
					(width 0)
					(fill yes)
				)
			)
		)
	)
	(footprint ""
		(layer "F.Cu")
		(at 50.850292 -447.167)
		(property "Reference" "SR1132"
			(at 0 0 0)
			(layer "F.SilkS")
			(hide yes)
			(effects
				(font
					(size 1.27 1.27)
				)
			)
		)
		(property "Value" "4K7R2J-2-GP"
			(at 0.064008 -3.993896 0)
			(unlocked yes)
			(layer "F.Fab")
			(hide yes)
			(effects
				(font
					(size 1.016 1.016)
					(thickness 0.1524)
				)
			)
		)
		(property "Device Type" "R402H16"
			(at 0.064008 -5.517896 0)
			(unlocked yes)
			(layer "F.Fab")
			(hide yes)
			(effects
				(font
					(size 1.016 1.016)
					(thickness 0.1524)
				)
			)
		)
		(duplicate_pad_numbers_are_jumpers no)
		(fp_line
			(start -0.508 -0.9398)
			(end -0.508 0.9398)
			(stroke
				(width 0.1524)
				(type default)
			)
			(layer "F.SilkS")
		)
		(fp_line
			(start 0.508 -0.9398)
			(end -0.508 -0.9398)
			(stroke
				(width 0.1524)
				(type default)
			)
			(layer "F.SilkS")
		)
		(fp_rect
			(start -0.508 0.9398)
			(end 0.508 -0.9398)
			(stroke
				(width 0)
				(type default)
			)
			(fill no)
			(layer "F.CrtYd")
		)
		(fp_rect
			(start -0.508 0.9398)
			(end 0.508 -0.9398)
			(stroke
				(width 0)
				(type default)
			)
			(fill no)
			(layer "F.Fab")
		)
		(pad "1" smd custom
			(at 0 -0.4445)
			(size 0.1397 0.1397)
			(layers "F.Cu" "F.Mask" "F.Paste")
			(net "P3V3")
			(options
				(clearance outline)
				(anchor circle)
			)
			(primitives
				(gr_poly
					(pts
						(arc
							(start -0.1778 -0.2794)
							(mid -0.249642 -0.249642)
							(end -0.2794 -0.1778)
						)
						(arc
							(start -0.2794 0.1778)
							(mid -0.249642 0.249642)
							(end -0.1778 0.2794)
						)
						(arc
							(start 0.1778 0.2794)
							(mid 0.249642 0.249642)
							(end 0.2794 0.1778)
						)
						(arc
							(start 0.2794 -0.1778)
							(mid 0.249642 -0.249642)
							(end 0.1778 -0.2794)
						)
					)
					(width 0)
					(fill yes)
				)
			)
		)
		(pad "2" smd custom
			(at 0 0.4445)
			(size 0.1397 0.1397)
			(layers "F.Cu" "F.Mask" "F.Paste")
			(net "SSD_ACT_DR5")
			(options
				(clearance outline)
				(anchor circle)
			)
			(primitives
				(gr_poly
					(pts
						(arc
							(start -0.1778 -0.2794)
							(mid -0.249642 -0.249642)
							(end -0.2794 -0.1778)
						)
						(arc
							(start -0.2794 0.1778)
							(mid -0.249642 0.249642)
							(end -0.1778 0.2794)
						)
						(arc
							(start 0.1778 0.2794)
							(mid 0.249642 0.249642)
							(end 0.2794 0.1778)
						)
						(arc
							(start 0.2794 -0.1778)
							(mid 0.249642 -0.249642)
							(end 0.1778 -0.2794)
						)
					)
					(width 0)
					(fill yes)
				)
			)
		)
	)
	(footprint ""
		(layer "F.Cu")
		(at 16.637 -495.427 180)
		(property "Reference" "Q13"
			(at 0 0 180)
			(layer "F.SilkS")
			(hide yes)
			(effects
				(font
					(size 1.27 1.27)
				)
			)
		)
		(property "Value" "2N7002A-7-GP"
			(at 0.127 -8.9662 180)
			(unlocked yes)
			(layer "F.Fab")
			(hide yes)
			(effects
				(font
					(size 1.016 1.016)
					(thickness 0.1524)
				)
			)
		)
		(property "Device Type" "SOT23DGS2D4H48"
			(at 0.127 -10.4902 180)
			(unlocked yes)
			(layer "F.Fab")
			(hide yes)
			(effects
				(font
					(size 1.016 1.016)
					(thickness 0.1524)
				)
			)
		)
		(duplicate_pad_numbers_are_jumpers no)
		(fp_line
			(start 1.651 1.778)
			(end 1.651 -1.778)
			(stroke
				(width 0.1524)
				(type default)
			)
			(layer "F.SilkS")
		)
		(fp_line
			(start 1.651 -1.778)
			(end -1.651 -1.778)
			(stroke
				(width 0.1524)
				(type default)
			)
			(layer "F.SilkS")
		)
		(fp_line
			(start -1.651 1.778)
			(end 1.651 1.778)
			(stroke
				(width 0.1524)
				(type default)
			)
			(layer "F.SilkS")
		)
		(fp_line
			(start -1.651 -1.778)
			(end -1.651 1.778)
			(stroke
				(width 0.1524)
				(type default)
			)
			(layer "F.SilkS")
		)
		(fp_poly
			(pts
				(xy -1.778 1.8796) (xy -1.778 -1.8796) (xy 1.778 -1.8796) (xy 1.778 1.8796)
			)
			(stroke
				(width 0)
				(type default)
			)
			(fill no)
			(layer "F.CrtYd")
		)
		(fp_poly
			(pts
				(xy -1.778 1.8796) (xy -1.778 -1.8796) (xy 1.778 -1.8796) (xy 1.778 1.8796)
			)
			(stroke
				(width 0)
				(type default)
			)
			(fill no)
			(layer "F.Fab")
		)
		(pad "D" smd custom
			(at 0 -0.9525 180)
			(size 0.1905 0.1905)
			(layers "F.Cu" "F.Mask" "F.Paste")
			(net "SW_SSD5_R")
			(options
				(clearance outline)
				(anchor circle)
			)
			(primitives
				(gr_poly
					(pts
						(arc
							(start -0.1778 0.5715)
							(mid -0.321484 0.511984)
							(end -0.381 0.3683)
						)
						(arc
							(start -0.381 -0.3683)
							(mid -0.321484 -0.511984)
							(end -0.1778 -0.5715)
						)
						(arc
							(start 0.1778 -0.5715)
							(mid 0.321484 -0.511984)
							(end 0.381 -0.3683)
						)
						(arc
							(start 0.381 0.3683)
							(mid 0.321484 0.511984)
							(end 0.1778 0.5715)
						)
					)
					(width 0)
					(fill yes)
				)
			)
		)
		(pad "G" smd custom
			(at -0.98425 0.9525 180)
			(size 0.1905 0.1905)
			(layers "F.Cu" "F.Mask" "F.Paste")
			(net "SSD5_PWREN")
			(options
				(clearance outline)
				(anchor circle)
			)
			(primitives
				(gr_poly
					(pts
						(arc
							(start -0.1778 0.5715)
							(mid -0.321484 0.511984)
							(end -0.381 0.3683)
						)
						(arc
							(start -0.381 -0.3683)
							(mid -0.321484 -0.511984)
							(end -0.1778 -0.5715)
						)
						(arc
							(start 0.1778 -0.5715)
							(mid 0.321484 -0.511984)
							(end 0.381 -0.3683)
						)
						(arc
							(start 0.381 0.3683)
							(mid 0.321484 0.511984)
							(end 0.1778 0.5715)
						)
					)
					(width 0)
					(fill yes)
				)
			)
		)
		(pad "S" smd custom
			(at 0.98425 0.9525 180)
			(size 0.1905 0.1905)
			(layers "F.Cu" "F.Mask" "F.Paste")
			(net "GND")
			(options
				(clearance outline)
				(anchor circle)
			)
			(primitives
				(gr_poly
					(pts
						(arc
							(start -0.1778 0.5715)
							(mid -0.321484 0.511984)
							(end -0.381 0.3683)
						)
						(arc
							(start -0.381 -0.3683)
							(mid -0.321484 -0.511984)
							(end -0.1778 -0.5715)
						)
						(arc
							(start 0.1778 -0.5715)
							(mid 0.321484 -0.511984)
							(end 0.381 -0.3683)
						)
						(arc
							(start 0.381 0.3683)
							(mid 0.321484 0.511984)
							(end 0.1778 0.5715)
						)
					)
					(width 0)
					(fill yes)
				)
			)
		)
	)
	(footprint ""
		(layer "F.Cu")
		(at 252.6284 -360.5022)
		(property "Reference" "C9533"
			(at 0 0 0)
			(layer "F.SilkS")
			(hide yes)
			(effects
				(font
					(size 1.27 1.27)
				)
			)
		)
		(property "Value" "SCD01U50V2KX-1GP"
			(at 1.1811 -2.7051 0)
			(unlocked yes)
			(layer "F.Fab")
			(hide yes)
			(effects
				(font
					(size 1.016 1.016)
					(thickness 0.1524)
				)
			)
		)
		(property "Device Type" "C402H22"
			(at 1.1811 -4.2291 0)
			(unlocked yes)
			(layer "F.Fab")
			(hide yes)
			(effects
				(font
					(size 1.016 1.016)
					(thickness 0.1524)
				)
			)
		)
		(duplicate_pad_numbers_are_jumpers no)
		(fp_rect
			(start -0.4318 0.9525)
			(end 0.4318 -0.9525)
			(stroke
				(width 0)
				(type default)
			)
			(fill no)
			(layer "F.CrtYd")
		)
		(fp_rect
			(start -0.4318 0.9525)
			(end 0.4318 -0.9525)
			(stroke
				(width 0)
				(type default)
			)
			(fill no)
			(layer "F.Fab")
		)
		(pad "1" smd custom
			(at 0 -0.4445)
			(size 0.1524 0.1524)
			(layers "F.Cu" "F.Mask" "F.Paste")
			(net "P12V")
			(options
				(clearance outline)
				(anchor circle)
			)
			(primitives
				(gr_poly
					(pts
						(arc
							(start 0.3048 -0.2032)
							(mid 0.275042 -0.275042)
							(end 0.2032 -0.3048)
						)
						(arc
							(start -0.2032 -0.3048)
							(mid -0.275042 -0.275042)
							(end -0.3048 -0.2032)
						)
						(arc
							(start -0.3048 0.2032)
							(mid -0.275042 0.275042)
							(end -0.2032 0.3048)
						)
						(arc
							(start 0.2032 0.3048)
							(mid 0.275042 0.275042)
							(end 0.3048 0.2032)
						)
					)
					(width 0)
					(fill yes)
				)
			)
		)
		(pad "2" smd custom
			(at 0 0.4445)
			(size 0.1524 0.1524)
			(layers "F.Cu" "F.Mask" "F.Paste")
			(net "GND")
			(options
				(clearance outline)
				(anchor circle)
			)
			(primitives
				(gr_poly
					(pts
						(arc
							(start 0.3048 -0.2032)
							(mid 0.275042 -0.275042)
							(end 0.2032 -0.3048)
						)
						(arc
							(start -0.2032 -0.3048)
							(mid -0.275042 -0.275042)
							(end -0.3048 -0.2032)
						)
						(arc
							(start -0.3048 0.2032)
							(mid -0.275042 0.275042)
							(end -0.2032 0.3048)
						)
						(arc
							(start 0.2032 0.3048)
							(mid 0.275042 0.275042)
							(end 0.3048 0.2032)
						)
					)
					(width 0)
					(fill yes)
				)
			)
		)
	)
	(footprint ""
		(layer "F.Cu")
		(at 69.215 -440.182)
		(property "Reference" "R354"
			(at 0 0 0)
			(layer "F.SilkS")
			(hide yes)
			(effects
				(font
					(size 1.27 1.27)
				)
			)
		)
		(property "Value" "0R2J-2-GP"
			(at 0.064008 -3.993896 0)
			(unlocked yes)
			(layer "F.Fab")
			(hide yes)
			(effects
				(font
					(size 1.016 1.016)
					(thickness 0.1524)
				)
			)
		)
		(property "Device Type" "R402H16"
			(at 0.064008 -5.517896 0)
			(unlocked yes)
			(layer "F.Fab")
			(hide yes)
			(effects
				(font
					(size 1.016 1.016)
					(thickness 0.1524)
				)
			)
		)
		(duplicate_pad_numbers_are_jumpers no)
		(fp_line
			(start -0.508 -0.9398)
			(end -0.508 0.9398)
			(stroke
				(width 0.1524)
				(type default)
			)
			(layer "F.SilkS")
		)
		(fp_line
			(start 0.508 -0.9398)
			(end -0.508 -0.9398)
			(stroke
				(width 0.1524)
				(type default)
			)
			(layer "F.SilkS")
		)
		(fp_rect
			(start -0.508 0.9398)
			(end 0.508 -0.9398)
			(stroke
				(width 0)
				(type default)
			)
			(fill no)
			(layer "F.CrtYd")
		)
		(fp_rect
			(start -0.508 0.9398)
			(end 0.508 -0.9398)
			(stroke
				(width 0)
				(type default)
			)
			(fill no)
			(layer "F.Fab")
		)
		(pad "1" smd custom
			(at 0 -0.4445)
			(size 0.1397 0.1397)
			(layers "F.Cu" "F.Mask" "F.Paste")
			(net "EEPROM_SDA")
			(options
				(clearance outline)
				(anchor circle)
			)
			(primitives
				(gr_poly
					(pts
						(arc
							(start -0.1778 -0.2794)
							(mid -0.249642 -0.249642)
							(end -0.2794 -0.1778)
						)
						(arc
							(start -0.2794 0.1778)
							(mid -0.249642 0.249642)
							(end -0.1778 0.2794)
						)
						(arc
							(start 0.1778 0.2794)
							(mid 0.249642 0.249642)
							(end 0.2794 0.1778)
						)
						(arc
							(start 0.2794 -0.1778)
							(mid 0.249642 -0.249642)
							(end 0.1778 -0.2794)
						)
					)
					(width 0)
					(fill yes)
				)
			)
		)
		(pad "2" smd custom
			(at 0 0.4445)
			(size 0.1397 0.1397)
			(layers "F.Cu" "F.Mask" "F.Paste")
			(net "I2C_B_SDA")
			(options
				(clearance outline)
				(anchor circle)
			)
			(primitives
				(gr_poly
					(pts
						(arc
							(start -0.1778 -0.2794)
							(mid -0.249642 -0.249642)
							(end -0.2794 -0.1778)
						)
						(arc
							(start -0.2794 0.1778)
							(mid -0.249642 0.249642)
							(end -0.1778 0.2794)
						)
						(arc
							(start 0.1778 0.2794)
							(mid 0.249642 0.249642)
							(end 0.2794 0.1778)
						)
						(arc
							(start 0.2794 -0.1778)
							(mid 0.249642 -0.249642)
							(end 0.1778 -0.2794)
						)
					)
					(width 0)
					(fill yes)
				)
			)
		)
	)
	(footprint ""
		(layer "F.Cu")
		(at 74.4474 -352.679 180)
		(property "Reference" "R374"
			(at 0 0 180)
			(layer "F.SilkS")
			(hide yes)
			(effects
				(font
					(size 1.27 1.27)
				)
			)
		)
		(property "Value" "4K7R2J-2-GP"
			(at 0.064008 -3.993896 180)
			(unlocked yes)
			(layer "F.Fab")
			(hide yes)
			(effects
				(font
					(size 1.016 1.016)
					(thickness 0.1524)
				)
			)
		)
		(property "Device Type" "R402H16"
			(at 0.064008 -5.517896 180)
			(unlocked yes)
			(layer "F.Fab")
			(hide yes)
			(effects
				(font
					(size 1.016 1.016)
					(thickness 0.1524)
				)
			)
		)
		(duplicate_pad_numbers_are_jumpers no)
		(fp_line
			(start 0.508 -0.9398)
			(end -0.508 -0.9398)
			(stroke
				(width 0.1524)
				(type default)
			)
			(layer "F.SilkS")
		)
		(fp_line
			(start -0.508 -0.9398)
			(end -0.508 0.9398)
			(stroke
				(width 0.1524)
				(type default)
			)
			(layer "F.SilkS")
		)
		(fp_rect
			(start -0.508 0.9398)
			(end 0.508 -0.9398)
			(stroke
				(width 0)
				(type default)
			)
			(fill no)
			(layer "F.CrtYd")
		)
		(fp_rect
			(start -0.508 0.9398)
			(end 0.508 -0.9398)
			(stroke
				(width 0)
				(type default)
			)
			(fill no)
			(layer "F.Fab")
		)
		(pad "1" smd custom
			(at 0 -0.4445 180)
			(size 0.1397 0.1397)
			(layers "F.Cu" "F.Mask" "F.Paste")
			(net "P3V3")
			(options
				(clearance outline)
				(anchor circle)
			)
			(primitives
				(gr_poly
					(pts
						(arc
							(start -0.1778 -0.2794)
							(mid -0.249642 -0.249642)
							(end -0.2794 -0.1778)
						)
						(arc
							(start -0.2794 0.1778)
							(mid -0.249642 0.249642)
							(end -0.1778 0.2794)
						)
						(arc
							(start 0.1778 0.2794)
							(mid 0.249642 0.249642)
							(end 0.2794 0.1778)
						)
						(arc
							(start 0.2794 -0.1778)
							(mid 0.249642 -0.249642)
							(end 0.1778 -0.2794)
						)
					)
					(width 0)
					(fill yes)
				)
			)
		)
		(pad "2" smd custom
			(at 0 0.4445 180)
			(size 0.1397 0.1397)
			(layers "F.Cu" "F.Mask" "F.Paste")
			(net "BMC_I2C_SDA_BUF_9")
			(options
				(clearance outline)
				(anchor circle)
			)
			(primitives
				(gr_poly
					(pts
						(arc
							(start -0.1778 -0.2794)
							(mid -0.249642 -0.249642)
							(end -0.2794 -0.1778)
						)
						(arc
							(start -0.2794 0.1778)
							(mid -0.249642 0.249642)
							(end -0.1778 0.2794)
						)
						(arc
							(start 0.1778 0.2794)
							(mid 0.249642 0.249642)
							(end 0.2794 0.1778)
						)
						(arc
							(start 0.2794 -0.1778)
							(mid 0.249642 -0.249642)
							(end 0.1778 -0.2794)
						)
					)
					(width 0)
					(fill yes)
				)
			)
		)
	)
	(footprint ""
		(layer "F.Cu")
		(at 225.1075 -141.40561 90)
		(property "Reference" "R9802"
			(at 0 0 90)
			(layer "F.SilkS")
			(hide yes)
			(effects
				(font
					(size 1.27 1.27)
				)
			)
		)
		(property "Value" "0R2J-2-GP"
			(at 0.064008 -3.993896 90)
			(unlocked yes)
			(layer "F.Fab")
			(hide yes)
			(effects
				(font
					(size 1.016 1.016)
					(thickness 0.1524)
				)
			)
		)
		(property "Device Type" "R402H16"
			(at 0.064008 -5.517896 90)
			(unlocked yes)
			(layer "F.Fab")
			(hide yes)
			(effects
				(font
					(size 1.016 1.016)
					(thickness 0.1524)
				)
			)
		)
		(duplicate_pad_numbers_are_jumpers no)
		(fp_line
			(start 0.508 -0.9398)
			(end -0.508 -0.9398)
			(stroke
				(width 0.1524)
				(type default)
			)
			(layer "F.SilkS")
		)
		(fp_line
			(start -0.508 -0.9398)
			(end -0.508 0.9398)
			(stroke
				(width 0.1524)
				(type default)
			)
			(layer "F.SilkS")
		)
		(fp_rect
			(start -0.508 0.9398)
			(end 0.508 -0.9398)
			(stroke
				(width 0)
				(type default)
			)
			(fill no)
			(layer "F.CrtYd")
		)
		(fp_rect
			(start -0.508 0.9398)
			(end 0.508 -0.9398)
			(stroke
				(width 0)
				(type default)
			)
			(fill no)
			(layer "F.Fab")
		)
		(pad "1" smd custom
			(at 0 -0.4445 90)
			(size 0.1397 0.1397)
			(layers "F.Cu" "F.Mask" "F.Paste")
			(net "ATTN_LED_DR3_R")
			(options
				(clearance outline)
				(anchor circle)
			)
			(primitives
				(gr_poly
					(pts
						(arc
							(start -0.1778 -0.2794)
							(mid -0.249642 -0.249642)
							(end -0.2794 -0.1778)
						)
						(arc
							(start -0.2794 0.1778)
							(mid -0.249642 0.249642)
							(end -0.1778 0.2794)
						)
						(arc
							(start 0.1778 0.2794)
							(mid 0.249642 0.249642)
							(end 0.2794 0.1778)
						)
						(arc
							(start 0.2794 -0.1778)
							(mid 0.249642 -0.249642)
							(end 0.1778 -0.2794)
						)
					)
					(width 0)
					(fill yes)
				)
			)
		)
		(pad "2" smd custom
			(at 0 0.4445 90)
			(size 0.1397 0.1397)
			(layers "F.Cu" "F.Mask" "F.Paste")
			(net "ATTN_LED_DR3_N")
			(options
				(clearance outline)
				(anchor circle)
			)
			(primitives
				(gr_poly
					(pts
						(arc
							(start -0.1778 -0.2794)
							(mid -0.249642 -0.249642)
							(end -0.2794 -0.1778)
						)
						(arc
							(start -0.2794 0.1778)
							(mid -0.249642 0.249642)
							(end -0.1778 0.2794)
						)
						(arc
							(start 0.1778 0.2794)
							(mid 0.249642 0.249642)
							(end 0.2794 0.1778)
						)
						(arc
							(start 0.2794 -0.1778)
							(mid 0.249642 -0.249642)
							(end 0.1778 -0.2794)
						)
					)
					(width 0)
					(fill yes)
				)
			)
		)
	)
	(footprint ""
		(layer "F.Cu")
		(at 213.3981 -403.5171 180)
		(property "Reference" "R9786"
			(at 0 0 180)
			(layer "F.SilkS")
			(hide yes)
			(effects
				(font
					(size 1.27 1.27)
				)
			)
		)
		(property "Value" "47KR2J-2-GP"
			(at 0.064008 -3.993896 180)
			(unlocked yes)
			(layer "F.Fab")
			(hide yes)
			(effects
				(font
					(size 1.016 1.016)
					(thickness 0.1524)
				)
			)
		)
		(property "Device Type" "R402H16"
			(at 0.064008 -5.517896 180)
			(unlocked yes)
			(layer "F.Fab")
			(hide yes)
			(effects
				(font
					(size 1.016 1.016)
					(thickness 0.1524)
				)
			)
		)
		(duplicate_pad_numbers_are_jumpers no)
		(fp_line
			(start 0.508 -0.9398)
			(end -0.508 -0.9398)
			(stroke
				(width 0.1524)
				(type default)
			)
			(layer "F.SilkS")
		)
		(fp_line
			(start -0.508 -0.9398)
			(end -0.508 0.9398)
			(stroke
				(width 0.1524)
				(type default)
			)
			(layer "F.SilkS")
		)
		(fp_rect
			(start -0.508 0.9398)
			(end 0.508 -0.9398)
			(stroke
				(width 0)
				(type default)
			)
			(fill no)
			(layer "F.CrtYd")
		)
		(fp_rect
			(start -0.508 0.9398)
			(end 0.508 -0.9398)
			(stroke
				(width 0)
				(type default)
			)
			(fill no)
			(layer "F.Fab")
		)
		(pad "1" smd custom
			(at 0 -0.4445 180)
			(size 0.1397 0.1397)
			(layers "F.Cu" "F.Mask" "F.Paste")
			(net "P12V")
			(options
				(clearance outline)
				(anchor circle)
			)
			(primitives
				(gr_poly
					(pts
						(arc
							(start -0.1778 -0.2794)
							(mid -0.249642 -0.249642)
							(end -0.2794 -0.1778)
						)
						(arc
							(start -0.2794 0.1778)
							(mid -0.249642 0.249642)
							(end -0.1778 0.2794)
						)
						(arc
							(start 0.1778 0.2794)
							(mid 0.249642 0.249642)
							(end 0.2794 0.1778)
						)
						(arc
							(start 0.2794 -0.1778)
							(mid 0.249642 -0.249642)
							(end 0.1778 -0.2794)
						)
					)
					(width 0)
					(fill yes)
				)
			)
		)
		(pad "2" smd custom
			(at 0 0.4445 180)
			(size 0.1397 0.1397)
			(layers "F.Cu" "F.Mask" "F.Paste")
			(net "P12V_MOST1_GATE")
			(options
				(clearance outline)
				(anchor circle)
			)
			(primitives
				(gr_poly
					(pts
						(arc
							(start -0.1778 -0.2794)
							(mid -0.249642 -0.249642)
							(end -0.2794 -0.1778)
						)
						(arc
							(start -0.2794 0.1778)
							(mid -0.249642 0.249642)
							(end -0.1778 0.2794)
						)
						(arc
							(start 0.1778 0.2794)
							(mid 0.249642 0.249642)
							(end 0.2794 0.1778)
						)
						(arc
							(start 0.2794 -0.1778)
							(mid 0.249642 -0.249642)
							(end 0.1778 -0.2794)
						)
					)
					(width 0)
					(fill yes)
				)
			)
		)
	)
	(footprint ""
		(layer "F.Cu")
		(at 24.638 -395.351 -90)
		(property "Reference" "R144"
			(at 0 0 270)
			(layer "F.SilkS")
			(hide yes)
			(effects
				(font
					(size 1.27 1.27)
				)
			)
		)
		(property "Value" "4K7R2J-2-GP"
			(at 0.064008 -3.993896 270)
			(unlocked yes)
			(layer "F.Fab")
			(hide yes)
			(effects
				(font
					(size 1.016 1.016)
					(thickness 0.1524)
				)
			)
		)
		(property "Device Type" "R402H16"
			(at 0.064008 -5.517896 270)
			(unlocked yes)
			(layer "F.Fab")
			(hide yes)
			(effects
				(font
					(size 1.016 1.016)
					(thickness 0.1524)
				)
			)
		)
		(duplicate_pad_numbers_are_jumpers no)
		(fp_line
			(start -0.508 -0.9398)
			(end -0.508 0.9398)
			(stroke
				(width 0.1524)
				(type default)
			)
			(layer "F.SilkS")
		)
		(fp_line
			(start 0.508 -0.9398)
			(end -0.508 -0.9398)
			(stroke
				(width 0.1524)
				(type default)
			)
			(layer "F.SilkS")
		)
		(fp_rect
			(start -0.508 0.9398)
			(end 0.508 -0.9398)
			(stroke
				(width 0)
				(type default)
			)
			(fill no)
			(layer "F.CrtYd")
		)
		(fp_rect
			(start -0.508 0.9398)
			(end 0.508 -0.9398)
			(stroke
				(width 0)
				(type default)
			)
			(fill no)
			(layer "F.Fab")
		)
		(pad "1" smd custom
			(at 0 -0.4445 270)
			(size 0.1397 0.1397)
			(layers "F.Cu" "F.Mask" "F.Paste")
			(net "P12V")
			(options
				(clearance outline)
				(anchor circle)
			)
			(primitives
				(gr_poly
					(pts
						(arc
							(start -0.1778 -0.2794)
							(mid -0.249642 -0.249642)
							(end -0.2794 -0.1778)
						)
						(arc
							(start -0.2794 0.1778)
							(mid -0.249642 0.249642)
							(end -0.1778 0.2794)
						)
						(arc
							(start 0.1778 0.2794)
							(mid 0.249642 0.249642)
							(end 0.2794 0.1778)
						)
						(arc
							(start 0.2794 -0.1778)
							(mid 0.249642 -0.249642)
							(end 0.1778 -0.2794)
						)
					)
					(width 0)
					(fill yes)
				)
			)
		)
		(pad "2" smd custom
			(at 0 0.4445 270)
			(size 0.1397 0.1397)
			(layers "F.Cu" "F.Mask" "F.Paste")
			(net "SW_SSD6_R")
			(options
				(clearance outline)
				(anchor circle)
			)
			(primitives
				(gr_poly
					(pts
						(arc
							(start -0.1778 -0.2794)
							(mid -0.249642 -0.249642)
							(end -0.2794 -0.1778)
						)
						(arc
							(start -0.2794 0.1778)
							(mid -0.249642 0.249642)
							(end -0.1778 0.2794)
						)
						(arc
							(start 0.1778 0.2794)
							(mid 0.249642 0.249642)
							(end 0.2794 0.1778)
						)
						(arc
							(start 0.2794 -0.1778)
							(mid 0.249642 -0.249642)
							(end 0.1778 -0.2794)
						)
					)
					(width 0)
					(fill yes)
				)
			)
		)
	)
	(footprint ""
		(layer "F.Cu")
		(at 32.131 -381.508 -90)
		(property "Reference" "C343"
			(at 0 0 270)
			(layer "F.SilkS")
			(hide yes)
			(effects
				(font
					(size 1.27 1.27)
				)
			)
		)
		(property "Value" "SCD1U16V2KX-3GP"
			(at 1.1811 -2.7051 270)
			(unlocked yes)
			(layer "F.Fab")
			(hide yes)
			(effects
				(font
					(size 1.016 1.016)
					(thickness 0.1524)
				)
			)
		)
		(property "Device Type" "C402H22"
			(at 1.1811 -4.2291 270)
			(unlocked yes)
			(layer "F.Fab")
			(hide yes)
			(effects
				(font
					(size 1.016 1.016)
					(thickness 0.1524)
				)
			)
		)
		(duplicate_pad_numbers_are_jumpers no)
		(fp_rect
			(start -0.4318 0.9525)
			(end 0.4318 -0.9525)
			(stroke
				(width 0)
				(type default)
			)
			(fill no)
			(layer "F.CrtYd")
		)
		(fp_rect
			(start -0.4318 0.9525)
			(end 0.4318 -0.9525)
			(stroke
				(width 0)
				(type default)
			)
			(fill no)
			(layer "F.Fab")
		)
		(pad "1" smd custom
			(at 0 -0.4445 270)
			(size 0.1524 0.1524)
			(layers "F.Cu" "F.Mask" "F.Paste")
			(net "P3V3")
			(options
				(clearance outline)
				(anchor circle)
			)
			(primitives
				(gr_poly
					(pts
						(arc
							(start 0.3048 -0.2032)
							(mid 0.275042 -0.275042)
							(end 0.2032 -0.3048)
						)
						(arc
							(start -0.2032 -0.3048)
							(mid -0.275042 -0.275042)
							(end -0.3048 -0.2032)
						)
						(arc
							(start -0.3048 0.2032)
							(mid -0.275042 0.275042)
							(end -0.2032 0.3048)
						)
						(arc
							(start 0.2032 0.3048)
							(mid 0.275042 0.275042)
							(end 0.3048 0.2032)
						)
					)
					(width 0)
					(fill yes)
				)
			)
		)
		(pad "2" smd custom
			(at 0 0.4445 270)
			(size 0.1524 0.1524)
			(layers "F.Cu" "F.Mask" "F.Paste")
			(net "GND")
			(options
				(clearance outline)
				(anchor circle)
			)
			(primitives
				(gr_poly
					(pts
						(arc
							(start 0.3048 -0.2032)
							(mid 0.275042 -0.275042)
							(end 0.2032 -0.3048)
						)
						(arc
							(start -0.2032 -0.3048)
							(mid -0.275042 -0.275042)
							(end -0.3048 -0.2032)
						)
						(arc
							(start -0.3048 0.2032)
							(mid -0.275042 0.275042)
							(end -0.2032 0.3048)
						)
						(arc
							(start 0.2032 0.3048)
							(mid 0.275042 0.275042)
							(end 0.3048 0.2032)
						)
					)
					(width 0)
					(fill yes)
				)
			)
		)
	)
	(footprint ""
		(layer "F.Cu")
		(at 37.1856 -108.3564 90)
		(property "Reference" "R151"
			(at 0 0 90)
			(layer "F.SilkS")
			(hide yes)
			(effects
				(font
					(size 1.27 1.27)
				)
			)
		)
		(property "Value" "4K7R2J-2-GP"
			(at 0.064008 -3.993896 90)
			(unlocked yes)
			(layer "F.Fab")
			(hide yes)
			(effects
				(font
					(size 1.016 1.016)
					(thickness 0.1524)
				)
			)
		)
		(property "Device Type" "R402H16"
			(at 0.064008 -5.517896 90)
			(unlocked yes)
			(layer "F.Fab")
			(hide yes)
			(effects
				(font
					(size 1.016 1.016)
					(thickness 0.1524)
				)
			)
		)
		(duplicate_pad_numbers_are_jumpers no)
		(fp_line
			(start 0.508 -0.9398)
			(end -0.508 -0.9398)
			(stroke
				(width 0.1524)
				(type default)
			)
			(layer "F.SilkS")
		)
		(fp_line
			(start -0.508 -0.9398)
			(end -0.508 0.9398)
			(stroke
				(width 0.1524)
				(type default)
			)
			(layer "F.SilkS")
		)
		(fp_rect
			(start -0.508 0.9398)
			(end 0.508 -0.9398)
			(stroke
				(width 0)
				(type default)
			)
			(fill no)
			(layer "F.CrtYd")
		)
		(fp_rect
			(start -0.508 0.9398)
			(end 0.508 -0.9398)
			(stroke
				(width 0)
				(type default)
			)
			(fill no)
			(layer "F.Fab")
		)
		(pad "1" smd custom
			(at 0 -0.4445 90)
			(size 0.1397 0.1397)
			(layers "F.Cu" "F.Mask" "F.Paste")
			(net "P12V")
			(options
				(clearance outline)
				(anchor circle)
			)
			(primitives
				(gr_poly
					(pts
						(arc
							(start -0.1778 -0.2794)
							(mid -0.249642 -0.249642)
							(end -0.2794 -0.1778)
						)
						(arc
							(start -0.2794 0.1778)
							(mid -0.249642 0.249642)
							(end -0.1778 0.2794)
						)
						(arc
							(start 0.1778 0.2794)
							(mid 0.249642 0.249642)
							(end 0.2794 0.1778)
						)
						(arc
							(start 0.2794 -0.1778)
							(mid 0.249642 -0.249642)
							(end 0.1778 -0.2794)
						)
					)
					(width 0)
					(fill yes)
				)
			)
		)
		(pad "2" smd custom
			(at 0 0.4445 90)
			(size 0.1397 0.1397)
			(layers "F.Cu" "F.Mask" "F.Paste")
			(net "SW_SSD13_R")
			(options
				(clearance outline)
				(anchor circle)
			)
			(primitives
				(gr_poly
					(pts
						(arc
							(start -0.1778 -0.2794)
							(mid -0.249642 -0.249642)
							(end -0.2794 -0.1778)
						)
						(arc
							(start -0.2794 0.1778)
							(mid -0.249642 0.249642)
							(end -0.1778 0.2794)
						)
						(arc
							(start 0.1778 0.2794)
							(mid 0.249642 0.249642)
							(end 0.2794 0.1778)
						)
						(arc
							(start 0.2794 -0.1778)
							(mid 0.249642 -0.249642)
							(end 0.1778 -0.2794)
						)
					)
					(width 0)
					(fill yes)
				)
			)
		)
	)
	(footprint ""
		(layer "F.Cu")
		(at 243.586 -412.5976)
		(property "Reference" "PC1289"
			(at 0 0 0)
			(layer "F.SilkS")
			(hide yes)
			(effects
				(font
					(size 1.27 1.27)
				)
			)
		)
		(property "Value" "SCD1U25V3KX-GP"
			(at 0 -2.8194 0)
			(unlocked yes)
			(layer "F.Fab")
			(hide yes)
			(effects
				(font
					(size 1.016 1.016)
					(thickness 0.1524)
				)
			)
		)
		(property "Device Type" "C603H36"
			(at 0 -4.3434 0)
			(unlocked yes)
			(layer "F.Fab")
			(hide yes)
			(effects
				(font
					(size 1.016 1.016)
					(thickness 0.1524)
				)
			)
		)
		(duplicate_pad_numbers_are_jumpers no)
		(fp_line
			(start 0.508 0)
			(end -0.508 0)
			(stroke
				(width 0.2032)
				(type default)
			)
			(layer "F.SilkS")
		)
		(fp_rect
			(start -0.5842 1.3335)
			(end 0.5842 -1.3335)
			(stroke
				(width 0)
				(type default)
			)
			(fill no)
			(layer "F.CrtYd")
		)
		(fp_rect
			(start -0.5842 1.3335)
			(end 0.5842 -1.3335)
			(stroke
				(width 0)
				(type default)
			)
			(fill no)
			(layer "F.Fab")
		)
		(pad "1" smd custom
			(at 0 -0.762)
			(size 0.2159 0.2159)
			(layers "F.Cu" "F.Mask" "F.Paste")
			(net "P3V3")
			(options
				(clearance outline)
				(anchor circle)
			)
			(primitives
				(gr_poly
					(pts
						(arc
							(start -0.3302 -0.4318)
							(mid -0.402042 -0.402042)
							(end -0.4318 -0.3302)
						)
						(arc
							(start -0.4318 0.3302)
							(mid -0.402042 0.402042)
							(end -0.3302 0.4318)
						)
						(arc
							(start 0.3302 0.4318)
							(mid 0.402042 0.402042)
							(end 0.4318 0.3302)
						)
						(arc
							(start 0.4318 -0.3302)
							(mid 0.402042 -0.402042)
							(end 0.3302 -0.4318)
						)
					)
					(width 0)
					(fill yes)
				)
			)
		)
		(pad "2" smd custom
			(at 0 0.762)
			(size 0.2159 0.2159)
			(layers "F.Cu" "F.Mask" "F.Paste")
			(net "GND")
			(options
				(clearance outline)
				(anchor circle)
			)
			(primitives
				(gr_poly
					(pts
						(arc
							(start -0.3302 -0.4318)
							(mid -0.402042 -0.402042)
							(end -0.4318 -0.3302)
						)
						(arc
							(start -0.4318 0.3302)
							(mid -0.402042 0.402042)
							(end -0.3302 0.4318)
						)
						(arc
							(start 0.3302 0.4318)
							(mid 0.402042 0.402042)
							(end 0.4318 0.3302)
						)
						(arc
							(start 0.4318 -0.3302)
							(mid 0.402042 -0.402042)
							(end 0.3302 -0.4318)
						)
					)
					(width 0)
					(fill yes)
				)
			)
		)
	)
	(footprint ""
		(layer "F.Cu")
		(at 24.003 -156.337 -90)
		(property "Reference" "R9421"
			(at 0 0 270)
			(layer "F.SilkS")
			(hide yes)
			(effects
				(font
					(size 1.27 1.27)
				)
			)
		)
		(property "Value" "330R2F-GP"
			(at 0.064008 -3.993896 270)
			(unlocked yes)
			(layer "F.Fab")
			(hide yes)
			(effects
				(font
					(size 1.016 1.016)
					(thickness 0.1524)
				)
			)
		)
		(property "Device Type" "R402H16"
			(at 0.064008 -5.517896 270)
			(unlocked yes)
			(layer "F.Fab")
			(hide yes)
			(effects
				(font
					(size 1.016 1.016)
					(thickness 0.1524)
				)
			)
		)
		(duplicate_pad_numbers_are_jumpers no)
		(fp_line
			(start -0.508 -0.9398)
			(end -0.508 0.9398)
			(stroke
				(width 0.1524)
				(type default)
			)
			(layer "F.SilkS")
		)
		(fp_line
			(start 0.508 -0.9398)
			(end -0.508 -0.9398)
			(stroke
				(width 0.1524)
				(type default)
			)
			(layer "F.SilkS")
		)
		(fp_rect
			(start -0.508 0.9398)
			(end 0.508 -0.9398)
			(stroke
				(width 0)
				(type default)
			)
			(fill no)
			(layer "F.CrtYd")
		)
		(fp_rect
			(start -0.508 0.9398)
			(end 0.508 -0.9398)
			(stroke
				(width 0)
				(type default)
			)
			(fill no)
			(layer "F.Fab")
		)
		(pad "1" smd custom
			(at 0 -0.4445 270)
			(size 0.1397 0.1397)
			(layers "F.Cu" "F.Mask" "F.Paste")
			(net "P3V3")
			(options
				(clearance outline)
				(anchor circle)
			)
			(primitives
				(gr_poly
					(pts
						(arc
							(start -0.1778 -0.2794)
							(mid -0.249642 -0.249642)
							(end -0.2794 -0.1778)
						)
						(arc
							(start -0.2794 0.1778)
							(mid -0.249642 0.249642)
							(end -0.1778 0.2794)
						)
						(arc
							(start 0.1778 0.2794)
							(mid 0.249642 0.249642)
							(end 0.2794 0.1778)
						)
						(arc
							(start 0.2794 -0.1778)
							(mid 0.249642 -0.249642)
							(end 0.1778 -0.2794)
						)
					)
					(width 0)
					(fill yes)
				)
			)
		)
		(pad "2" smd custom
			(at 0 0.4445 270)
			(size 0.1397 0.1397)
			(layers "F.Cu" "F.Mask" "F.Paste")
			(net "DRV_ATTN_13")
			(options
				(clearance outline)
				(anchor circle)
			)
			(primitives
				(gr_poly
					(pts
						(arc
							(start -0.1778 -0.2794)
							(mid -0.249642 -0.249642)
							(end -0.2794 -0.1778)
						)
						(arc
							(start -0.2794 0.1778)
							(mid -0.249642 0.249642)
							(end -0.1778 0.2794)
						)
						(arc
							(start 0.1778 0.2794)
							(mid 0.249642 0.249642)
							(end 0.2794 0.1778)
						)
						(arc
							(start 0.2794 -0.1778)
							(mid 0.249642 -0.249642)
							(end 0.1778 -0.2794)
						)
					)
					(width 0)
					(fill yes)
				)
			)
		)
	)
	(footprint ""
		(layer "F.Cu")
		(at 234.315 -430.53 -90)
		(property "Reference" "PR9085"
			(at 0 0 270)
			(layer "F.SilkS")
			(hide yes)
			(effects
				(font
					(size 1.27 1.27)
				)
			)
		)
		(property "Value" "10R3F-GP"
			(at -0.0254 -2.5146 270)
			(unlocked yes)
			(layer "F.Fab")
			(hide yes)
			(effects
				(font
					(size 1.016 1.016)
					(thickness 0.1524)
				)
			)
		)
		(property "Device Type" "R603H22"
			(at -0.0254 -4.0386 270)
			(unlocked yes)
			(layer "F.Fab")
			(hide yes)
			(effects
				(font
					(size 1.016 1.016)
					(thickness 0.1524)
				)
			)
		)
		(duplicate_pad_numbers_are_jumpers no)
		(fp_line
			(start -0.4826 0)
			(end -0.2032 0)
			(stroke
				(width 0.2032)
				(type default)
			)
			(layer "F.SilkS")
		)
		(fp_line
			(start 0.2032 0)
			(end 0.4826 0)
			(stroke
				(width 0.2032)
				(type default)
			)
			(layer "F.SilkS")
		)
		(fp_rect
			(start -0.5842 1.3335)
			(end 0.5842 -1.3335)
			(stroke
				(width 0)
				(type default)
			)
			(fill no)
			(layer "F.CrtYd")
		)
		(fp_rect
			(start -0.5842 1.3335)
			(end 0.5842 -1.3335)
			(stroke
				(width 0)
				(type default)
			)
			(fill no)
			(layer "F.Fab")
		)
		(pad "1" smd custom
			(at 0 -0.762 270)
			(size 0.2159 0.2159)
			(layers "F.Cu" "F.Mask" "F.Paste")
			(net "P3V3_CC")
			(options
				(clearance outline)
				(anchor circle)
			)
			(primitives
				(gr_poly
					(pts
						(arc
							(start -0.3302 -0.4318)
							(mid -0.402042 -0.402042)
							(end -0.4318 -0.3302)
						)
						(arc
							(start -0.4318 0.3302)
							(mid -0.402042 0.402042)
							(end -0.3302 0.4318)
						)
						(arc
							(start 0.3302 0.4318)
							(mid 0.402042 0.402042)
							(end 0.4318 0.3302)
						)
						(arc
							(start 0.4318 -0.3302)
							(mid 0.402042 -0.402042)
							(end 0.3302 -0.4318)
						)
					)
					(width 0)
					(fill yes)
				)
			)
		)
		(pad "2" smd custom
			(at 0 0.762 270)
			(size 0.2159 0.2159)
			(layers "F.Cu" "F.Mask" "F.Paste")
			(net "P3V3_CC_R")
			(options
				(clearance outline)
				(anchor circle)
			)
			(primitives
				(gr_poly
					(pts
						(arc
							(start -0.3302 -0.4318)
							(mid -0.402042 -0.402042)
							(end -0.4318 -0.3302)
						)
						(arc
							(start -0.4318 0.3302)
							(mid -0.402042 0.402042)
							(end -0.3302 0.4318)
						)
						(arc
							(start 0.3302 0.4318)
							(mid 0.402042 0.402042)
							(end 0.4318 0.3302)
						)
						(arc
							(start 0.4318 -0.3302)
							(mid 0.402042 -0.402042)
							(end 0.3302 -0.4318)
						)
					)
					(width 0)
					(fill yes)
				)
			)
		)
	)
	(footprint ""
		(layer "F.Cu")
		(at 30.3022 -17.145 180)
		(property "Reference" "R418"
			(at 0 0 180)
			(layer "F.SilkS")
			(hide yes)
			(effects
				(font
					(size 1.27 1.27)
				)
			)
		)
		(property "Value" "0R2J-2-GP"
			(at 0.064008 -3.993896 180)
			(unlocked yes)
			(layer "F.Fab")
			(hide yes)
			(effects
				(font
					(size 1.016 1.016)
					(thickness 0.1524)
				)
			)
		)
		(property "Device Type" "R402H16"
			(at 0.064008 -5.517896 180)
			(unlocked yes)
			(layer "F.Fab")
			(hide yes)
			(effects
				(font
					(size 1.016 1.016)
					(thickness 0.1524)
				)
			)
		)
		(duplicate_pad_numbers_are_jumpers no)
		(fp_line
			(start 0.508 -0.9398)
			(end -0.508 -0.9398)
			(stroke
				(width 0.1524)
				(type default)
			)
			(layer "F.SilkS")
		)
		(fp_line
			(start -0.508 -0.9398)
			(end -0.508 0.9398)
			(stroke
				(width 0.1524)
				(type default)
			)
			(layer "F.SilkS")
		)
		(fp_rect
			(start -0.508 0.9398)
			(end 0.508 -0.9398)
			(stroke
				(width 0)
				(type default)
			)
			(fill no)
			(layer "F.CrtYd")
		)
		(fp_rect
			(start -0.508 0.9398)
			(end 0.508 -0.9398)
			(stroke
				(width 0)
				(type default)
			)
			(fill no)
			(layer "F.Fab")
		)
		(pad "1" smd custom
			(at 0 -0.4445 180)
			(size 0.1397 0.1397)
			(layers "F.Cu" "F.Mask" "F.Paste")
			(net "SDA_DR14_R")
			(options
				(clearance outline)
				(anchor circle)
			)
			(primitives
				(gr_poly
					(pts
						(arc
							(start -0.1778 -0.2794)
							(mid -0.249642 -0.249642)
							(end -0.2794 -0.1778)
						)
						(arc
							(start -0.2794 0.1778)
							(mid -0.249642 0.249642)
							(end -0.1778 0.2794)
						)
						(arc
							(start 0.1778 0.2794)
							(mid 0.249642 0.249642)
							(end 0.2794 0.1778)
						)
						(arc
							(start 0.2794 -0.1778)
							(mid 0.249642 -0.249642)
							(end 0.1778 -0.2794)
						)
					)
					(width 0)
					(fill yes)
				)
			)
		)
		(pad "2" smd custom
			(at 0 0.4445 180)
			(size 0.1397 0.1397)
			(layers "F.Cu" "F.Mask" "F.Paste")
			(net "SDA_DR14")
			(options
				(clearance outline)
				(anchor circle)
			)
			(primitives
				(gr_poly
					(pts
						(arc
							(start -0.1778 -0.2794)
							(mid -0.249642 -0.249642)
							(end -0.2794 -0.1778)
						)
						(arc
							(start -0.2794 0.1778)
							(mid -0.249642 0.249642)
							(end -0.1778 0.2794)
						)
						(arc
							(start 0.1778 0.2794)
							(mid 0.249642 0.249642)
							(end 0.2794 0.1778)
						)
						(arc
							(start 0.2794 -0.1778)
							(mid 0.249642 -0.249642)
							(end 0.1778 -0.2794)
						)
					)
					(width 0)
					(fill yes)
				)
			)
		)
	)
	(footprint ""
		(layer "F.Cu")
		(at 25.4 -339.852 180)
		(property "Reference" "PC1224"
			(at 0 0 180)
			(layer "F.SilkS")
			(hide yes)
			(effects
				(font
					(size 1.27 1.27)
				)
			)
		)
		(property "Value" "SCD1U25V3KX-GP"
			(at 0 -2.8194 180)
			(unlocked yes)
			(layer "F.Fab")
			(hide yes)
			(effects
				(font
					(size 1.016 1.016)
					(thickness 0.1524)
				)
			)
		)
		(property "Device Type" "C603H36"
			(at 0 -4.3434 180)
			(unlocked yes)
			(layer "F.Fab")
			(hide yes)
			(effects
				(font
					(size 1.016 1.016)
					(thickness 0.1524)
				)
			)
		)
		(duplicate_pad_numbers_are_jumpers no)
		(fp_line
			(start 0.508 0)
			(end -0.508 0)
			(stroke
				(width 0.2032)
				(type default)
			)
			(layer "F.SilkS")
		)
		(fp_rect
			(start -0.5842 1.3335)
			(end 0.5842 -1.3335)
			(stroke
				(width 0)
				(type default)
			)
			(fill no)
			(layer "F.CrtYd")
		)
		(fp_rect
			(start -0.5842 1.3335)
			(end 0.5842 -1.3335)
			(stroke
				(width 0)
				(type default)
			)
			(fill no)
			(layer "F.Fab")
		)
		(pad "1" smd custom
			(at 0 -0.762 180)
			(size 0.2159 0.2159)
			(layers "F.Cu" "F.Mask" "F.Paste")
			(net "P3V3")
			(options
				(clearance outline)
				(anchor circle)
			)
			(primitives
				(gr_poly
					(pts
						(arc
							(start -0.3302 -0.4318)
							(mid -0.402042 -0.402042)
							(end -0.4318 -0.3302)
						)
						(arc
							(start -0.4318 0.3302)
							(mid -0.402042 0.402042)
							(end -0.3302 0.4318)
						)
						(arc
							(start 0.3302 0.4318)
							(mid 0.402042 0.402042)
							(end 0.4318 0.3302)
						)
						(arc
							(start 0.4318 -0.3302)
							(mid 0.402042 -0.402042)
							(end 0.3302 -0.4318)
						)
					)
					(width 0)
					(fill yes)
				)
			)
		)
		(pad "2" smd custom
			(at 0 0.762 180)
			(size 0.2159 0.2159)
			(layers "F.Cu" "F.Mask" "F.Paste")
			(net "GND")
			(options
				(clearance outline)
				(anchor circle)
			)
			(primitives
				(gr_poly
					(pts
						(arc
							(start -0.3302 -0.4318)
							(mid -0.402042 -0.402042)
							(end -0.4318 -0.3302)
						)
						(arc
							(start -0.4318 0.3302)
							(mid -0.402042 0.402042)
							(end -0.3302 0.4318)
						)
						(arc
							(start 0.3302 0.4318)
							(mid 0.402042 0.402042)
							(end 0.4318 0.3302)
						)
						(arc
							(start 0.4318 -0.3302)
							(mid 0.402042 -0.402042)
							(end 0.3302 -0.4318)
						)
					)
					(width 0)
					(fill yes)
				)
			)
		)
	)
	(footprint ""
		(layer "F.Cu")
		(at 68.707 -437.388 90)
		(property "Reference" "R368"
			(at 0 0 90)
			(layer "F.SilkS")
			(hide yes)
			(effects
				(font
					(size 1.27 1.27)
				)
			)
		)
		(property "Value" "4K7R2J-2-GP"
			(at 0.064008 -3.993896 90)
			(unlocked yes)
			(layer "F.Fab")
			(hide yes)
			(effects
				(font
					(size 1.016 1.016)
					(thickness 0.1524)
				)
			)
		)
		(property "Device Type" "R402H16"
			(at 0.064008 -5.517896 90)
			(unlocked yes)
			(layer "F.Fab")
			(hide yes)
			(effects
				(font
					(size 1.016 1.016)
					(thickness 0.1524)
				)
			)
		)
		(duplicate_pad_numbers_are_jumpers no)
		(fp_line
			(start 0.508 -0.9398)
			(end -0.508 -0.9398)
			(stroke
				(width 0.1524)
				(type default)
			)
			(layer "F.SilkS")
		)
		(fp_line
			(start -0.508 -0.9398)
			(end -0.508 0.9398)
			(stroke
				(width 0.1524)
				(type default)
			)
			(layer "F.SilkS")
		)
		(fp_rect
			(start -0.508 0.9398)
			(end 0.508 -0.9398)
			(stroke
				(width 0)
				(type default)
			)
			(fill no)
			(layer "F.CrtYd")
		)
		(fp_rect
			(start -0.508 0.9398)
			(end 0.508 -0.9398)
			(stroke
				(width 0)
				(type default)
			)
			(fill no)
			(layer "F.Fab")
		)
		(pad "1" smd custom
			(at 0 -0.4445 90)
			(size 0.1397 0.1397)
			(layers "F.Cu" "F.Mask" "F.Paste")
			(net "P3V3")
			(options
				(clearance outline)
				(anchor circle)
			)
			(primitives
				(gr_poly
					(pts
						(arc
							(start -0.1778 -0.2794)
							(mid -0.249642 -0.249642)
							(end -0.2794 -0.1778)
						)
						(arc
							(start -0.2794 0.1778)
							(mid -0.249642 0.249642)
							(end -0.1778 0.2794)
						)
						(arc
							(start 0.1778 0.2794)
							(mid 0.249642 0.249642)
							(end 0.2794 0.1778)
						)
						(arc
							(start 0.2794 -0.1778)
							(mid 0.249642 -0.249642)
							(end 0.1778 -0.2794)
						)
					)
					(width 0)
					(fill yes)
				)
			)
		)
		(pad "2" smd custom
			(at 0 0.4445 90)
			(size 0.1397 0.1397)
			(layers "F.Cu" "F.Mask" "F.Paste")
			(net "I2C_B_SDA")
			(options
				(clearance outline)
				(anchor circle)
			)
			(primitives
				(gr_poly
					(pts
						(arc
							(start -0.1778 -0.2794)
							(mid -0.249642 -0.249642)
							(end -0.2794 -0.1778)
						)
						(arc
							(start -0.2794 0.1778)
							(mid -0.249642 0.249642)
							(end -0.1778 0.2794)
						)
						(arc
							(start 0.1778 0.2794)
							(mid 0.249642 0.249642)
							(end 0.2794 0.1778)
						)
						(arc
							(start 0.2794 -0.1778)
							(mid 0.249642 -0.249642)
							(end 0.1778 -0.2794)
						)
					)
					(width 0)
					(fill yes)
				)
			)
		)
	)
	(footprint ""
		(layer "F.Cu")
		(at 100.4824 -304.927 180)
		(property "Reference" "C9515"
			(at 0 0 180)
			(layer "F.SilkS")
			(hide yes)
			(effects
				(font
					(size 1.27 1.27)
				)
			)
		)
		(property "Value" "SCD1U16V2KX-3GP"
			(at 1.1811 -2.7051 180)
			(unlocked yes)
			(layer "F.Fab")
			(hide yes)
			(effects
				(font
					(size 1.016 1.016)
					(thickness 0.1524)
				)
			)
		)
		(property "Device Type" "C402H22"
			(at 1.1811 -4.2291 180)
			(unlocked yes)
			(layer "F.Fab")
			(hide yes)
			(effects
				(font
					(size 1.016 1.016)
					(thickness 0.1524)
				)
			)
		)
		(duplicate_pad_numbers_are_jumpers no)
		(fp_rect
			(start -0.4318 0.9525)
			(end 0.4318 -0.9525)
			(stroke
				(width 0)
				(type default)
			)
			(fill no)
			(layer "F.CrtYd")
		)
		(fp_rect
			(start -0.4318 0.9525)
			(end 0.4318 -0.9525)
			(stroke
				(width 0)
				(type default)
			)
			(fill no)
			(layer "F.Fab")
		)
		(pad "1" smd custom
			(at 0 -0.4445 180)
			(size 0.1524 0.1524)
			(layers "F.Cu" "F.Mask" "F.Paste")
			(net "VDD_DIFF_2")
			(options
				(clearance outline)
				(anchor circle)
			)
			(primitives
				(gr_poly
					(pts
						(arc
							(start 0.3048 -0.2032)
							(mid 0.275042 -0.275042)
							(end 0.2032 -0.3048)
						)
						(arc
							(start -0.2032 -0.3048)
							(mid -0.275042 -0.275042)
							(end -0.3048 -0.2032)
						)
						(arc
							(start -0.3048 0.2032)
							(mid -0.275042 0.275042)
							(end -0.2032 0.3048)
						)
						(arc
							(start 0.2032 0.3048)
							(mid 0.275042 0.275042)
							(end 0.3048 0.2032)
						)
					)
					(width 0)
					(fill yes)
				)
			)
		)
		(pad "2" smd custom
			(at 0 0.4445 180)
			(size 0.1524 0.1524)
			(layers "F.Cu" "F.Mask" "F.Paste")
			(net "GND")
			(options
				(clearance outline)
				(anchor circle)
			)
			(primitives
				(gr_poly
					(pts
						(arc
							(start 0.3048 -0.2032)
							(mid 0.275042 -0.275042)
							(end 0.2032 -0.3048)
						)
						(arc
							(start -0.2032 -0.3048)
							(mid -0.275042 -0.275042)
							(end -0.3048 -0.2032)
						)
						(arc
							(start -0.3048 0.2032)
							(mid -0.275042 0.275042)
							(end -0.2032 0.3048)
						)
						(arc
							(start 0.2032 0.3048)
							(mid 0.275042 0.275042)
							(end 0.3048 0.2032)
						)
					)
					(width 0)
					(fill yes)
				)
			)
		)
	)
	(footprint ""
		(layer "F.Cu")
		(at 36.576 -268.351 180)
		(property "Reference" "PC1249"
			(at 0 0 180)
			(layer "F.SilkS")
			(hide yes)
			(effects
				(font
					(size 1.27 1.27)
				)
			)
		)
		(property "Value" "SCD1U25V3KX-GP"
			(at 0 -2.8194 180)
			(unlocked yes)
			(layer "F.Fab")
			(hide yes)
			(effects
				(font
					(size 1.016 1.016)
					(thickness 0.1524)
				)
			)
		)
		(property "Device Type" "C603H36"
			(at 0 -4.3434 180)
			(unlocked yes)
			(layer "F.Fab")
			(hide yes)
			(effects
				(font
					(size 1.016 1.016)
					(thickness 0.1524)
				)
			)
		)
		(duplicate_pad_numbers_are_jumpers no)
		(fp_line
			(start 0.508 0)
			(end -0.508 0)
			(stroke
				(width 0.2032)
				(type default)
			)
			(layer "F.SilkS")
		)
		(fp_rect
			(start -0.5842 1.3335)
			(end 0.5842 -1.3335)
			(stroke
				(width 0)
				(type default)
			)
			(fill no)
			(layer "F.CrtYd")
		)
		(fp_rect
			(start -0.5842 1.3335)
			(end 0.5842 -1.3335)
			(stroke
				(width 0)
				(type default)
			)
			(fill no)
			(layer "F.Fab")
		)
		(pad "1" smd custom
			(at 0 -0.762 180)
			(size 0.2159 0.2159)
			(layers "F.Cu" "F.Mask" "F.Paste")
			(net "P3V3")
			(options
				(clearance outline)
				(anchor circle)
			)
			(primitives
				(gr_poly
					(pts
						(arc
							(start -0.3302 -0.4318)
							(mid -0.402042 -0.402042)
							(end -0.4318 -0.3302)
						)
						(arc
							(start -0.4318 0.3302)
							(mid -0.402042 0.402042)
							(end -0.3302 0.4318)
						)
						(arc
							(start 0.3302 0.4318)
							(mid 0.402042 0.402042)
							(end 0.4318 0.3302)
						)
						(arc
							(start 0.4318 -0.3302)
							(mid 0.402042 -0.402042)
							(end 0.3302 -0.4318)
						)
					)
					(width 0)
					(fill yes)
				)
			)
		)
		(pad "2" smd custom
			(at 0 0.762 180)
			(size 0.2159 0.2159)
			(layers "F.Cu" "F.Mask" "F.Paste")
			(net "GND")
			(options
				(clearance outline)
				(anchor circle)
			)
			(primitives
				(gr_poly
					(pts
						(arc
							(start -0.3302 -0.4318)
							(mid -0.402042 -0.402042)
							(end -0.4318 -0.3302)
						)
						(arc
							(start -0.4318 0.3302)
							(mid -0.402042 0.402042)
							(end -0.3302 0.4318)
						)
						(arc
							(start 0.3302 0.4318)
							(mid 0.402042 0.402042)
							(end 0.4318 0.3302)
						)
						(arc
							(start 0.4318 -0.3302)
							(mid 0.402042 -0.402042)
							(end 0.3302 -0.4318)
						)
					)
					(width 0)
					(fill yes)
				)
			)
		)
	)
	(footprint ""
		(layer "F.Cu")
		(at 85.725 -304.6857 180)
		(property "Reference" "R9964"
			(at 0 0 180)
			(layer "F.SilkS")
			(hide yes)
			(effects
				(font
					(size 1.27 1.27)
				)
			)
		)
		(property "Value" "100R1F-GP"
			(at -3.3274 -1.3335 180)
			(unlocked yes)
			(layer "F.Fab")
			(hide yes)
			(effects
				(font
					(size 1.016 1.016)
					(thickness 0.1524)
				)
			)
		)
		(property "Device Type" "R0201H12"
			(at -3.3274 -2.8575 180)
			(unlocked yes)
			(layer "F.Fab")
			(hide yes)
			(effects
				(font
					(size 1.016 1.016)
					(thickness 0.1524)
				)
			)
		)
		(duplicate_pad_numbers_are_jumpers no)
		(fp_rect
			(start -0.2794 0.6477)
			(end 0.2794 -0.6477)
			(stroke
				(width 0)
				(type default)
			)
			(fill no)
			(layer "F.CrtYd")
		)
		(fp_rect
			(start -0.2794 0.6477)
			(end 0.2794 -0.6477)
			(stroke
				(width 0)
				(type default)
			)
			(fill no)
			(layer "F.Fab")
		)
		(pad "1" smd custom
			(at 0 -0.2794 180)
			(size 0.0762 0.0762)
			(layers "F.Cu" "F.Mask" "F.Paste")
			(net "PE_100M_CLK3_N")
			(options
				(clearance outline)
				(anchor circle)
			)
			(primitives
				(gr_poly
					(pts
						(arc
							(start 0.1524 -0.127)
							(mid 0.137521 -0.162921)
							(end 0.1016 -0.1778)
						)
						(arc
							(start -0.1016 -0.1778)
							(mid -0.137521 -0.162921)
							(end -0.1524 -0.127)
						)
						(arc
							(start -0.1524 0.127)
							(mid -0.137521 0.162921)
							(end -0.1016 0.1778)
						)
						(arc
							(start 0.1016 0.1778)
							(mid 0.137521 0.162921)
							(end 0.1524 0.127)
						)
					)
					(width 0)
					(fill yes)
				)
			)
		)
		(pad "2" smd custom
			(at 0 0.2794 180)
			(size 0.0762 0.0762)
			(layers "F.Cu" "F.Mask" "F.Paste")
			(net "PE_100M_CLK3_P")
			(options
				(clearance outline)
				(anchor circle)
			)
			(primitives
				(gr_poly
					(pts
						(arc
							(start 0.1524 -0.127)
							(mid 0.137521 -0.162921)
							(end 0.1016 -0.1778)
						)
						(arc
							(start -0.1016 -0.1778)
							(mid -0.137521 -0.162921)
							(end -0.1524 -0.127)
						)
						(arc
							(start -0.1524 0.127)
							(mid -0.137521 0.162921)
							(end -0.1016 0.1778)
						)
						(arc
							(start 0.1016 0.1778)
							(mid 0.137521 0.162921)
							(end 0.1524 0.127)
						)
					)
					(width 0)
					(fill yes)
				)
			)
		)
	)
	(footprint ""
		(layer "F.Cu")
		(at 24.003 -378.968 90)
		(property "Reference" "R335"
			(at 0 0 90)
			(layer "F.SilkS")
			(hide yes)
			(effects
				(font
					(size 1.27 1.27)
				)
			)
		)
		(property "Value" "0R2J-2-GP"
			(at 0.064008 -3.993896 90)
			(unlocked yes)
			(layer "F.Fab")
			(hide yes)
			(effects
				(font
					(size 1.016 1.016)
					(thickness 0.1524)
				)
			)
		)
		(property "Device Type" "R402H16"
			(at 0.064008 -5.517896 90)
			(unlocked yes)
			(layer "F.Fab")
			(hide yes)
			(effects
				(font
					(size 1.016 1.016)
					(thickness 0.1524)
				)
			)
		)
		(duplicate_pad_numbers_are_jumpers no)
		(fp_line
			(start 0.508 -0.9398)
			(end -0.508 -0.9398)
			(stroke
				(width 0.1524)
				(type default)
			)
			(layer "F.SilkS")
		)
		(fp_line
			(start -0.508 -0.9398)
			(end -0.508 0.9398)
			(stroke
				(width 0.1524)
				(type default)
			)
			(layer "F.SilkS")
		)
		(fp_rect
			(start -0.508 0.9398)
			(end 0.508 -0.9398)
			(stroke
				(width 0)
				(type default)
			)
			(fill no)
			(layer "F.CrtYd")
		)
		(fp_rect
			(start -0.508 0.9398)
			(end 0.508 -0.9398)
			(stroke
				(width 0)
				(type default)
			)
			(fill no)
			(layer "F.Fab")
		)
		(pad "1" smd custom
			(at 0 -0.4445 90)
			(size 0.1397 0.1397)
			(layers "F.Cu" "F.Mask" "F.Paste")
			(net "I2C_B_SCL")
			(options
				(clearance outline)
				(anchor circle)
			)
			(primitives
				(gr_poly
					(pts
						(arc
							(start -0.1778 -0.2794)
							(mid -0.249642 -0.249642)
							(end -0.2794 -0.1778)
						)
						(arc
							(start -0.2794 0.1778)
							(mid -0.249642 0.249642)
							(end -0.1778 0.2794)
						)
						(arc
							(start 0.1778 0.2794)
							(mid 0.249642 0.249642)
							(end 0.2794 0.1778)
						)
						(arc
							(start 0.2794 -0.1778)
							(mid 0.249642 -0.249642)
							(end 0.1778 -0.2794)
						)
					)
					(width 0)
					(fill yes)
				)
			)
		)
		(pad "2" smd custom
			(at 0 0.4445 90)
			(size 0.1397 0.1397)
			(layers "F.Cu" "F.Mask" "F.Paste")
			(net "TMP4_SCL")
			(options
				(clearance outline)
				(anchor circle)
			)
			(primitives
				(gr_poly
					(pts
						(arc
							(start -0.1778 -0.2794)
							(mid -0.249642 -0.249642)
							(end -0.2794 -0.1778)
						)
						(arc
							(start -0.2794 0.1778)
							(mid -0.249642 0.249642)
							(end -0.1778 0.2794)
						)
						(arc
							(start 0.1778 0.2794)
							(mid 0.249642 0.249642)
							(end 0.2794 0.1778)
						)
						(arc
							(start 0.2794 -0.1778)
							(mid 0.249642 -0.249642)
							(end 0.1778 -0.2794)
						)
					)
					(width 0)
					(fill yes)
				)
			)
		)
	)
	(footprint ""
		(layer "F.Cu")
		(at 88.011 -436.499)
		(property "Reference" "C8894"
			(at 0 0 0)
			(layer "F.SilkS")
			(hide yes)
			(effects
				(font
					(size 1.27 1.27)
				)
			)
		)
		(property "Value" "SCD1U16V2KX-3GP"
			(at 1.1811 -2.7051 0)
			(unlocked yes)
			(layer "F.Fab")
			(hide yes)
			(effects
				(font
					(size 1.016 1.016)
					(thickness 0.1524)
				)
			)
		)
		(property "Device Type" "C402H22"
			(at 1.1811 -4.2291 0)
			(unlocked yes)
			(layer "F.Fab")
			(hide yes)
			(effects
				(font
					(size 1.016 1.016)
					(thickness 0.1524)
				)
			)
		)
		(duplicate_pad_numbers_are_jumpers no)
		(fp_rect
			(start -0.4318 0.9525)
			(end 0.4318 -0.9525)
			(stroke
				(width 0)
				(type default)
			)
			(fill no)
			(layer "F.CrtYd")
		)
		(fp_rect
			(start -0.4318 0.9525)
			(end 0.4318 -0.9525)
			(stroke
				(width 0)
				(type default)
			)
			(fill no)
			(layer "F.Fab")
		)
		(pad "1" smd custom
			(at 0 -0.4445)
			(size 0.1524 0.1524)
			(layers "F.Cu" "F.Mask" "F.Paste")
			(net "VDDA_1")
			(options
				(clearance outline)
				(anchor circle)
			)
			(primitives
				(gr_poly
					(pts
						(arc
							(start 0.3048 -0.2032)
							(mid 0.275042 -0.275042)
							(end 0.2032 -0.3048)
						)
						(arc
							(start -0.2032 -0.3048)
							(mid -0.275042 -0.275042)
							(end -0.3048 -0.2032)
						)
						(arc
							(start -0.3048 0.2032)
							(mid -0.275042 0.275042)
							(end -0.2032 0.3048)
						)
						(arc
							(start 0.2032 0.3048)
							(mid 0.275042 0.275042)
							(end 0.3048 0.2032)
						)
					)
					(width 0)
					(fill yes)
				)
			)
		)
		(pad "2" smd custom
			(at 0 0.4445)
			(size 0.1524 0.1524)
			(layers "F.Cu" "F.Mask" "F.Paste")
			(net "GND")
			(options
				(clearance outline)
				(anchor circle)
			)
			(primitives
				(gr_poly
					(pts
						(arc
							(start 0.3048 -0.2032)
							(mid 0.275042 -0.275042)
							(end 0.2032 -0.3048)
						)
						(arc
							(start -0.2032 -0.3048)
							(mid -0.275042 -0.275042)
							(end -0.3048 -0.2032)
						)
						(arc
							(start -0.3048 0.2032)
							(mid -0.275042 0.275042)
							(end -0.2032 0.3048)
						)
						(arc
							(start 0.2032 0.3048)
							(mid 0.275042 0.275042)
							(end 0.3048 0.2032)
						)
					)
					(width 0)
					(fill yes)
				)
			)
		)
	)
	(footprint ""
		(layer "F.Cu")
		(at 93.98 -210.82 90)
		(property "Reference" "EU3"
			(at 0 0 90)
			(layer "F.SilkS")
			(hide yes)
			(effects
				(font
					(size 1.27 1.27)
				)
			)
		)
		(property "Value" "9ZXL1231AKLFT-GP"
			(at -6.5278 -7.2009 90)
			(unlocked yes)
			(layer "F.Fab")
			(hide yes)
			(effects
				(font
					(size 1.016 1.016)
					(thickness 0.1524)
				)
			)
		)
		(property "Device Type" "QFN64G9-G6D25H40"
			(at -6.5278 -8.7249 90)
			(unlocked yes)
			(layer "F.Fab")
			(hide yes)
			(effects
				(font
					(size 1.016 1.016)
					(thickness 0.1524)
				)
			)
		)
		(duplicate_pad_numbers_are_jumpers no)
		(fp_line
			(start 1.7526 -5.71881)
			(end 1.7526 -5.21081)
			(stroke
				(width 0.1524)
				(type default)
			)
			(layer "F.SilkS")
		)
		(fp_line
			(start -3.2639 -5.71881)
			(end -3.2639 -5.21081)
			(stroke
				(width 0.1524)
				(type default)
			)
			(layer "F.SilkS")
		)
		(fp_line
			(start -3.9878 -5.5118)
			(end -5.5118 -5.5118)
			(stroke
				(width 0.1524)
				(type default)
			)
			(layer "F.SilkS")
		)
		(fp_line
			(start -5.5118 -5.5118)
			(end -5.5118 -3.9243)
			(stroke
				(width 0.1524)
				(type default)
			)
			(layer "F.SilkS")
		)
		(fp_line
			(start -0.74041 -5.21081)
			(end -0.74041 -5.97281)
			(stroke
				(width 0.1524)
				(type default)
			)
			(layer "F.SilkS")
		)
		(fp_line
			(start -5.97281 -2.2606)
			(end -5.21081 -2.2606)
			(stroke
				(width 0.1524)
				(type default)
			)
			(layer "F.SilkS")
		)
		(fp_line
			(start 5.21081 -1.778)
			(end 5.97281 -1.778)
			(stroke
				(width 0.1524)
				(type default)
			)
			(layer "F.SilkS")
		)
		(fp_line
			(start -5.21081 0.254)
			(end -5.71881 0.254)
			(stroke
				(width 0.1524)
				(type default)
			)
			(layer "F.SilkS")
		)
		(fp_line
			(start 5.71881 0.7112)
			(end 5.21081 0.7112)
			(stroke
				(width 0.1524)
				(type default)
			)
			(layer "F.SilkS")
		)
		(fp_line
			(start -5.97281 2.7432)
			(end -5.21081 2.7432)
			(stroke
				(width 0.1524)
				(type default)
			)
			(layer "F.SilkS")
		)
		(fp_line
			(start 5.21081 3.22961)
			(end 5.97281 3.22961)
			(stroke
				(width 0.1524)
				(type default)
			)
			(layer "F.SilkS")
		)
		(fp_line
			(start -5.4991 4.1148)
			(end -5.4991 5.5118)
			(stroke
				(width 0.1524)
				(type default)
			)
			(layer "F.SilkS")
		)
		(fp_line
			(start 2.2352 5.21081)
			(end 2.2352 5.71881)
			(stroke
				(width 0.1524)
				(type default)
			)
			(layer "F.SilkS")
		)
		(fp_line
			(start -2.7432 5.21081)
			(end -2.7432 5.71881)
			(stroke
				(width 0.1524)
				(type default)
			)
			(layer "F.SilkS")
		)
		(fp_line
			(start 5.5118 5.4991)
			(end 5.5118 3.9878)
			(stroke
				(width 0.1524)
				(type default)
			)
			(layer "F.SilkS")
		)
		(fp_line
			(start 4.0767 5.4991)
			(end 5.5118 5.4991)
			(stroke
				(width 0.1524)
				(type default)
			)
			(layer "F.SilkS")
		)
		(fp_line
			(start -5.4991 5.5118)
			(end -4.2037 5.5118)
			(stroke
				(width 0.1524)
				(type default)
			)
			(layer "F.SilkS")
		)
		(fp_line
			(start -0.7366 5.97281)
			(end -0.7366 5.21081)
			(stroke
				(width 0.1524)
				(type default)
			)
			(layer "F.SilkS")
		)
		(fp_poly
			(pts
				(xy 5.5118 -4.05511) (xy 4.05511 -5.5118) (xy 5.5118 -5.5118)
			)
			(stroke
				(width 0)
				(type default)
			)
			(fill yes)
			(layer "F.SilkS")
		)
		(fp_rect
			(start -4.4958 4.4958)
			(end 4.4958 -4.4958)
			(stroke
				(width 0)
				(type default)
			)
			(fill no)
			(layer "F.CrtYd")
		)
		(fp_poly
			(pts
				(xy -5.5118 5.5118) (xy -5.5118 -5.5118) (xy 5.5118 -5.5118) (xy 5.5118 -0.5461) (xy 4.4958 -0.5461)
				(xy 4.4958 -4.4958) (xy -4.4958 -4.4958) (xy -4.4958 4.4958) (xy 4.4958 4.4958) (xy 4.4958 -0.5334)
				(xy 5.5118 -0.5334) (xy 5.5118 5.5118)
			)
			(stroke
				(width 0)
				(type default)
			)
			(fill no)
			(layer "F.CrtYd")
		)
		(fp_rect
			(start -5.5118 5.5118)
			(end 5.5118 -5.5118)
			(stroke
				(width 0)
				(type default)
			)
			(fill no)
			(layer "F.Fab")
		)
		(pad "1" smd rect
			(at 3.75031 -4.550918 90)
			(size 0.3048 0.9144)
			(layers "F.Cu" "F.Mask" "F.Paste")
			(net "VDDA_3")
		)
		(pad "2" smd rect
			(at 3.24993 -4.42341 90)
			(size 0.3048 1.1684)
			(layers "F.Cu" "F.Mask" "F.Paste")
			(net "GND")
		)
		(pad "3" smd rect
			(at 2.74955 -4.42341 90)
			(size 0.3048 1.1684)
			(layers "F.Cu" "F.Mask" "F.Paste")
			(net "Net_1326")
		)
		(pad "4" smd rect
			(at 2.25044 -4.42341 90)
			(size 0.3048 1.1684)
			(layers "F.Cu" "F.Mask" "F.Paste")
			(net "CLK_BUF_EU3_100M_133M#")
		)
		(pad "5" smd rect
			(at 1.75006 -4.42341 90)
			(size 0.3048 1.1684)
			(layers "F.Cu" "F.Mask" "F.Paste")
			(net "CLK_BUF_EU3_HIBW_BYPM_LOBW#")
		)
		(pad "6" smd rect
			(at 1.24968 -4.42341 90)
			(size 0.3048 1.1684)
			(layers "F.Cu" "F.Mask" "F.Paste")
			(net "P3V3_PG")
		)
		(pad "7" smd rect
			(at 0.75057 -4.42341 90)
			(size 0.3048 1.1684)
			(layers "F.Cu" "F.Mask" "F.Paste")
			(net "GND")
		)
		(pad "8" smd rect
			(at 0.25019 -4.42341 90)
			(size 0.3048 1.1684)
			(layers "F.Cu" "F.Mask" "F.Paste")
			(net "VDDR_3")
		)
		(pad "9" smd rect
			(at -0.25019 -4.42341 90)
			(size 0.3048 1.1684)
			(layers "F.Cu" "F.Mask" "F.Paste")
			(net "PE_100M_CLK2_P")
		)
		(pad "10" smd rect
			(at -0.75057 -4.42341 90)
			(size 0.3048 1.1684)
			(layers "F.Cu" "F.Mask" "F.Paste")
			(net "PE_100M_CLK2_N")
		)
		(pad "11" smd rect
			(at -1.24968 -4.42341 90)
			(size 0.3048 1.1684)
			(layers "F.Cu" "F.Mask" "F.Paste")
			(net "CLK_BUF_EU3_SMB_A0_TRI")
		)
		(pad "12" smd rect
			(at -1.75006 -4.42341 90)
			(size 0.3048 1.1684)
			(layers "F.Cu" "F.Mask" "F.Paste")
			(net "I2C_SDA_BUF_8_EU3_R")
		)
		(pad "13" smd rect
			(at -2.25044 -4.42341 90)
			(size 0.3048 1.1684)
			(layers "F.Cu" "F.Mask" "F.Paste")
			(net "I2C_SCL_BUF_8_EU3_R")
		)
		(pad "14" smd rect
			(at -2.74955 -4.42341 90)
			(size 0.3048 1.1684)
			(layers "F.Cu" "F.Mask" "F.Paste")
			(net "CLK_BUF_EU3_SMB_A1_TRI")
		)
		(pad "15" smd rect
			(at -3.24993 -4.42341 90)
			(size 0.3048 1.1684)
			(layers "F.Cu" "F.Mask" "F.Paste")
			(net "Net_1328")
		)
		(pad "16" smd rect
			(at -3.75031 -4.550918 90)
			(size 0.3048 0.9144)
			(layers "F.Cu" "F.Mask" "F.Paste")
			(net "Net_1327")
		)
		(pad "17" smd rect
			(at -4.550918 -3.75031 90)
			(size 0.9144 0.3048)
			(layers "F.Cu" "F.Mask" "F.Paste")
			(net "Net_331")
		)
		(pad "18" smd rect
			(at -4.42341 -3.24993 90)
			(size 1.1684 0.3048)
			(layers "F.Cu" "F.Mask" "F.Paste")
			(net "Net_330")
		)
		(pad "19" smd rect
			(at -4.42341 -2.74955 90)
			(size 1.1684 0.3048)
			(layers "F.Cu" "F.Mask" "F.Paste")
			(net "CLK_BUFFER_EU3_VOE_N")
		)
		(pad "20" smd rect
			(at -4.42341 -2.25044 90)
			(size 1.1684 0.3048)
			(layers "F.Cu" "F.Mask" "F.Paste")
			(net "CLK_BUFFER_EU3_VOE_N")
		)
		(pad "21" smd rect
			(at -4.42341 -1.75006 90)
			(size 1.1684 0.3048)
			(layers "F.Cu" "F.Mask" "F.Paste")
			(net "Net_329")
		)
		(pad "22" smd rect
			(at -4.42341 -1.24968 90)
			(size 1.1684 0.3048)
			(layers "F.Cu" "F.Mask" "F.Paste")
			(net "Net_328")
		)
		(pad "23" smd rect
			(at -4.42341 -0.75057 90)
			(size 1.1684 0.3048)
			(layers "F.Cu" "F.Mask" "F.Paste")
			(net "GND")
		)
		(pad "24" smd rect
			(at -4.42341 -0.25019 90)
			(size 1.1684 0.3048)
			(layers "F.Cu" "F.Mask" "F.Paste")
			(net "VDD_DIFF_3")
		)
		(pad "25" smd rect
			(at -4.42341 0.25019 90)
			(size 1.1684 0.3048)
			(layers "F.Cu" "F.Mask" "F.Paste")
			(net "VDD_IO_3")
		)
		(pad "26" smd rect
			(at -4.42341 0.75057 90)
			(size 1.1684 0.3048)
			(layers "F.Cu" "F.Mask" "F.Paste")
			(net "PE_CLK_100M_DR4_2_R_P")
		)
		(pad "27" smd rect
			(at -4.42341 1.24968 90)
			(size 1.1684 0.3048)
			(layers "F.Cu" "F.Mask" "F.Paste")
			(net "PE_CLK_100M_DR4_2_R_N")
		)
		(pad "28" smd rect
			(at -4.42341 1.75006 90)
			(size 1.1684 0.3048)
			(layers "F.Cu" "F.Mask" "F.Paste")
			(net "SSD_PRSNT4")
		)
		(pad "29" smd rect
			(at -4.42341 2.25044 90)
			(size 1.1684 0.3048)
			(layers "F.Cu" "F.Mask" "F.Paste")
			(net "SSD4_CLK0_OE_R_N")
		)
		(pad "30" smd rect
			(at -4.42341 2.74955 90)
			(size 1.1684 0.3048)
			(layers "F.Cu" "F.Mask" "F.Paste")
			(net "PE_CLK_100M_DR4_1_R_P")
		)
		(pad "31" smd rect
			(at -4.42341 3.24993 90)
			(size 1.1684 0.3048)
			(layers "F.Cu" "F.Mask" "F.Paste")
			(net "PE_CLK_100M_DR4_1_R_N")
		)
		(pad "32" smd rect
			(at -4.550918 3.75031 90)
			(size 0.9144 0.3048)
			(layers "F.Cu" "F.Mask" "F.Paste")
			(net "VDD_IO_3")
		)
		(pad "33" smd rect
			(at -3.75031 4.550918 90)
			(size 0.3048 0.9144)
			(layers "F.Cu" "F.Mask" "F.Paste")
			(net "GND")
		)
		(pad "34" smd rect
			(at -3.24993 4.42341 90)
			(size 0.3048 1.1684)
			(layers "F.Cu" "F.Mask" "F.Paste")
			(net "PE_CLK_100M_DR3_2_R_P")
		)
		(pad "35" smd rect
			(at -2.74955 4.42341 90)
			(size 0.3048 1.1684)
			(layers "F.Cu" "F.Mask" "F.Paste")
			(net "PE_CLK_100M_DR3_2_R_N")
		)
		(pad "36" smd rect
			(at -2.25044 4.42341 90)
			(size 0.3048 1.1684)
			(layers "F.Cu" "F.Mask" "F.Paste")
			(net "SSD_PRSNT3")
		)
		(pad "37" smd rect
			(at -1.75006 4.42341 90)
			(size 0.3048 1.1684)
			(layers "F.Cu" "F.Mask" "F.Paste")
			(net "SSD3_CLK0_OE_R_N")
		)
		(pad "38" smd rect
			(at -1.24968 4.42341 90)
			(size 0.3048 1.1684)
			(layers "F.Cu" "F.Mask" "F.Paste")
			(net "PE_CLK_100M_DR3_1_R_P")
		)
		(pad "39" smd rect
			(at -0.75057 4.42341 90)
			(size 0.3048 1.1684)
			(layers "F.Cu" "F.Mask" "F.Paste")
			(net "PE_CLK_100M_DR3_1_R_N")
		)
		(pad "40" smd rect
			(at -0.25019 4.42341 90)
			(size 0.3048 1.1684)
			(layers "F.Cu" "F.Mask" "F.Paste")
			(net "VDD_DIFF_3")
		)
		(pad "41" smd rect
			(at 0.25019 4.42341 90)
			(size 0.3048 1.1684)
			(layers "F.Cu" "F.Mask" "F.Paste")
			(net "GND")
		)
		(pad "42" smd rect
			(at 0.75057 4.42341 90)
			(size 0.3048 1.1684)
			(layers "F.Cu" "F.Mask" "F.Paste")
			(net "Net_309")
		)
		(pad "43" smd rect
			(at 1.24968 4.42341 90)
			(size 0.3048 1.1684)
			(layers "F.Cu" "F.Mask" "F.Paste")
			(net "Net_308")
		)
		(pad "44" smd rect
			(at 1.75006 4.42341 90)
			(size 0.3048 1.1684)
			(layers "F.Cu" "F.Mask" "F.Paste")
			(net "CLK_BUFFER_EU3_VOE_N")
		)
		(pad "45" smd rect
			(at 2.25044 4.42341 90)
			(size 0.3048 1.1684)
			(layers "F.Cu" "F.Mask" "F.Paste")
			(net "CLK_BUFFER_EU3_VOE_N")
		)
		(pad "46" smd rect
			(at 2.74955 4.42341 90)
			(size 0.3048 1.1684)
			(layers "F.Cu" "F.Mask" "F.Paste")
			(net "Net_311")
		)
		(pad "47" smd rect
			(at 3.24993 4.42341 90)
			(size 0.3048 1.1684)
			(layers "F.Cu" "F.Mask" "F.Paste")
			(net "Net_310")
		)
		(pad "48" smd rect
			(at 3.75031 4.550918 90)
			(size 0.3048 0.9144)
			(layers "F.Cu" "F.Mask" "F.Paste")
			(net "GND")
		)
		(pad "49" smd rect
			(at 4.550918 3.75031 90)
			(size 0.9144 0.3048)
			(layers "F.Cu" "F.Mask" "F.Paste")
			(net "VDD_IO_3")
		)
		(pad "50" smd rect
			(at 4.42341 3.24993 90)
			(size 1.1684 0.3048)
			(layers "F.Cu" "F.Mask" "F.Paste")
			(net "PE_CLK_100M_DR7_2_R_P")
		)
		(pad "51" smd rect
			(at 4.42341 2.74955 90)
			(size 1.1684 0.3048)
			(layers "F.Cu" "F.Mask" "F.Paste")
			(net "PE_CLK_100M_DR7_2_R_N")
		)
		(pad "52" smd rect
			(at 4.42341 2.25044 90)
			(size 1.1684 0.3048)
			(layers "F.Cu" "F.Mask" "F.Paste")
			(net "SSD_PRSNT7")
		)
		(pad "53" smd rect
			(at 4.42341 1.75006 90)
			(size 1.1684 0.3048)
			(layers "F.Cu" "F.Mask" "F.Paste")
			(net "SSD7_CLK0_OE_R_N")
		)
		(pad "54" smd rect
			(at 4.42341 1.24968 90)
			(size 1.1684 0.3048)
			(layers "F.Cu" "F.Mask" "F.Paste")
			(net "PE_CLK_100M_DR7_1_R_P")
		)
		(pad "55" smd rect
			(at 4.42341 0.75057 90)
			(size 1.1684 0.3048)
			(layers "F.Cu" "F.Mask" "F.Paste")
			(net "PE_CLK_100M_DR7_1_R_N")
		)
		(pad "56" smd rect
			(at 4.42341 0.25019 90)
			(size 1.1684 0.3048)
			(layers "F.Cu" "F.Mask" "F.Paste")
			(net "VDD_IO_3")
		)
		(pad "57" smd rect
			(at 4.42341 -0.25019 90)
			(size 1.1684 0.3048)
			(layers "F.Cu" "F.Mask" "F.Paste")
			(net "VDD_DIFF_3")
		)
		(pad "58" smd rect
			(at 4.42341 -0.75057 90)
			(size 1.1684 0.3048)
			(layers "F.Cu" "F.Mask" "F.Paste")
			(net "GND")
		)
		(pad "59" smd rect
			(at 4.42341 -1.24968 90)
			(size 1.1684 0.3048)
			(layers "F.Cu" "F.Mask" "F.Paste")
			(net "PE_CLK_100M_DR12_2_R_P")
		)
		(pad "60" smd rect
			(at 4.42341 -1.75006 90)
			(size 1.1684 0.3048)
			(layers "F.Cu" "F.Mask" "F.Paste")
			(net "PE_CLK_100M_DR12_2_R_N")
		)
		(pad "61" smd rect
			(at 4.42341 -2.25044 90)
			(size 1.1684 0.3048)
			(layers "F.Cu" "F.Mask" "F.Paste")
			(net "SSD_PRSNT12")
		)
		(pad "62" smd rect
			(at 4.42341 -2.74955 90)
			(size 1.1684 0.3048)
			(layers "F.Cu" "F.Mask" "F.Paste")
			(net "SSD12_CLK0_OE_R_N")
		)
		(pad "63" smd rect
			(at 4.42341 -3.24993 90)
			(size 1.1684 0.3048)
			(layers "F.Cu" "F.Mask" "F.Paste")
			(net "PE_CLK_100M_DR12_1_R_P")
		)
		(pad "64" smd rect
			(at 4.550918 -3.75031 90)
			(size 0.9144 0.3048)
			(layers "F.Cu" "F.Mask" "F.Paste")
			(net "PE_CLK_100M_DR12_1_R_N")
		)
		(pad "65" smd rect
			(at 0 0 90)
			(size 6.2484 6.2484)
			(layers "F.Cu" "F.Mask" "F.Paste")
			(net "GND")
		)
	)
	(footprint ""
		(layer "F.Cu")
		(at 82.931 -106.934 90)
		(property "Reference" "SR954"
			(at 0 0 90)
			(layer "F.SilkS")
			(hide yes)
			(effects
				(font
					(size 1.27 1.27)
				)
			)
		)
		(property "Value" "4K7R2F-GP"
			(at 0.064008 -3.993896 90)
			(unlocked yes)
			(layer "F.Fab")
			(hide yes)
			(effects
				(font
					(size 1.016 1.016)
					(thickness 0.1524)
				)
			)
		)
		(property "Device Type" "R402H16"
			(at 0.064008 -5.517896 90)
			(unlocked yes)
			(layer "F.Fab")
			(hide yes)
			(effects
				(font
					(size 1.016 1.016)
					(thickness 0.1524)
				)
			)
		)
		(duplicate_pad_numbers_are_jumpers no)
		(fp_line
			(start 0.508 -0.9398)
			(end -0.508 -0.9398)
			(stroke
				(width 0.1524)
				(type default)
			)
			(layer "F.SilkS")
		)
		(fp_line
			(start -0.508 -0.9398)
			(end -0.508 0.9398)
			(stroke
				(width 0.1524)
				(type default)
			)
			(layer "F.SilkS")
		)
		(fp_rect
			(start -0.508 0.9398)
			(end 0.508 -0.9398)
			(stroke
				(width 0)
				(type default)
			)
			(fill no)
			(layer "F.CrtYd")
		)
		(fp_rect
			(start -0.508 0.9398)
			(end 0.508 -0.9398)
			(stroke
				(width 0)
				(type default)
			)
			(fill no)
			(layer "F.Fab")
		)
		(pad "1" smd custom
			(at 0 -0.4445 90)
			(size 0.1397 0.1397)
			(layers "F.Cu" "F.Mask" "F.Paste")
			(net "VDD_DIFF_4")
			(options
				(clearance outline)
				(anchor circle)
			)
			(primitives
				(gr_poly
					(pts
						(arc
							(start -0.1778 -0.2794)
							(mid -0.249642 -0.249642)
							(end -0.2794 -0.1778)
						)
						(arc
							(start -0.2794 0.1778)
							(mid -0.249642 0.249642)
							(end -0.1778 0.2794)
						)
						(arc
							(start 0.1778 0.2794)
							(mid 0.249642 0.249642)
							(end 0.2794 0.1778)
						)
						(arc
							(start 0.2794 -0.1778)
							(mid 0.249642 -0.249642)
							(end 0.1778 -0.2794)
						)
					)
					(width 0)
					(fill yes)
				)
			)
		)
		(pad "2" smd custom
			(at 0 0.4445 90)
			(size 0.1397 0.1397)
			(layers "F.Cu" "F.Mask" "F.Paste")
			(net "CLK_BUF_EU4_100M_133M#")
			(options
				(clearance outline)
				(anchor circle)
			)
			(primitives
				(gr_poly
					(pts
						(arc
							(start -0.1778 -0.2794)
							(mid -0.249642 -0.249642)
							(end -0.2794 -0.1778)
						)
						(arc
							(start -0.2794 0.1778)
							(mid -0.249642 0.249642)
							(end -0.1778 0.2794)
						)
						(arc
							(start 0.1778 0.2794)
							(mid 0.249642 0.249642)
							(end 0.2794 0.1778)
						)
						(arc
							(start 0.2794 -0.1778)
							(mid 0.249642 -0.249642)
							(end 0.1778 -0.2794)
						)
					)
					(width 0)
					(fill yes)
				)
			)
		)
	)
	(footprint ""
		(layer "F.Cu")
		(at 82.931 -215.138 90)
		(property "Reference" "SR953"
			(at 0 0 90)
			(layer "F.SilkS")
			(hide yes)
			(effects
				(font
					(size 1.27 1.27)
				)
			)
		)
		(property "Value" "4K7R2F-GP"
			(at 0.064008 -3.993896 90)
			(unlocked yes)
			(layer "F.Fab")
			(hide yes)
			(effects
				(font
					(size 1.016 1.016)
					(thickness 0.1524)
				)
			)
		)
		(property "Device Type" "R402H16"
			(at 0.064008 -5.517896 90)
			(unlocked yes)
			(layer "F.Fab")
			(hide yes)
			(effects
				(font
					(size 1.016 1.016)
					(thickness 0.1524)
				)
			)
		)
		(duplicate_pad_numbers_are_jumpers no)
		(fp_line
			(start 0.508 -0.9398)
			(end -0.508 -0.9398)
			(stroke
				(width 0.1524)
				(type default)
			)
			(layer "F.SilkS")
		)
		(fp_line
			(start -0.508 -0.9398)
			(end -0.508 0.9398)
			(stroke
				(width 0.1524)
				(type default)
			)
			(layer "F.SilkS")
		)
		(fp_rect
			(start -0.508 0.9398)
			(end 0.508 -0.9398)
			(stroke
				(width 0)
				(type default)
			)
			(fill no)
			(layer "F.CrtYd")
		)
		(fp_rect
			(start -0.508 0.9398)
			(end 0.508 -0.9398)
			(stroke
				(width 0)
				(type default)
			)
			(fill no)
			(layer "F.Fab")
		)
		(pad "1" smd custom
			(at 0 -0.4445 90)
			(size 0.1397 0.1397)
			(layers "F.Cu" "F.Mask" "F.Paste")
			(net "VDD_DIFF_3")
			(options
				(clearance outline)
				(anchor circle)
			)
			(primitives
				(gr_poly
					(pts
						(arc
							(start -0.1778 -0.2794)
							(mid -0.249642 -0.249642)
							(end -0.2794 -0.1778)
						)
						(arc
							(start -0.2794 0.1778)
							(mid -0.249642 0.249642)
							(end -0.1778 0.2794)
						)
						(arc
							(start 0.1778 0.2794)
							(mid 0.249642 0.249642)
							(end 0.2794 0.1778)
						)
						(arc
							(start 0.2794 -0.1778)
							(mid 0.249642 -0.249642)
							(end 0.1778 -0.2794)
						)
					)
					(width 0)
					(fill yes)
				)
			)
		)
		(pad "2" smd custom
			(at 0 0.4445 90)
			(size 0.1397 0.1397)
			(layers "F.Cu" "F.Mask" "F.Paste")
			(net "CLK_BUF_EU3_HIBW_BYPM_LOBW#")
			(options
				(clearance outline)
				(anchor circle)
			)
			(primitives
				(gr_poly
					(pts
						(arc
							(start -0.1778 -0.2794)
							(mid -0.249642 -0.249642)
							(end -0.2794 -0.1778)
						)
						(arc
							(start -0.2794 0.1778)
							(mid -0.249642 0.249642)
							(end -0.1778 0.2794)
						)
						(arc
							(start 0.1778 0.2794)
							(mid 0.249642 0.249642)
							(end 0.2794 0.1778)
						)
						(arc
							(start 0.2794 -0.1778)
							(mid 0.249642 -0.249642)
							(end 0.1778 -0.2794)
						)
					)
					(width 0)
					(fill yes)
				)
			)
		)
	)
	(footprint ""
		(layer "F.Cu")
		(at 102.616 -306.705 90)
		(property "Reference" "R9074"
			(at 0 0 90)
			(layer "F.SilkS")
			(hide yes)
			(effects
				(font
					(size 1.27 1.27)
				)
			)
		)
		(property "Value" "27R2F-GP"
			(at 0.064008 -3.993896 90)
			(unlocked yes)
			(layer "F.Fab")
			(hide yes)
			(effects
				(font
					(size 1.016 1.016)
					(thickness 0.1524)
				)
			)
		)
		(property "Device Type" "R402H16"
			(at 0.064008 -5.517896 90)
			(unlocked yes)
			(layer "F.Fab")
			(hide yes)
			(effects
				(font
					(size 1.016 1.016)
					(thickness 0.1524)
				)
			)
		)
		(duplicate_pad_numbers_are_jumpers no)
		(fp_line
			(start 0.508 -0.9398)
			(end -0.508 -0.9398)
			(stroke
				(width 0.1524)
				(type default)
			)
			(layer "F.SilkS")
		)
		(fp_line
			(start -0.508 -0.9398)
			(end -0.508 0.9398)
			(stroke
				(width 0.1524)
				(type default)
			)
			(layer "F.SilkS")
		)
		(fp_rect
			(start -0.508 0.9398)
			(end 0.508 -0.9398)
			(stroke
				(width 0)
				(type default)
			)
			(fill no)
			(layer "F.CrtYd")
		)
		(fp_rect
			(start -0.508 0.9398)
			(end 0.508 -0.9398)
			(stroke
				(width 0)
				(type default)
			)
			(fill no)
			(layer "F.Fab")
		)
		(pad "1" smd custom
			(at 0 -0.4445 90)
			(size 0.1397 0.1397)
			(layers "F.Cu" "F.Mask" "F.Paste")
			(net "PE_CLK_100M_DR1_2_R_P")
			(options
				(clearance outline)
				(anchor circle)
			)
			(primitives
				(gr_poly
					(pts
						(arc
							(start -0.1778 -0.2794)
							(mid -0.249642 -0.249642)
							(end -0.2794 -0.1778)
						)
						(arc
							(start -0.2794 0.1778)
							(mid -0.249642 0.249642)
							(end -0.1778 0.2794)
						)
						(arc
							(start 0.1778 0.2794)
							(mid 0.249642 0.249642)
							(end 0.2794 0.1778)
						)
						(arc
							(start 0.2794 -0.1778)
							(mid 0.249642 -0.249642)
							(end 0.1778 -0.2794)
						)
					)
					(width 0)
					(fill yes)
				)
			)
		)
		(pad "2" smd custom
			(at 0 0.4445 90)
			(size 0.1397 0.1397)
			(layers "F.Cu" "F.Mask" "F.Paste")
			(net "PE_CLK100M_DR1_2_P")
			(options
				(clearance outline)
				(anchor circle)
			)
			(primitives
				(gr_poly
					(pts
						(arc
							(start -0.1778 -0.2794)
							(mid -0.249642 -0.249642)
							(end -0.2794 -0.1778)
						)
						(arc
							(start -0.2794 0.1778)
							(mid -0.249642 0.249642)
							(end -0.1778 0.2794)
						)
						(arc
							(start 0.1778 0.2794)
							(mid 0.249642 0.249642)
							(end 0.2794 0.1778)
						)
						(arc
							(start 0.2794 -0.1778)
							(mid 0.249642 -0.249642)
							(end 0.1778 -0.2794)
						)
					)
					(width 0)
					(fill yes)
				)
			)
		)
	)
	(footprint ""
		(layer "F.Cu")
		(at 227.391214 -142.343632 90)
		(property "Reference" "R9934"
			(at 0 0 90)
			(layer "F.SilkS")
			(hide yes)
			(effects
				(font
					(size 1.27 1.27)
				)
			)
		)
		(property "Value" "4K7R2J-2-GP"
			(at 0.064008 -3.993896 90)
			(unlocked yes)
			(layer "F.Fab")
			(hide yes)
			(effects
				(font
					(size 1.016 1.016)
					(thickness 0.1524)
				)
			)
		)
		(property "Device Type" "R402H16"
			(at 0.064008 -5.517896 90)
			(unlocked yes)
			(layer "F.Fab")
			(hide yes)
			(effects
				(font
					(size 1.016 1.016)
					(thickness 0.1524)
				)
			)
		)
		(duplicate_pad_numbers_are_jumpers no)
		(fp_line
			(start 0.508 -0.9398)
			(end -0.508 -0.9398)
			(stroke
				(width 0.1524)
				(type default)
			)
			(layer "F.SilkS")
		)
		(fp_line
			(start -0.508 -0.9398)
			(end -0.508 0.9398)
			(stroke
				(width 0.1524)
				(type default)
			)
			(layer "F.SilkS")
		)
		(fp_rect
			(start -0.508 0.9398)
			(end 0.508 -0.9398)
			(stroke
				(width 0)
				(type default)
			)
			(fill no)
			(layer "F.CrtYd")
		)
		(fp_rect
			(start -0.508 0.9398)
			(end 0.508 -0.9398)
			(stroke
				(width 0)
				(type default)
			)
			(fill no)
			(layer "F.Fab")
		)
		(pad "1" smd custom
			(at 0 -0.4445 90)
			(size 0.1397 0.1397)
			(layers "F.Cu" "F.Mask" "F.Paste")
			(net "P3V3")
			(options
				(clearance outline)
				(anchor circle)
			)
			(primitives
				(gr_poly
					(pts
						(arc
							(start -0.1778 -0.2794)
							(mid -0.249642 -0.249642)
							(end -0.2794 -0.1778)
						)
						(arc
							(start -0.2794 0.1778)
							(mid -0.249642 0.249642)
							(end -0.1778 0.2794)
						)
						(arc
							(start 0.1778 0.2794)
							(mid 0.249642 0.249642)
							(end 0.2794 0.1778)
						)
						(arc
							(start 0.2794 -0.1778)
							(mid 0.249642 -0.249642)
							(end 0.1778 -0.2794)
						)
					)
					(width 0)
					(fill yes)
				)
			)
		)
		(pad "2" smd custom
			(at 0 0.4445 90)
			(size 0.1397 0.1397)
			(layers "F.Cu" "F.Mask" "F.Paste")
			(net "SSD_ACT_DR3_MOS_N")
			(options
				(clearance outline)
				(anchor circle)
			)
			(primitives
				(gr_poly
					(pts
						(arc
							(start -0.1778 -0.2794)
							(mid -0.249642 -0.249642)
							(end -0.2794 -0.1778)
						)
						(arc
							(start -0.2794 0.1778)
							(mid -0.249642 0.249642)
							(end -0.1778 0.2794)
						)
						(arc
							(start 0.1778 0.2794)
							(mid 0.249642 0.249642)
							(end 0.2794 0.1778)
						)
						(arc
							(start 0.2794 -0.1778)
							(mid 0.249642 -0.249642)
							(end 0.1778 -0.2794)
						)
					)
					(width 0)
					(fill yes)
				)
			)
		)
	)
	(footprint ""
		(layer "F.Cu")
		(at 31.10103 -187.684918 180)
		(property "Reference" "SR1108"
			(at 0 0 180)
			(layer "F.SilkS")
			(hide yes)
			(effects
				(font
					(size 1.27 1.27)
				)
			)
		)
		(property "Value" "4K7R2F-GP"
			(at 0.064008 -3.993896 180)
			(unlocked yes)
			(layer "F.Fab")
			(hide yes)
			(effects
				(font
					(size 1.016 1.016)
					(thickness 0.1524)
				)
			)
		)
		(property "Device Type" "R402H16"
			(at 0.064008 -5.517896 180)
			(unlocked yes)
			(layer "F.Fab")
			(hide yes)
			(effects
				(font
					(size 1.016 1.016)
					(thickness 0.1524)
				)
			)
		)
		(duplicate_pad_numbers_are_jumpers no)
		(fp_line
			(start 0.508 -0.9398)
			(end -0.508 -0.9398)
			(stroke
				(width 0.1524)
				(type default)
			)
			(layer "F.SilkS")
		)
		(fp_line
			(start -0.508 -0.9398)
			(end -0.508 0.9398)
			(stroke
				(width 0.1524)
				(type default)
			)
			(layer "F.SilkS")
		)
		(fp_rect
			(start -0.508 0.9398)
			(end 0.508 -0.9398)
			(stroke
				(width 0)
				(type default)
			)
			(fill no)
			(layer "F.CrtYd")
		)
		(fp_rect
			(start -0.508 0.9398)
			(end 0.508 -0.9398)
			(stroke
				(width 0)
				(type default)
			)
			(fill no)
			(layer "F.Fab")
		)
		(pad "1" smd custom
			(at 0 -0.4445 180)
			(size 0.1397 0.1397)
			(layers "F.Cu" "F.Mask" "F.Paste")
			(net "DUALPORTEN#8")
			(options
				(clearance outline)
				(anchor circle)
			)
			(primitives
				(gr_poly
					(pts
						(arc
							(start -0.1778 -0.2794)
							(mid -0.249642 -0.249642)
							(end -0.2794 -0.1778)
						)
						(arc
							(start -0.2794 0.1778)
							(mid -0.249642 0.249642)
							(end -0.1778 0.2794)
						)
						(arc
							(start 0.1778 0.2794)
							(mid 0.249642 0.249642)
							(end 0.2794 0.1778)
						)
						(arc
							(start 0.2794 -0.1778)
							(mid 0.249642 -0.249642)
							(end 0.1778 -0.2794)
						)
					)
					(width 0)
					(fill yes)
				)
			)
		)
		(pad "2" smd custom
			(at 0 0.4445 180)
			(size 0.1397 0.1397)
			(layers "F.Cu" "F.Mask" "F.Paste")
			(net "GND")
			(options
				(clearance outline)
				(anchor circle)
			)
			(primitives
				(gr_poly
					(pts
						(arc
							(start -0.1778 -0.2794)
							(mid -0.249642 -0.249642)
							(end -0.2794 -0.1778)
						)
						(arc
							(start -0.2794 0.1778)
							(mid -0.249642 0.249642)
							(end -0.1778 0.2794)
						)
						(arc
							(start 0.1778 0.2794)
							(mid 0.249642 0.249642)
							(end 0.2794 0.1778)
						)
						(arc
							(start 0.2794 -0.1778)
							(mid 0.249642 -0.249642)
							(end 0.1778 -0.2794)
						)
					)
					(width 0)
					(fill yes)
				)
			)
		)
	)
	(footprint ""
		(layer "F.Cu")
		(at 228.499924 -453.099932)
		(property "Reference" "LED100"
			(at 0 0 0)
			(layer "F.SilkS")
			(hide yes)
			(effects
				(font
					(size 1.27 1.27)
				)
			)
		)
		(property "Value" "LED-RB-4-GP"
			(at 5.88899 1.80848 0)
			(unlocked yes)
			(layer "F.Fab")
			(hide yes)
			(effects
				(font
					(size 1.016 1.016)
					(thickness 0.1524)
				)
			)
		)
		(property "Device Type" "LED1613-4PH20"
			(at 5.88899 0.28448 0)
			(unlocked yes)
			(layer "F.Fab")
			(hide yes)
			(effects
				(font
					(size 1.016 1.016)
					(thickness 0.1524)
				)
			)
		)
		(duplicate_pad_numbers_are_jumpers no)
		(fp_line
			(start -1.4478 -0.9652)
			(end 1.4478 -0.9652)
			(stroke
				(width 0.1524)
				(type default)
			)
			(layer "F.SilkS")
		)
		(fp_line
			(start -1.4478 0.9652)
			(end -1.4478 -0.9652)
			(stroke
				(width 0.1524)
				(type default)
			)
			(layer "F.SilkS")
		)
		(fp_line
			(start -1.4478 0.9652)
			(end -1.4478 -0.9652)
			(stroke
				(width 0.508)
				(type default)
			)
			(layer "F.SilkS")
		)
		(fp_line
			(start 1.4478 -0.9652)
			(end 1.4478 0.9652)
			(stroke
				(width 0.1524)
				(type default)
			)
			(layer "F.SilkS")
		)
		(fp_line
			(start 1.4478 0.9652)
			(end -1.4478 0.9652)
			(stroke
				(width 0.1524)
				(type default)
			)
			(layer "F.SilkS")
		)
		(fp_rect
			(start -0.8001 0.6477)
			(end 0.8001 -0.6477)
			(stroke
				(width 0)
				(type default)
			)
			(fill no)
			(layer "F.CrtYd")
		)
		(fp_poly
			(pts
				(xy -1.7018 1.2192) (xy -1.7018 -0.06223) (xy -0.8001 -0.06223) (xy -0.8001 0.6477) (xy 0.8001 0.6477)
				(xy 0.8001 -0.6477) (xy -0.8001 -0.6477) (xy -0.8001 -0.0635) (xy -1.7018 -0.0635) (xy -1.7018 -1.2192)
				(xy 1.7018 -1.2192) (xy 1.7018 1.2192)
			)
			(stroke
				(width 0)
				(type default)
			)
			(fill no)
			(layer "F.CrtYd")
		)
		(fp_rect
			(start -1.7018 1.2192)
			(end 1.7018 -1.2192)
			(stroke
				(width 0)
				(type default)
			)
			(fill no)
			(layer "F.Fab")
		)
		(pad "1" smd rect
			(at -0.73025 0.4064)
			(size 0.9144 0.6096)
			(layers "F.Cu" "F.Mask" "F.Paste")
			(net "SSD_ACT_DR0_MOS_N")
		)
		(pad "2" smd rect
			(at -0.73025 -0.4064)
			(size 0.9144 0.6096)
			(layers "F.Cu" "F.Mask" "F.Paste")
			(net "ATTN_LED_DR0_MOS_N")
		)
		(pad "3" smd rect
			(at 0.73025 -0.4064)
			(size 0.9144 0.6096)
			(layers "F.Cu" "F.Mask" "F.Paste")
			(net "DRV_ATTN_0")
		)
		(pad "4" smd rect
			(at 0.73025 0.4064)
			(size 0.9144 0.6096)
			(layers "F.Cu" "F.Mask" "F.Paste")
			(net "DRV_ACT_0")
		)
	)
	(footprint ""
		(layer "F.Cu")
		(at 24.003 -94.234)
		(property "Reference" "R9769"
			(at 0 0 0)
			(layer "F.SilkS")
			(hide yes)
			(effects
				(font
					(size 1.27 1.27)
				)
			)
		)
		(property "Value" "4K7R2J-2-GP"
			(at 0.064008 -3.993896 0)
			(unlocked yes)
			(layer "F.Fab")
			(hide yes)
			(effects
				(font
					(size 1.016 1.016)
					(thickness 0.1524)
				)
			)
		)
		(property "Device Type" "R402H16"
			(at 0.064008 -5.517896 0)
			(unlocked yes)
			(layer "F.Fab")
			(hide yes)
			(effects
				(font
					(size 1.016 1.016)
					(thickness 0.1524)
				)
			)
		)
		(duplicate_pad_numbers_are_jumpers no)
		(fp_line
			(start -0.508 -0.9398)
			(end -0.508 0.9398)
			(stroke
				(width 0.1524)
				(type default)
			)
			(layer "F.SilkS")
		)
		(fp_line
			(start 0.508 -0.9398)
			(end -0.508 -0.9398)
			(stroke
				(width 0.1524)
				(type default)
			)
			(layer "F.SilkS")
		)
		(fp_rect
			(start -0.508 0.9398)
			(end 0.508 -0.9398)
			(stroke
				(width 0)
				(type default)
			)
			(fill no)
			(layer "F.CrtYd")
		)
		(fp_rect
			(start -0.508 0.9398)
			(end 0.508 -0.9398)
			(stroke
				(width 0)
				(type default)
			)
			(fill no)
			(layer "F.Fab")
		)
		(pad "1" smd custom
			(at 0 -0.4445)
			(size 0.1397 0.1397)
			(layers "F.Cu" "F.Mask" "F.Paste")
			(net "SSD9_PWREN")
			(options
				(clearance outline)
				(anchor circle)
			)
			(primitives
				(gr_poly
					(pts
						(arc
							(start -0.1778 -0.2794)
							(mid -0.249642 -0.249642)
							(end -0.2794 -0.1778)
						)
						(arc
							(start -0.2794 0.1778)
							(mid -0.249642 0.249642)
							(end -0.1778 0.2794)
						)
						(arc
							(start 0.1778 0.2794)
							(mid 0.249642 0.249642)
							(end 0.2794 0.1778)
						)
						(arc
							(start 0.2794 -0.1778)
							(mid 0.249642 -0.249642)
							(end 0.1778 -0.2794)
						)
					)
					(width 0)
					(fill yes)
				)
			)
		)
		(pad "2" smd custom
			(at 0 0.4445)
			(size 0.1397 0.1397)
			(layers "F.Cu" "F.Mask" "F.Paste")
			(net "GND")
			(options
				(clearance outline)
				(anchor circle)
			)
			(primitives
				(gr_poly
					(pts
						(arc
							(start -0.1778 -0.2794)
							(mid -0.249642 -0.249642)
							(end -0.2794 -0.1778)
						)
						(arc
							(start -0.2794 0.1778)
							(mid -0.249642 0.249642)
							(end -0.1778 0.2794)
						)
						(arc
							(start 0.1778 0.2794)
							(mid 0.249642 0.249642)
							(end 0.2794 0.1778)
						)
						(arc
							(start 0.2794 -0.1778)
							(mid 0.249642 -0.249642)
							(end 0.1778 -0.2794)
						)
					)
					(width 0)
					(fill yes)
				)
			)
		)
	)
	(footprint ""
		(layer "F.Cu")
		(at 86.487 -423.164)
		(property "Reference" "R9069"
			(at 0 0 0)
			(layer "F.SilkS")
			(hide yes)
			(effects
				(font
					(size 1.27 1.27)
				)
			)
		)
		(property "Value" "27R2F-GP"
			(at 0.064008 -3.993896 0)
			(unlocked yes)
			(layer "F.Fab")
			(hide yes)
			(effects
				(font
					(size 1.016 1.016)
					(thickness 0.1524)
				)
			)
		)
		(property "Device Type" "R402H16"
			(at 0.064008 -5.517896 0)
			(unlocked yes)
			(layer "F.Fab")
			(hide yes)
			(effects
				(font
					(size 1.016 1.016)
					(thickness 0.1524)
				)
			)
		)
		(duplicate_pad_numbers_are_jumpers no)
		(fp_line
			(start -0.508 -0.9398)
			(end -0.508 0.9398)
			(stroke
				(width 0.1524)
				(type default)
			)
			(layer "F.SilkS")
		)
		(fp_line
			(start 0.508 -0.9398)
			(end -0.508 -0.9398)
			(stroke
				(width 0.1524)
				(type default)
			)
			(layer "F.SilkS")
		)
		(fp_rect
			(start -0.508 0.9398)
			(end 0.508 -0.9398)
			(stroke
				(width 0)
				(type default)
			)
			(fill no)
			(layer "F.CrtYd")
		)
		(fp_rect
			(start -0.508 0.9398)
			(end 0.508 -0.9398)
			(stroke
				(width 0)
				(type default)
			)
			(fill no)
			(layer "F.Fab")
		)
		(pad "1" smd custom
			(at 0 -0.4445)
			(size 0.1397 0.1397)
			(layers "F.Cu" "F.Mask" "F.Paste")
			(net "PE_CLK_100M_DR10_2_R_P")
			(options
				(clearance outline)
				(anchor circle)
			)
			(primitives
				(gr_poly
					(pts
						(arc
							(start -0.1778 -0.2794)
							(mid -0.249642 -0.249642)
							(end -0.2794 -0.1778)
						)
						(arc
							(start -0.2794 0.1778)
							(mid -0.249642 0.249642)
							(end -0.1778 0.2794)
						)
						(arc
							(start 0.1778 0.2794)
							(mid 0.249642 0.249642)
							(end 0.2794 0.1778)
						)
						(arc
							(start 0.2794 -0.1778)
							(mid 0.249642 -0.249642)
							(end 0.1778 -0.2794)
						)
					)
					(width 0)
					(fill yes)
				)
			)
		)
		(pad "2" smd custom
			(at 0 0.4445)
			(size 0.1397 0.1397)
			(layers "F.Cu" "F.Mask" "F.Paste")
			(net "PE_CLK100M_DR10_2_P")
			(options
				(clearance outline)
				(anchor circle)
			)
			(primitives
				(gr_poly
					(pts
						(arc
							(start -0.1778 -0.2794)
							(mid -0.249642 -0.249642)
							(end -0.2794 -0.1778)
						)
						(arc
							(start -0.2794 0.1778)
							(mid -0.249642 0.249642)
							(end -0.1778 0.2794)
						)
						(arc
							(start 0.1778 0.2794)
							(mid 0.249642 0.249642)
							(end 0.2794 0.1778)
						)
						(arc
							(start 0.2794 -0.1778)
							(mid 0.249642 -0.249642)
							(end 0.1778 -0.2794)
						)
					)
					(width 0)
					(fill yes)
				)
			)
		)
	)
	(footprint ""
		(layer "F.Cu")
		(at 209.677 -454.66 180)
		(property "Reference" "R316"
			(at 0 0 180)
			(layer "F.SilkS")
			(hide yes)
			(effects
				(font
					(size 1.27 1.27)
				)
			)
		)
		(property "Value" "4K7R2F-GP"
			(at 0.064008 -3.993896 180)
			(unlocked yes)
			(layer "F.Fab")
			(hide yes)
			(effects
				(font
					(size 1.016 1.016)
					(thickness 0.1524)
				)
			)
		)
		(property "Device Type" "R402H16"
			(at 0.064008 -5.517896 180)
			(unlocked yes)
			(layer "F.Fab")
			(hide yes)
			(effects
				(font
					(size 1.016 1.016)
					(thickness 0.1524)
				)
			)
		)
		(duplicate_pad_numbers_are_jumpers no)
		(fp_line
			(start 0.508 -0.9398)
			(end -0.508 -0.9398)
			(stroke
				(width 0.1524)
				(type default)
			)
			(layer "F.SilkS")
		)
		(fp_line
			(start -0.508 -0.9398)
			(end -0.508 0.9398)
			(stroke
				(width 0.1524)
				(type default)
			)
			(layer "F.SilkS")
		)
		(fp_rect
			(start -0.508 0.9398)
			(end 0.508 -0.9398)
			(stroke
				(width 0)
				(type default)
			)
			(fill no)
			(layer "F.CrtYd")
		)
		(fp_rect
			(start -0.508 0.9398)
			(end 0.508 -0.9398)
			(stroke
				(width 0)
				(type default)
			)
			(fill no)
			(layer "F.Fab")
		)
		(pad "1" smd custom
			(at 0 -0.4445 180)
			(size 0.1397 0.1397)
			(layers "F.Cu" "F.Mask" "F.Paste")
			(net "P3V3")
			(options
				(clearance outline)
				(anchor circle)
			)
			(primitives
				(gr_poly
					(pts
						(arc
							(start -0.1778 -0.2794)
							(mid -0.249642 -0.249642)
							(end -0.2794 -0.1778)
						)
						(arc
							(start -0.2794 0.1778)
							(mid -0.249642 0.249642)
							(end -0.1778 0.2794)
						)
						(arc
							(start 0.1778 0.2794)
							(mid 0.249642 0.249642)
							(end 0.2794 0.1778)
						)
						(arc
							(start 0.2794 -0.1778)
							(mid 0.249642 -0.249642)
							(end 0.1778 -0.2794)
						)
					)
					(width 0)
					(fill yes)
				)
			)
		)
		(pad "2" smd custom
			(at 0 0.4445 180)
			(size 0.1397 0.1397)
			(layers "F.Cu" "F.Mask" "F.Paste")
			(net "I2C_B_TMP2_A1")
			(options
				(clearance outline)
				(anchor circle)
			)
			(primitives
				(gr_poly
					(pts
						(arc
							(start -0.1778 -0.2794)
							(mid -0.249642 -0.249642)
							(end -0.2794 -0.1778)
						)
						(arc
							(start -0.2794 0.1778)
							(mid -0.249642 0.249642)
							(end -0.1778 0.2794)
						)
						(arc
							(start 0.1778 0.2794)
							(mid 0.249642 0.249642)
							(end 0.2794 0.1778)
						)
						(arc
							(start 0.2794 -0.1778)
							(mid 0.249642 -0.249642)
							(end 0.1778 -0.2794)
						)
					)
					(width 0)
					(fill yes)
				)
			)
		)
	)
	(footprint ""
		(layer "F.Cu")
		(at 24.8158 -191.643 -90)
		(property "Reference" "R146"
			(at 0 0 270)
			(layer "F.SilkS")
			(hide yes)
			(effects
				(font
					(size 1.27 1.27)
				)
			)
		)
		(property "Value" "4K7R2J-2-GP"
			(at 0.064008 -3.993896 270)
			(unlocked yes)
			(layer "F.Fab")
			(hide yes)
			(effects
				(font
					(size 1.016 1.016)
					(thickness 0.1524)
				)
			)
		)
		(property "Device Type" "R402H16"
			(at 0.064008 -5.517896 270)
			(unlocked yes)
			(layer "F.Fab")
			(hide yes)
			(effects
				(font
					(size 1.016 1.016)
					(thickness 0.1524)
				)
			)
		)
		(duplicate_pad_numbers_are_jumpers no)
		(fp_line
			(start -0.508 -0.9398)
			(end -0.508 0.9398)
			(stroke
				(width 0.1524)
				(type default)
			)
			(layer "F.SilkS")
		)
		(fp_line
			(start 0.508 -0.9398)
			(end -0.508 -0.9398)
			(stroke
				(width 0.1524)
				(type default)
			)
			(layer "F.SilkS")
		)
		(fp_rect
			(start -0.508 0.9398)
			(end 0.508 -0.9398)
			(stroke
				(width 0)
				(type default)
			)
			(fill no)
			(layer "F.CrtYd")
		)
		(fp_rect
			(start -0.508 0.9398)
			(end 0.508 -0.9398)
			(stroke
				(width 0)
				(type default)
			)
			(fill no)
			(layer "F.Fab")
		)
		(pad "1" smd custom
			(at 0 -0.4445 270)
			(size 0.1397 0.1397)
			(layers "F.Cu" "F.Mask" "F.Paste")
			(net "P12V")
			(options
				(clearance outline)
				(anchor circle)
			)
			(primitives
				(gr_poly
					(pts
						(arc
							(start -0.1778 -0.2794)
							(mid -0.249642 -0.249642)
							(end -0.2794 -0.1778)
						)
						(arc
							(start -0.2794 0.1778)
							(mid -0.249642 0.249642)
							(end -0.1778 0.2794)
						)
						(arc
							(start 0.1778 0.2794)
							(mid 0.249642 0.249642)
							(end 0.2794 0.1778)
						)
						(arc
							(start 0.2794 -0.1778)
							(mid 0.249642 -0.249642)
							(end 0.1778 -0.2794)
						)
					)
					(width 0)
					(fill yes)
				)
			)
		)
		(pad "2" smd custom
			(at 0 0.4445 270)
			(size 0.1397 0.1397)
			(layers "F.Cu" "F.Mask" "F.Paste")
			(net "SW_SSD8_R")
			(options
				(clearance outline)
				(anchor circle)
			)
			(primitives
				(gr_poly
					(pts
						(arc
							(start -0.1778 -0.2794)
							(mid -0.249642 -0.249642)
							(end -0.2794 -0.1778)
						)
						(arc
							(start -0.2794 0.1778)
							(mid -0.249642 0.249642)
							(end -0.1778 0.2794)
						)
						(arc
							(start 0.1778 0.2794)
							(mid 0.249642 0.249642)
							(end 0.2794 0.1778)
						)
						(arc
							(start 0.2794 -0.1778)
							(mid 0.249642 -0.249642)
							(end 0.1778 -0.2794)
						)
					)
					(width 0)
					(fill yes)
				)
			)
		)
	)
	(footprint ""
		(layer "F.Cu")
		(at 84.455 -427.99 90)
		(property "Reference" "R420"
			(at 0 0 90)
			(layer "F.SilkS")
			(hide yes)
			(effects
				(font
					(size 1.27 1.27)
				)
			)
		)
		(property "Value" "0R2J-2-GP"
			(at 0.064008 -3.993896 90)
			(unlocked yes)
			(layer "F.Fab")
			(hide yes)
			(effects
				(font
					(size 1.016 1.016)
					(thickness 0.1524)
				)
			)
		)
		(property "Device Type" "R402H16"
			(at 0.064008 -5.517896 90)
			(unlocked yes)
			(layer "F.Fab")
			(hide yes)
			(effects
				(font
					(size 1.016 1.016)
					(thickness 0.1524)
				)
			)
		)
		(duplicate_pad_numbers_are_jumpers no)
		(fp_line
			(start 0.508 -0.9398)
			(end -0.508 -0.9398)
			(stroke
				(width 0.1524)
				(type default)
			)
			(layer "F.SilkS")
		)
		(fp_line
			(start -0.508 -0.9398)
			(end -0.508 0.9398)
			(stroke
				(width 0.1524)
				(type default)
			)
			(layer "F.SilkS")
		)
		(fp_rect
			(start -0.508 0.9398)
			(end 0.508 -0.9398)
			(stroke
				(width 0)
				(type default)
			)
			(fill no)
			(layer "F.CrtYd")
		)
		(fp_rect
			(start -0.508 0.9398)
			(end 0.508 -0.9398)
			(stroke
				(width 0)
				(type default)
			)
			(fill no)
			(layer "F.Fab")
		)
		(pad "1" smd custom
			(at 0 -0.4445 90)
			(size 0.1397 0.1397)
			(layers "F.Cu" "F.Mask" "F.Paste")
			(net "BMC_I2C_SDA_BUF_9")
			(options
				(clearance outline)
				(anchor circle)
			)
			(primitives
				(gr_poly
					(pts
						(arc
							(start -0.1778 -0.2794)
							(mid -0.249642 -0.249642)
							(end -0.2794 -0.1778)
						)
						(arc
							(start -0.2794 0.1778)
							(mid -0.249642 0.249642)
							(end -0.1778 0.2794)
						)
						(arc
							(start 0.1778 0.2794)
							(mid 0.249642 0.249642)
							(end 0.2794 0.1778)
						)
						(arc
							(start 0.2794 -0.1778)
							(mid 0.249642 -0.249642)
							(end 0.1778 -0.2794)
						)
					)
					(width 0)
					(fill yes)
				)
			)
		)
		(pad "2" smd custom
			(at 0 0.4445 90)
			(size 0.1397 0.1397)
			(layers "F.Cu" "F.Mask" "F.Paste")
			(net "I2C_SDA_BUF_9_EU1_R")
			(options
				(clearance outline)
				(anchor circle)
			)
			(primitives
				(gr_poly
					(pts
						(arc
							(start -0.1778 -0.2794)
							(mid -0.249642 -0.249642)
							(end -0.2794 -0.1778)
						)
						(arc
							(start -0.2794 0.1778)
							(mid -0.249642 0.249642)
							(end -0.1778 0.2794)
						)
						(arc
							(start 0.1778 0.2794)
							(mid 0.249642 0.249642)
							(end 0.2794 0.1778)
						)
						(arc
							(start 0.2794 -0.1778)
							(mid 0.249642 -0.249642)
							(end 0.1778 -0.2794)
						)
					)
					(width 0)
					(fill yes)
				)
			)
		)
	)
	(footprint ""
		(layer "F.Cu")
		(at 99.949 -97.028 180)
		(property "Reference" "C8875"
			(at 0 0 180)
			(layer "F.SilkS")
			(hide yes)
			(effects
				(font
					(size 1.27 1.27)
				)
			)
		)
		(property "Value" "SCD1U16V2KX-3GP"
			(at 1.1811 -2.7051 180)
			(unlocked yes)
			(layer "F.Fab")
			(hide yes)
			(effects
				(font
					(size 1.016 1.016)
					(thickness 0.1524)
				)
			)
		)
		(property "Device Type" "C402H22"
			(at 1.1811 -4.2291 180)
			(unlocked yes)
			(layer "F.Fab")
			(hide yes)
			(effects
				(font
					(size 1.016 1.016)
					(thickness 0.1524)
				)
			)
		)
		(duplicate_pad_numbers_are_jumpers no)
		(fp_rect
			(start -0.4318 0.9525)
			(end 0.4318 -0.9525)
			(stroke
				(width 0)
				(type default)
			)
			(fill no)
			(layer "F.CrtYd")
		)
		(fp_rect
			(start -0.4318 0.9525)
			(end 0.4318 -0.9525)
			(stroke
				(width 0)
				(type default)
			)
			(fill no)
			(layer "F.Fab")
		)
		(pad "1" smd custom
			(at 0 -0.4445 180)
			(size 0.1524 0.1524)
			(layers "F.Cu" "F.Mask" "F.Paste")
			(net "VDD_IO_4")
			(options
				(clearance outline)
				(anchor circle)
			)
			(primitives
				(gr_poly
					(pts
						(arc
							(start 0.3048 -0.2032)
							(mid 0.275042 -0.275042)
							(end 0.2032 -0.3048)
						)
						(arc
							(start -0.2032 -0.3048)
							(mid -0.275042 -0.275042)
							(end -0.3048 -0.2032)
						)
						(arc
							(start -0.3048 0.2032)
							(mid -0.275042 0.275042)
							(end -0.2032 0.3048)
						)
						(arc
							(start 0.2032 0.3048)
							(mid 0.275042 0.275042)
							(end 0.3048 0.2032)
						)
					)
					(width 0)
					(fill yes)
				)
			)
		)
		(pad "2" smd custom
			(at 0 0.4445 180)
			(size 0.1524 0.1524)
			(layers "F.Cu" "F.Mask" "F.Paste")
			(net "GND")
			(options
				(clearance outline)
				(anchor circle)
			)
			(primitives
				(gr_poly
					(pts
						(arc
							(start 0.3048 -0.2032)
							(mid 0.275042 -0.275042)
							(end 0.2032 -0.3048)
						)
						(arc
							(start -0.2032 -0.3048)
							(mid -0.275042 -0.275042)
							(end -0.3048 -0.2032)
						)
						(arc
							(start -0.3048 0.2032)
							(mid -0.275042 0.275042)
							(end -0.2032 0.3048)
						)
						(arc
							(start 0.2032 0.3048)
							(mid 0.275042 0.275042)
							(end 0.3048 0.2032)
						)
					)
					(width 0)
					(fill yes)
				)
			)
		)
	)
	(footprint ""
		(layer "F.Cu")
		(at 33.1089 -411.6959)
		(property "Reference" "R9846"
			(at 0 0 0)
			(layer "F.SilkS")
			(hide yes)
			(effects
				(font
					(size 1.27 1.27)
				)
			)
		)
		(property "Value" "47KR2J-2-GP"
			(at 0.064008 -3.993896 0)
			(unlocked yes)
			(layer "F.Fab")
			(hide yes)
			(effects
				(font
					(size 1.016 1.016)
					(thickness 0.1524)
				)
			)
		)
		(property "Device Type" "R402H16"
			(at 0.064008 -5.517896 0)
			(unlocked yes)
			(layer "F.Fab")
			(hide yes)
			(effects
				(font
					(size 1.016 1.016)
					(thickness 0.1524)
				)
			)
		)
		(duplicate_pad_numbers_are_jumpers no)
		(fp_line
			(start -0.508 -0.9398)
			(end -0.508 0.9398)
			(stroke
				(width 0.1524)
				(type default)
			)
			(layer "F.SilkS")
		)
		(fp_line
			(start 0.508 -0.9398)
			(end -0.508 -0.9398)
			(stroke
				(width 0.1524)
				(type default)
			)
			(layer "F.SilkS")
		)
		(fp_rect
			(start -0.508 0.9398)
			(end 0.508 -0.9398)
			(stroke
				(width 0)
				(type default)
			)
			(fill no)
			(layer "F.CrtYd")
		)
		(fp_rect
			(start -0.508 0.9398)
			(end 0.508 -0.9398)
			(stroke
				(width 0)
				(type default)
			)
			(fill no)
			(layer "F.Fab")
		)
		(pad "1" smd custom
			(at 0 -0.4445)
			(size 0.1397 0.1397)
			(layers "F.Cu" "F.Mask" "F.Paste")
			(net "P12V")
			(options
				(clearance outline)
				(anchor circle)
			)
			(primitives
				(gr_poly
					(pts
						(arc
							(start -0.1778 -0.2794)
							(mid -0.249642 -0.249642)
							(end -0.2794 -0.1778)
						)
						(arc
							(start -0.2794 0.1778)
							(mid -0.249642 0.249642)
							(end -0.1778 0.2794)
						)
						(arc
							(start 0.1778 0.2794)
							(mid 0.249642 0.249642)
							(end 0.2794 0.1778)
						)
						(arc
							(start 0.2794 -0.1778)
							(mid 0.249642 -0.249642)
							(end 0.1778 -0.2794)
						)
					)
					(width 0)
					(fill yes)
				)
			)
		)
		(pad "2" smd custom
			(at 0 0.4445)
			(size 0.1397 0.1397)
			(layers "F.Cu" "F.Mask" "F.Paste")
			(net "P12V_MOST10_GATE")
			(options
				(clearance outline)
				(anchor circle)
			)
			(primitives
				(gr_poly
					(pts
						(arc
							(start -0.1778 -0.2794)
							(mid -0.249642 -0.249642)
							(end -0.2794 -0.1778)
						)
						(arc
							(start -0.2794 0.1778)
							(mid -0.249642 0.249642)
							(end -0.1778 0.2794)
						)
						(arc
							(start 0.1778 0.2794)
							(mid 0.249642 0.249642)
							(end 0.2794 0.1778)
						)
						(arc
							(start 0.2794 -0.1778)
							(mid 0.249642 -0.249642)
							(end 0.1778 -0.2794)
						)
					)
					(width 0)
					(fill yes)
				)
			)
		)
	)
	(footprint ""
		(layer "F.Cu")
		(at 13.937488 -425.843192 180)
		(property "Reference" "C9539"
			(at 0 0 180)
			(layer "F.SilkS")
			(hide yes)
			(effects
				(font
					(size 1.27 1.27)
				)
			)
		)
		(property "Value" "SCD01U50V2KX-1GP"
			(at 1.1811 -2.7051 180)
			(unlocked yes)
			(layer "F.Fab")
			(hide yes)
			(effects
				(font
					(size 1.016 1.016)
					(thickness 0.1524)
				)
			)
		)
		(property "Device Type" "C402H22"
			(at 1.1811 -4.2291 180)
			(unlocked yes)
			(layer "F.Fab")
			(hide yes)
			(effects
				(font
					(size 1.016 1.016)
					(thickness 0.1524)
				)
			)
		)
		(duplicate_pad_numbers_are_jumpers no)
		(fp_rect
			(start -0.4318 0.9525)
			(end 0.4318 -0.9525)
			(stroke
				(width 0)
				(type default)
			)
			(fill no)
			(layer "F.CrtYd")
		)
		(fp_rect
			(start -0.4318 0.9525)
			(end 0.4318 -0.9525)
			(stroke
				(width 0)
				(type default)
			)
			(fill no)
			(layer "F.Fab")
		)
		(pad "1" smd custom
			(at 0 -0.4445 180)
			(size 0.1524 0.1524)
			(layers "F.Cu" "F.Mask" "F.Paste")
			(net "PE_100M_CLK3_N")
			(options
				(clearance outline)
				(anchor circle)
			)
			(primitives
				(gr_poly
					(pts
						(arc
							(start 0.3048 -0.2032)
							(mid 0.275042 -0.275042)
							(end 0.2032 -0.3048)
						)
						(arc
							(start -0.2032 -0.3048)
							(mid -0.275042 -0.275042)
							(end -0.3048 -0.2032)
						)
						(arc
							(start -0.3048 0.2032)
							(mid -0.275042 0.275042)
							(end -0.2032 0.3048)
						)
						(arc
							(start 0.2032 0.3048)
							(mid 0.275042 0.275042)
							(end 0.3048 0.2032)
						)
					)
					(width 0)
					(fill yes)
				)
			)
		)
		(pad "2" smd custom
			(at 0 0.4445 180)
			(size 0.1524 0.1524)
			(layers "F.Cu" "F.Mask" "F.Paste")
			(net "PE_100M_CLK3_C_N")
			(options
				(clearance outline)
				(anchor circle)
			)
			(primitives
				(gr_poly
					(pts
						(arc
							(start 0.3048 -0.2032)
							(mid 0.275042 -0.275042)
							(end 0.2032 -0.3048)
						)
						(arc
							(start -0.2032 -0.3048)
							(mid -0.275042 -0.275042)
							(end -0.3048 -0.2032)
						)
						(arc
							(start -0.3048 0.2032)
							(mid -0.275042 0.275042)
							(end -0.2032 0.3048)
						)
						(arc
							(start 0.2032 0.3048)
							(mid 0.275042 0.275042)
							(end 0.3048 0.2032)
						)
					)
					(width 0)
					(fill yes)
				)
			)
		)
	)
	(footprint ""
		(layer "F.Cu")
		(at 8.7122 -464.1342 90)
		(property "Reference" "PC1164"
			(at 0 0 90)
			(layer "F.SilkS")
			(hide yes)
			(effects
				(font
					(size 1.27 1.27)
				)
			)
		)
		(property "Value" "SCD1U50V3KX-GP"
			(at 0 -2.8194 90)
			(unlocked yes)
			(layer "F.Fab")
			(hide yes)
			(effects
				(font
					(size 1.016 1.016)
					(thickness 0.1524)
				)
			)
		)
		(property "Device Type" "C603H36"
			(at 0 -4.3434 90)
			(unlocked yes)
			(layer "F.Fab")
			(hide yes)
			(effects
				(font
					(size 1.016 1.016)
					(thickness 0.1524)
				)
			)
		)
		(duplicate_pad_numbers_are_jumpers no)
		(fp_line
			(start 0.508 0)
			(end -0.508 0)
			(stroke
				(width 0.2032)
				(type default)
			)
			(layer "F.SilkS")
		)
		(fp_rect
			(start -0.5842 1.3335)
			(end 0.5842 -1.3335)
			(stroke
				(width 0)
				(type default)
			)
			(fill no)
			(layer "F.CrtYd")
		)
		(fp_rect
			(start -0.5842 1.3335)
			(end 0.5842 -1.3335)
			(stroke
				(width 0)
				(type default)
			)
			(fill no)
			(layer "F.Fab")
		)
		(pad "1" smd custom
			(at 0 -0.762 90)
			(size 0.2159 0.2159)
			(layers "F.Cu" "F.Mask" "F.Paste")
			(net "P12V")
			(options
				(clearance outline)
				(anchor circle)
			)
			(primitives
				(gr_poly
					(pts
						(arc
							(start -0.3302 -0.4318)
							(mid -0.402042 -0.402042)
							(end -0.4318 -0.3302)
						)
						(arc
							(start -0.4318 0.3302)
							(mid -0.402042 0.402042)
							(end -0.3302 0.4318)
						)
						(arc
							(start 0.3302 0.4318)
							(mid 0.402042 0.402042)
							(end 0.4318 0.3302)
						)
						(arc
							(start 0.4318 -0.3302)
							(mid 0.402042 -0.402042)
							(end 0.3302 -0.4318)
						)
					)
					(width 0)
					(fill yes)
				)
			)
		)
		(pad "2" smd custom
			(at 0 0.762 90)
			(size 0.2159 0.2159)
			(layers "F.Cu" "F.Mask" "F.Paste")
			(net "GND")
			(options
				(clearance outline)
				(anchor circle)
			)
			(primitives
				(gr_poly
					(pts
						(arc
							(start -0.3302 -0.4318)
							(mid -0.402042 -0.402042)
							(end -0.4318 -0.3302)
						)
						(arc
							(start -0.4318 0.3302)
							(mid -0.402042 0.402042)
							(end -0.3302 0.4318)
						)
						(arc
							(start 0.3302 0.4318)
							(mid 0.402042 0.402042)
							(end 0.4318 0.3302)
						)
						(arc
							(start 0.4318 -0.3302)
							(mid 0.402042 -0.402042)
							(end 0.3302 -0.4318)
						)
					)
					(width 0)
					(fill yes)
				)
			)
		)
	)
	(footprint ""
		(layer "F.Cu")
		(at 24.892 -365.887 90)
		(property "Reference" "Q84"
			(at 0 0 90)
			(layer "F.SilkS")
			(hide yes)
			(effects
				(font
					(size 1.27 1.27)
				)
			)
		)
		(property "Value" "2N7002A-7-GP"
			(at 0.127 -8.9662 90)
			(unlocked yes)
			(layer "F.Fab")
			(hide yes)
			(effects
				(font
					(size 1.016 1.016)
					(thickness 0.1524)
				)
			)
		)
		(property "Device Type" "SOT23DGS2D4H48"
			(at 0.127 -10.4902 90)
			(unlocked yes)
			(layer "F.Fab")
			(hide yes)
			(effects
				(font
					(size 1.016 1.016)
					(thickness 0.1524)
				)
			)
		)
		(duplicate_pad_numbers_are_jumpers no)
		(fp_line
			(start 1.651 -1.778)
			(end -1.651 -1.778)
			(stroke
				(width 0.1524)
				(type default)
			)
			(layer "F.SilkS")
		)
		(fp_line
			(start -1.651 -1.778)
			(end -1.651 1.778)
			(stroke
				(width 0.1524)
				(type default)
			)
			(layer "F.SilkS")
		)
		(fp_line
			(start 1.651 1.778)
			(end 1.651 -1.778)
			(stroke
				(width 0.1524)
				(type default)
			)
			(layer "F.SilkS")
		)
		(fp_line
			(start -1.651 1.778)
			(end 1.651 1.778)
			(stroke
				(width 0.1524)
				(type default)
			)
			(layer "F.SilkS")
		)
		(fp_poly
			(pts
				(xy -1.778 1.8796) (xy -1.778 -1.8796) (xy 1.778 -1.8796) (xy 1.778 1.8796)
			)
			(stroke
				(width 0)
				(type default)
			)
			(fill no)
			(layer "F.CrtYd")
		)
		(fp_poly
			(pts
				(xy -1.778 1.8796) (xy -1.778 -1.8796) (xy 1.778 -1.8796) (xy 1.778 1.8796)
			)
			(stroke
				(width 0)
				(type default)
			)
			(fill no)
			(layer "F.Fab")
		)
		(pad "D" smd custom
			(at 0 -0.9525 90)
			(size 0.1905 0.1905)
			(layers "F.Cu" "F.Mask" "F.Paste")
			(net "SSD11_CLK0_OE_MOS_N")
			(options
				(clearance outline)
				(anchor circle)
			)
			(primitives
				(gr_poly
					(pts
						(arc
							(start -0.1778 0.5715)
							(mid -0.321484 0.511984)
							(end -0.381 0.3683)
						)
						(arc
							(start -0.381 -0.3683)
							(mid -0.321484 -0.511984)
							(end -0.1778 -0.5715)
						)
						(arc
							(start 0.1778 -0.5715)
							(mid 0.321484 -0.511984)
							(end 0.381 -0.3683)
						)
						(arc
							(start 0.381 0.3683)
							(mid 0.321484 0.511984)
							(end 0.1778 0.5715)
						)
					)
					(width 0)
					(fill yes)
				)
			)
		)
		(pad "G" smd custom
			(at -0.98425 0.9525 90)
			(size 0.1905 0.1905)
			(layers "F.Cu" "F.Mask" "F.Paste")
			(net "SSD11_CLK0_OE_R_N")
			(options
				(clearance outline)
				(anchor circle)
			)
			(primitives
				(gr_poly
					(pts
						(arc
							(start -0.1778 0.5715)
							(mid -0.321484 0.511984)
							(end -0.381 0.3683)
						)
						(arc
							(start -0.381 -0.3683)
							(mid -0.321484 -0.511984)
							(end -0.1778 -0.5715)
						)
						(arc
							(start 0.1778 -0.5715)
							(mid 0.321484 -0.511984)
							(end 0.381 -0.3683)
						)
						(arc
							(start 0.381 0.3683)
							(mid 0.321484 0.511984)
							(end 0.1778 0.5715)
						)
					)
					(width 0)
					(fill yes)
				)
			)
		)
		(pad "S" smd custom
			(at 0.98425 0.9525 90)
			(size 0.1905 0.1905)
			(layers "F.Cu" "F.Mask" "F.Paste")
			(net "GND")
			(options
				(clearance outline)
				(anchor circle)
			)
			(primitives
				(gr_poly
					(pts
						(arc
							(start -0.1778 0.5715)
							(mid -0.321484 0.511984)
							(end -0.381 0.3683)
						)
						(arc
							(start -0.381 -0.3683)
							(mid -0.321484 -0.511984)
							(end -0.1778 -0.5715)
						)
						(arc
							(start 0.1778 -0.5715)
							(mid 0.321484 -0.511984)
							(end 0.381 -0.3683)
						)
						(arc
							(start 0.381 0.3683)
							(mid 0.321484 0.511984)
							(end 0.1778 0.5715)
						)
					)
					(width 0)
					(fill yes)
				)
			)
		)
	)
	(footprint ""
		(layer "F.Cu")
		(at 18.50009 -155.90012)
		(property "Reference" "LED13"
			(at 0 0 0)
			(layer "F.SilkS")
			(hide yes)
			(effects
				(font
					(size 1.27 1.27)
				)
			)
		)
		(property "Value" "LED-RB-4-GP"
			(at 5.88899 1.80848 0)
			(unlocked yes)
			(layer "F.Fab")
			(hide yes)
			(effects
				(font
					(size 1.016 1.016)
					(thickness 0.1524)
				)
			)
		)
		(property "Device Type" "LED1613-4PH20"
			(at 5.88899 0.28448 0)
			(unlocked yes)
			(layer "F.Fab")
			(hide yes)
			(effects
				(font
					(size 1.016 1.016)
					(thickness 0.1524)
				)
			)
		)
		(duplicate_pad_numbers_are_jumpers no)
		(fp_line
			(start -1.4478 -0.9652)
			(end 1.4478 -0.9652)
			(stroke
				(width 0.1524)
				(type default)
			)
			(layer "F.SilkS")
		)
		(fp_line
			(start -1.4478 0.9652)
			(end -1.4478 -0.9652)
			(stroke
				(width 0.1524)
				(type default)
			)
			(layer "F.SilkS")
		)
		(fp_line
			(start -1.4478 0.9652)
			(end -1.4478 -0.9652)
			(stroke
				(width 0.508)
				(type default)
			)
			(layer "F.SilkS")
		)
		(fp_line
			(start 1.4478 -0.9652)
			(end 1.4478 0.9652)
			(stroke
				(width 0.1524)
				(type default)
			)
			(layer "F.SilkS")
		)
		(fp_line
			(start 1.4478 0.9652)
			(end -1.4478 0.9652)
			(stroke
				(width 0.1524)
				(type default)
			)
			(layer "F.SilkS")
		)
		(fp_rect
			(start -0.8001 0.6477)
			(end 0.8001 -0.6477)
			(stroke
				(width 0)
				(type default)
			)
			(fill no)
			(layer "F.CrtYd")
		)
		(fp_poly
			(pts
				(xy -1.7018 1.2192) (xy -1.7018 -0.06223) (xy -0.8001 -0.06223) (xy -0.8001 0.6477) (xy 0.8001 0.6477)
				(xy 0.8001 -0.6477) (xy -0.8001 -0.6477) (xy -0.8001 -0.0635) (xy -1.7018 -0.0635) (xy -1.7018 -1.2192)
				(xy 1.7018 -1.2192) (xy 1.7018 1.2192)
			)
			(stroke
				(width 0)
				(type default)
			)
			(fill no)
			(layer "F.CrtYd")
		)
		(fp_rect
			(start -1.7018 1.2192)
			(end 1.7018 -1.2192)
			(stroke
				(width 0)
				(type default)
			)
			(fill no)
			(layer "F.Fab")
		)
		(pad "1" smd rect
			(at -0.73025 0.4064)
			(size 0.9144 0.6096)
			(layers "F.Cu" "F.Mask" "F.Paste")
			(net "SSD_ACT_DR13_MOS_N")
		)
		(pad "2" smd rect
			(at -0.73025 -0.4064)
			(size 0.9144 0.6096)
			(layers "F.Cu" "F.Mask" "F.Paste")
			(net "ATTN_LED_DR13_MOS_N")
		)
		(pad "3" smd rect
			(at 0.73025 -0.4064)
			(size 0.9144 0.6096)
			(layers "F.Cu" "F.Mask" "F.Paste")
			(net "DRV_ATTN_13")
		)
		(pad "4" smd rect
			(at 0.73025 0.4064)
			(size 0.9144 0.6096)
			(layers "F.Cu" "F.Mask" "F.Paste")
			(net "DRV_ACT_13")
		)
	)
	(footprint ""
		(layer "F.Cu")
		(at 84.455 -298.323 -90)
		(property "Reference" "R9037"
			(at 0 0 270)
			(layer "F.SilkS")
			(hide yes)
			(effects
				(font
					(size 1.27 1.27)
				)
			)
		)
		(property "Value" "4K7R2F-GP"
			(at 0.064008 -3.993896 270)
			(unlocked yes)
			(layer "F.Fab")
			(hide yes)
			(effects
				(font
					(size 1.016 1.016)
					(thickness 0.1524)
				)
			)
		)
		(property "Device Type" "R402H16"
			(at 0.064008 -5.517896 270)
			(unlocked yes)
			(layer "F.Fab")
			(hide yes)
			(effects
				(font
					(size 1.016 1.016)
					(thickness 0.1524)
				)
			)
		)
		(duplicate_pad_numbers_are_jumpers no)
		(fp_line
			(start -0.508 -0.9398)
			(end -0.508 0.9398)
			(stroke
				(width 0.1524)
				(type default)
			)
			(layer "F.SilkS")
		)
		(fp_line
			(start 0.508 -0.9398)
			(end -0.508 -0.9398)
			(stroke
				(width 0.1524)
				(type default)
			)
			(layer "F.SilkS")
		)
		(fp_rect
			(start -0.508 0.9398)
			(end 0.508 -0.9398)
			(stroke
				(width 0)
				(type default)
			)
			(fill no)
			(layer "F.CrtYd")
		)
		(fp_rect
			(start -0.508 0.9398)
			(end 0.508 -0.9398)
			(stroke
				(width 0)
				(type default)
			)
			(fill no)
			(layer "F.Fab")
		)
		(pad "1" smd custom
			(at 0 -0.4445 270)
			(size 0.1397 0.1397)
			(layers "F.Cu" "F.Mask" "F.Paste")
			(net "CLK_BUF_EU2_SMB_A1_TRI")
			(options
				(clearance outline)
				(anchor circle)
			)
			(primitives
				(gr_poly
					(pts
						(arc
							(start -0.1778 -0.2794)
							(mid -0.249642 -0.249642)
							(end -0.2794 -0.1778)
						)
						(arc
							(start -0.2794 0.1778)
							(mid -0.249642 0.249642)
							(end -0.1778 0.2794)
						)
						(arc
							(start 0.1778 0.2794)
							(mid 0.249642 0.249642)
							(end 0.2794 0.1778)
						)
						(arc
							(start 0.2794 -0.1778)
							(mid 0.249642 -0.249642)
							(end 0.1778 -0.2794)
						)
					)
					(width 0)
					(fill yes)
				)
			)
		)
		(pad "2" smd custom
			(at 0 0.4445 270)
			(size 0.1397 0.1397)
			(layers "F.Cu" "F.Mask" "F.Paste")
			(net "GND")
			(options
				(clearance outline)
				(anchor circle)
			)
			(primitives
				(gr_poly
					(pts
						(arc
							(start -0.1778 -0.2794)
							(mid -0.249642 -0.249642)
							(end -0.2794 -0.1778)
						)
						(arc
							(start -0.2794 0.1778)
							(mid -0.249642 0.249642)
							(end -0.1778 0.2794)
						)
						(arc
							(start 0.1778 0.2794)
							(mid 0.249642 0.249642)
							(end 0.2794 0.1778)
						)
						(arc
							(start 0.2794 -0.1778)
							(mid 0.249642 -0.249642)
							(end 0.1778 -0.2794)
						)
					)
					(width 0)
					(fill yes)
				)
			)
		)
	)
	(footprint ""
		(layer "F.Cu")
		(at 82.931 -216.154 90)
		(property "Reference" "SR951"
			(at 0 0 90)
			(layer "F.SilkS")
			(hide yes)
			(effects
				(font
					(size 1.27 1.27)
				)
			)
		)
		(property "Value" "4K7R2F-GP"
			(at 0.064008 -3.993896 90)
			(unlocked yes)
			(layer "F.Fab")
			(hide yes)
			(effects
				(font
					(size 1.016 1.016)
					(thickness 0.1524)
				)
			)
		)
		(property "Device Type" "R402H16"
			(at 0.064008 -5.517896 90)
			(unlocked yes)
			(layer "F.Fab")
			(hide yes)
			(effects
				(font
					(size 1.016 1.016)
					(thickness 0.1524)
				)
			)
		)
		(duplicate_pad_numbers_are_jumpers no)
		(fp_line
			(start 0.508 -0.9398)
			(end -0.508 -0.9398)
			(stroke
				(width 0.1524)
				(type default)
			)
			(layer "F.SilkS")
		)
		(fp_line
			(start -0.508 -0.9398)
			(end -0.508 0.9398)
			(stroke
				(width 0.1524)
				(type default)
			)
			(layer "F.SilkS")
		)
		(fp_rect
			(start -0.508 0.9398)
			(end 0.508 -0.9398)
			(stroke
				(width 0)
				(type default)
			)
			(fill no)
			(layer "F.CrtYd")
		)
		(fp_rect
			(start -0.508 0.9398)
			(end 0.508 -0.9398)
			(stroke
				(width 0)
				(type default)
			)
			(fill no)
			(layer "F.Fab")
		)
		(pad "1" smd custom
			(at 0 -0.4445 90)
			(size 0.1397 0.1397)
			(layers "F.Cu" "F.Mask" "F.Paste")
			(net "VDD_DIFF_3")
			(options
				(clearance outline)
				(anchor circle)
			)
			(primitives
				(gr_poly
					(pts
						(arc
							(start -0.1778 -0.2794)
							(mid -0.249642 -0.249642)
							(end -0.2794 -0.1778)
						)
						(arc
							(start -0.2794 0.1778)
							(mid -0.249642 0.249642)
							(end -0.1778 0.2794)
						)
						(arc
							(start 0.1778 0.2794)
							(mid 0.249642 0.249642)
							(end 0.2794 0.1778)
						)
						(arc
							(start 0.2794 -0.1778)
							(mid 0.249642 -0.249642)
							(end 0.1778 -0.2794)
						)
					)
					(width 0)
					(fill yes)
				)
			)
		)
		(pad "2" smd custom
			(at 0 0.4445 90)
			(size 0.1397 0.1397)
			(layers "F.Cu" "F.Mask" "F.Paste")
			(net "CLK_BUF_EU3_100M_133M#")
			(options
				(clearance outline)
				(anchor circle)
			)
			(primitives
				(gr_poly
					(pts
						(arc
							(start -0.1778 -0.2794)
							(mid -0.249642 -0.249642)
							(end -0.2794 -0.1778)
						)
						(arc
							(start -0.2794 0.1778)
							(mid -0.249642 0.249642)
							(end -0.1778 0.2794)
						)
						(arc
							(start 0.1778 0.2794)
							(mid 0.249642 0.249642)
							(end 0.2794 0.1778)
						)
						(arc
							(start 0.2794 -0.1778)
							(mid 0.249642 -0.249642)
							(end 0.1778 -0.2794)
						)
					)
					(width 0)
					(fill yes)
				)
			)
		)
	)
	(footprint ""
		(layer "F.Cu")
		(at 83.4644 -431.3047 180)
		(property "Reference" "R9959"
			(at 0 0 180)
			(layer "F.SilkS")
			(hide yes)
			(effects
				(font
					(size 1.27 1.27)
				)
			)
		)
		(property "Value" "100R1F-GP"
			(at -3.3274 -1.3335 180)
			(unlocked yes)
			(layer "F.Fab")
			(hide yes)
			(effects
				(font
					(size 1.016 1.016)
					(thickness 0.1524)
				)
			)
		)
		(property "Device Type" "R0201H12"
			(at -3.3274 -2.8575 180)
			(unlocked yes)
			(layer "F.Fab")
			(hide yes)
			(effects
				(font
					(size 1.016 1.016)
					(thickness 0.1524)
				)
			)
		)
		(duplicate_pad_numbers_are_jumpers no)
		(fp_rect
			(start -0.2794 0.6477)
			(end 0.2794 -0.6477)
			(stroke
				(width 0)
				(type default)
			)
			(fill no)
			(layer "F.CrtYd")
		)
		(fp_rect
			(start -0.2794 0.6477)
			(end 0.2794 -0.6477)
			(stroke
				(width 0)
				(type default)
			)
			(fill no)
			(layer "F.Fab")
		)
		(pad "1" smd custom
			(at 0 -0.2794 180)
			(size 0.0762 0.0762)
			(layers "F.Cu" "F.Mask" "F.Paste")
			(net "PE_100M_CLK4_N")
			(options
				(clearance outline)
				(anchor circle)
			)
			(primitives
				(gr_poly
					(pts
						(arc
							(start 0.1524 -0.127)
							(mid 0.137521 -0.162921)
							(end 0.1016 -0.1778)
						)
						(arc
							(start -0.1016 -0.1778)
							(mid -0.137521 -0.162921)
							(end -0.1524 -0.127)
						)
						(arc
							(start -0.1524 0.127)
							(mid -0.137521 0.162921)
							(end -0.1016 0.1778)
						)
						(arc
							(start 0.1016 0.1778)
							(mid 0.137521 0.162921)
							(end 0.1524 0.127)
						)
					)
					(width 0)
					(fill yes)
				)
			)
		)
		(pad "2" smd custom
			(at 0 0.2794 180)
			(size 0.0762 0.0762)
			(layers "F.Cu" "F.Mask" "F.Paste")
			(net "PE_100M_CLK4_P")
			(options
				(clearance outline)
				(anchor circle)
			)
			(primitives
				(gr_poly
					(pts
						(arc
							(start 0.1524 -0.127)
							(mid 0.137521 -0.162921)
							(end 0.1016 -0.1778)
						)
						(arc
							(start -0.1016 -0.1778)
							(mid -0.137521 -0.162921)
							(end -0.1524 -0.127)
						)
						(arc
							(start -0.1524 0.127)
							(mid -0.137521 0.162921)
							(end -0.1016 0.1778)
						)
						(arc
							(start 0.1016 0.1778)
							(mid 0.137521 0.162921)
							(end 0.1524 0.127)
						)
					)
					(width 0)
					(fill yes)
				)
			)
		)
	)
	(footprint ""
		(layer "F.Cu")
		(at 94.488 -93.853)
		(property "Reference" "C8876"
			(at 0 0 0)
			(layer "F.SilkS")
			(hide yes)
			(effects
				(font
					(size 1.27 1.27)
				)
			)
		)
		(property "Value" "SCD1U16V2KX-3GP"
			(at 1.1811 -2.7051 0)
			(unlocked yes)
			(layer "F.Fab")
			(hide yes)
			(effects
				(font
					(size 1.016 1.016)
					(thickness 0.1524)
				)
			)
		)
		(property "Device Type" "C402H22"
			(at 1.1811 -4.2291 0)
			(unlocked yes)
			(layer "F.Fab")
			(hide yes)
			(effects
				(font
					(size 1.016 1.016)
					(thickness 0.1524)
				)
			)
		)
		(duplicate_pad_numbers_are_jumpers no)
		(fp_rect
			(start -0.4318 0.9525)
			(end 0.4318 -0.9525)
			(stroke
				(width 0)
				(type default)
			)
			(fill no)
			(layer "F.CrtYd")
		)
		(fp_rect
			(start -0.4318 0.9525)
			(end 0.4318 -0.9525)
			(stroke
				(width 0)
				(type default)
			)
			(fill no)
			(layer "F.Fab")
		)
		(pad "1" smd custom
			(at 0 -0.4445)
			(size 0.1524 0.1524)
			(layers "F.Cu" "F.Mask" "F.Paste")
			(net "VDD_IO_4")
			(options
				(clearance outline)
				(anchor circle)
			)
			(primitives
				(gr_poly
					(pts
						(arc
							(start 0.3048 -0.2032)
							(mid 0.275042 -0.275042)
							(end 0.2032 -0.3048)
						)
						(arc
							(start -0.2032 -0.3048)
							(mid -0.275042 -0.275042)
							(end -0.3048 -0.2032)
						)
						(arc
							(start -0.3048 0.2032)
							(mid -0.275042 0.275042)
							(end -0.2032 0.3048)
						)
						(arc
							(start 0.2032 0.3048)
							(mid 0.275042 0.275042)
							(end 0.3048 0.2032)
						)
					)
					(width 0)
					(fill yes)
				)
			)
		)
		(pad "2" smd custom
			(at 0 0.4445)
			(size 0.1524 0.1524)
			(layers "F.Cu" "F.Mask" "F.Paste")
			(net "GND")
			(options
				(clearance outline)
				(anchor circle)
			)
			(primitives
				(gr_poly
					(pts
						(arc
							(start 0.3048 -0.2032)
							(mid 0.275042 -0.275042)
							(end 0.2032 -0.3048)
						)
						(arc
							(start -0.2032 -0.3048)
							(mid -0.275042 -0.275042)
							(end -0.3048 -0.2032)
						)
						(arc
							(start -0.3048 0.2032)
							(mid -0.275042 0.275042)
							(end -0.2032 0.3048)
						)
						(arc
							(start 0.2032 0.3048)
							(mid 0.275042 0.275042)
							(end 0.3048 0.2032)
						)
					)
					(width 0)
					(fill yes)
				)
			)
		)
	)
	(footprint ""
		(layer "F.Cu")
		(at 93.599 -109.474 180)
		(property "Reference" "C9433"
			(at 0 0 180)
			(layer "F.SilkS")
			(hide yes)
			(effects
				(font
					(size 1.27 1.27)
				)
			)
		)
		(property "Value" "SCD1U16V2KX-3GP"
			(at 1.1811 -2.7051 180)
			(unlocked yes)
			(layer "F.Fab")
			(hide yes)
			(effects
				(font
					(size 1.016 1.016)
					(thickness 0.1524)
				)
			)
		)
		(property "Device Type" "C402H22"
			(at 1.1811 -4.2291 180)
			(unlocked yes)
			(layer "F.Fab")
			(hide yes)
			(effects
				(font
					(size 1.016 1.016)
					(thickness 0.1524)
				)
			)
		)
		(duplicate_pad_numbers_are_jumpers no)
		(fp_rect
			(start -0.4318 0.9525)
			(end 0.4318 -0.9525)
			(stroke
				(width 0)
				(type default)
			)
			(fill no)
			(layer "F.CrtYd")
		)
		(fp_rect
			(start -0.4318 0.9525)
			(end 0.4318 -0.9525)
			(stroke
				(width 0)
				(type default)
			)
			(fill no)
			(layer "F.Fab")
		)
		(pad "1" smd custom
			(at 0 -0.4445 180)
			(size 0.1524 0.1524)
			(layers "F.Cu" "F.Mask" "F.Paste")
			(net "VDD_DIFF_4")
			(options
				(clearance outline)
				(anchor circle)
			)
			(primitives
				(gr_poly
					(pts
						(arc
							(start 0.3048 -0.2032)
							(mid 0.275042 -0.275042)
							(end 0.2032 -0.3048)
						)
						(arc
							(start -0.2032 -0.3048)
							(mid -0.275042 -0.275042)
							(end -0.3048 -0.2032)
						)
						(arc
							(start -0.3048 0.2032)
							(mid -0.275042 0.275042)
							(end -0.2032 0.3048)
						)
						(arc
							(start 0.2032 0.3048)
							(mid 0.275042 0.275042)
							(end 0.3048 0.2032)
						)
					)
					(width 0)
					(fill yes)
				)
			)
		)
		(pad "2" smd custom
			(at 0 0.4445 180)
			(size 0.1524 0.1524)
			(layers "F.Cu" "F.Mask" "F.Paste")
			(net "GND")
			(options
				(clearance outline)
				(anchor circle)
			)
			(primitives
				(gr_poly
					(pts
						(arc
							(start 0.3048 -0.2032)
							(mid 0.275042 -0.275042)
							(end 0.2032 -0.3048)
						)
						(arc
							(start -0.2032 -0.3048)
							(mid -0.275042 -0.275042)
							(end -0.3048 -0.2032)
						)
						(arc
							(start -0.3048 0.2032)
							(mid -0.275042 0.275042)
							(end -0.2032 0.3048)
						)
						(arc
							(start 0.2032 0.3048)
							(mid 0.275042 0.275042)
							(end 0.3048 0.2032)
						)
					)
					(width 0)
					(fill yes)
				)
			)
		)
	)
	(footprint ""
		(layer "F.Cu")
		(at 21.9964 -474.3196 90)
		(property "Reference" "R9847"
			(at 0 0 90)
			(layer "F.SilkS")
			(hide yes)
			(effects
				(font
					(size 1.27 1.27)
				)
			)
		)
		(property "Value" "0R2J-2-GP"
			(at 0.064008 -3.993896 90)
			(unlocked yes)
			(layer "F.Fab")
			(hide yes)
			(effects
				(font
					(size 1.016 1.016)
					(thickness 0.1524)
				)
			)
		)
		(property "Device Type" "R402H16"
			(at 0.064008 -5.517896 90)
			(unlocked yes)
			(layer "F.Fab")
			(hide yes)
			(effects
				(font
					(size 1.016 1.016)
					(thickness 0.1524)
				)
			)
		)
		(duplicate_pad_numbers_are_jumpers no)
		(fp_line
			(start 0.508 -0.9398)
			(end -0.508 -0.9398)
			(stroke
				(width 0.1524)
				(type default)
			)
			(layer "F.SilkS")
		)
		(fp_line
			(start -0.508 -0.9398)
			(end -0.508 0.9398)
			(stroke
				(width 0.1524)
				(type default)
			)
			(layer "F.SilkS")
		)
		(fp_rect
			(start -0.508 0.9398)
			(end 0.508 -0.9398)
			(stroke
				(width 0)
				(type default)
			)
			(fill no)
			(layer "F.CrtYd")
		)
		(fp_rect
			(start -0.508 0.9398)
			(end 0.508 -0.9398)
			(stroke
				(width 0)
				(type default)
			)
			(fill no)
			(layer "F.Fab")
		)
		(pad "1" smd custom
			(at 0 -0.4445 90)
			(size 0.1397 0.1397)
			(layers "F.Cu" "F.Mask" "F.Paste")
			(net "ATTN_LED_DR10_AND")
			(options
				(clearance outline)
				(anchor circle)
			)
			(primitives
				(gr_poly
					(pts
						(arc
							(start -0.1778 -0.2794)
							(mid -0.249642 -0.249642)
							(end -0.2794 -0.1778)
						)
						(arc
							(start -0.2794 0.1778)
							(mid -0.249642 0.249642)
							(end -0.1778 0.2794)
						)
						(arc
							(start 0.1778 0.2794)
							(mid 0.249642 0.249642)
							(end 0.2794 0.1778)
						)
						(arc
							(start 0.2794 -0.1778)
							(mid 0.249642 -0.249642)
							(end 0.1778 -0.2794)
						)
					)
					(width 0)
					(fill yes)
				)
			)
		)
		(pad "2" smd custom
			(at 0 0.4445 90)
			(size 0.1397 0.1397)
			(layers "F.Cu" "F.Mask" "F.Paste")
			(net "ATTN_LED_DR10_AND_R")
			(options
				(clearance outline)
				(anchor circle)
			)
			(primitives
				(gr_poly
					(pts
						(arc
							(start -0.1778 -0.2794)
							(mid -0.249642 -0.249642)
							(end -0.2794 -0.1778)
						)
						(arc
							(start -0.2794 0.1778)
							(mid -0.249642 0.249642)
							(end -0.1778 0.2794)
						)
						(arc
							(start 0.1778 0.2794)
							(mid 0.249642 0.249642)
							(end 0.2794 0.1778)
						)
						(arc
							(start 0.2794 -0.1778)
							(mid 0.249642 -0.249642)
							(end 0.1778 -0.2794)
						)
					)
					(width 0)
					(fill yes)
				)
			)
		)
	)
	(footprint ""
		(layer "F.Cu")
		(at 26.7716 -8.4074 -90)
		(property "Reference" "R9249"
			(at 0 0 270)
			(layer "F.SilkS")
			(hide yes)
			(effects
				(font
					(size 1.27 1.27)
				)
			)
		)
		(property "Value" "2R2010F-GP"
			(at 0.0762 -4.5466 270)
			(unlocked yes)
			(layer "F.Fab")
			(hide yes)
			(effects
				(font
					(size 1.016 1.016)
					(thickness 0.1524)
				)
			)
		)
		(property "Device Type" "R2010H26"
			(at 0.0762 -6.1468 270)
			(unlocked yes)
			(layer "F.Fab")
			(hide yes)
			(effects
				(font
					(size 1.016 1.016)
					(thickness 0.1524)
				)
			)
		)
		(duplicate_pad_numbers_are_jumpers no)
		(fp_line
			(start -3.302 1.651)
			(end 3.302 1.651)
			(stroke
				(width 0.1524)
				(type default)
			)
			(layer "F.SilkS")
		)
		(fp_line
			(start 3.302 1.651)
			(end 3.302 -1.651)
			(stroke
				(width 0.1524)
				(type default)
			)
			(layer "F.SilkS")
		)
		(fp_line
			(start -3.302 -1.651)
			(end -3.302 1.651)
			(stroke
				(width 0.1524)
				(type default)
			)
			(layer "F.SilkS")
		)
		(fp_line
			(start 3.302 -1.651)
			(end -3.302 -1.651)
			(stroke
				(width 0.1524)
				(type default)
			)
			(layer "F.SilkS")
		)
		(fp_poly
			(pts
				(xy -3.3782 1.7272) (xy 3.3782 1.7272) (xy 3.3782 -1.7272) (xy -3.3782 -1.7272)
			)
			(stroke
				(width 0)
				(type default)
			)
			(fill no)
			(layer "F.CrtYd")
		)
		(fp_poly
			(pts
				(xy 3.3782 -1.7272) (xy -3.3782 -1.7272) (xy -3.3782 1.7272) (xy 3.3782 1.7272)
			)
			(stroke
				(width 0)
				(type default)
			)
			(fill no)
			(layer "F.Fab")
		)
		(pad "1" smd rect
			(at -2.3495 0 270)
			(size 1.143 2.794)
			(layers "F.Cu" "F.Mask" "F.Paste")
			(net "P12V_SSD14")
		)
		(pad "2" smd rect
			(at 2.3495 0 270)
			(size 1.143 2.794)
			(layers "F.Cu" "F.Mask" "F.Paste")
			(net "12V_PRECH_SSD14")
		)
	)
	(footprint ""
		(layer "F.Cu")
		(at 78.8162 -432.2445)
		(property "Reference" "R9960"
			(at 0 0 0)
			(layer "F.SilkS")
			(hide yes)
			(effects
				(font
					(size 1.27 1.27)
				)
			)
		)
		(property "Value" "470R2F-GP"
			(at 0.064008 -3.993896 0)
			(unlocked yes)
			(layer "F.Fab")
			(hide yes)
			(effects
				(font
					(size 1.016 1.016)
					(thickness 0.1524)
				)
			)
		)
		(property "Device Type" "R402H16"
			(at 0.064008 -5.517896 0)
			(unlocked yes)
			(layer "F.Fab")
			(hide yes)
			(effects
				(font
					(size 1.016 1.016)
					(thickness 0.1524)
				)
			)
		)
		(duplicate_pad_numbers_are_jumpers no)
		(fp_line
			(start -0.508 -0.9398)
			(end -0.508 0.9398)
			(stroke
				(width 0.1524)
				(type default)
			)
			(layer "F.SilkS")
		)
		(fp_line
			(start 0.508 -0.9398)
			(end -0.508 -0.9398)
			(stroke
				(width 0.1524)
				(type default)
			)
			(layer "F.SilkS")
		)
		(fp_rect
			(start -0.508 0.9398)
			(end 0.508 -0.9398)
			(stroke
				(width 0)
				(type default)
			)
			(fill no)
			(layer "F.CrtYd")
		)
		(fp_rect
			(start -0.508 0.9398)
			(end 0.508 -0.9398)
			(stroke
				(width 0)
				(type default)
			)
			(fill no)
			(layer "F.Fab")
		)
		(pad "1" smd custom
			(at 0 -0.4445)
			(size 0.1397 0.1397)
			(layers "F.Cu" "F.Mask" "F.Paste")
			(net "VDD_DIFF_1")
			(options
				(clearance outline)
				(anchor circle)
			)
			(primitives
				(gr_poly
					(pts
						(arc
							(start -0.1778 -0.2794)
							(mid -0.249642 -0.249642)
							(end -0.2794 -0.1778)
						)
						(arc
							(start -0.2794 0.1778)
							(mid -0.249642 0.249642)
							(end -0.1778 0.2794)
						)
						(arc
							(start 0.1778 0.2794)
							(mid 0.249642 0.249642)
							(end 0.2794 0.1778)
						)
						(arc
							(start 0.2794 -0.1778)
							(mid 0.249642 -0.249642)
							(end 0.1778 -0.2794)
						)
					)
					(width 0)
					(fill yes)
				)
			)
		)
		(pad "2" smd custom
			(at 0 0.4445)
			(size 0.1397 0.1397)
			(layers "F.Cu" "F.Mask" "F.Paste")
			(net "PE_100M_CLK4_P")
			(options
				(clearance outline)
				(anchor circle)
			)
			(primitives
				(gr_poly
					(pts
						(arc
							(start -0.1778 -0.2794)
							(mid -0.249642 -0.249642)
							(end -0.2794 -0.1778)
						)
						(arc
							(start -0.2794 0.1778)
							(mid -0.249642 0.249642)
							(end -0.1778 0.2794)
						)
						(arc
							(start 0.1778 0.2794)
							(mid 0.249642 0.249642)
							(end 0.2794 0.1778)
						)
						(arc
							(start 0.2794 -0.1778)
							(mid 0.249642 -0.249642)
							(end 0.1778 -0.2794)
						)
					)
					(width 0)
					(fill yes)
				)
			)
		)
	)
	(footprint ""
		(layer "F.Cu")
		(at 217.297 -393.573 180)
		(property "Reference" "SR1094"
			(at 0 0 180)
			(layer "F.SilkS")
			(hide yes)
			(effects
				(font
					(size 1.27 1.27)
				)
			)
		)
		(property "Value" "4K7R2F-GP"
			(at 0.064008 -3.993896 180)
			(unlocked yes)
			(layer "F.Fab")
			(hide yes)
			(effects
				(font
					(size 1.016 1.016)
					(thickness 0.1524)
				)
			)
		)
		(property "Device Type" "R402H16"
			(at 0.064008 -5.517896 180)
			(unlocked yes)
			(layer "F.Fab")
			(hide yes)
			(effects
				(font
					(size 1.016 1.016)
					(thickness 0.1524)
				)
			)
		)
		(duplicate_pad_numbers_are_jumpers no)
		(fp_line
			(start 0.508 -0.9398)
			(end -0.508 -0.9398)
			(stroke
				(width 0.1524)
				(type default)
			)
			(layer "F.SilkS")
		)
		(fp_line
			(start -0.508 -0.9398)
			(end -0.508 0.9398)
			(stroke
				(width 0.1524)
				(type default)
			)
			(layer "F.SilkS")
		)
		(fp_rect
			(start -0.508 0.9398)
			(end 0.508 -0.9398)
			(stroke
				(width 0)
				(type default)
			)
			(fill no)
			(layer "F.CrtYd")
		)
		(fp_rect
			(start -0.508 0.9398)
			(end 0.508 -0.9398)
			(stroke
				(width 0)
				(type default)
			)
			(fill no)
			(layer "F.Fab")
		)
		(pad "1" smd custom
			(at 0 -0.4445 180)
			(size 0.1397 0.1397)
			(layers "F.Cu" "F.Mask" "F.Paste")
			(net "DUALPORTEN#1")
			(options
				(clearance outline)
				(anchor circle)
			)
			(primitives
				(gr_poly
					(pts
						(arc
							(start -0.1778 -0.2794)
							(mid -0.249642 -0.249642)
							(end -0.2794 -0.1778)
						)
						(arc
							(start -0.2794 0.1778)
							(mid -0.249642 0.249642)
							(end -0.1778 0.2794)
						)
						(arc
							(start 0.1778 0.2794)
							(mid 0.249642 0.249642)
							(end 0.2794 0.1778)
						)
						(arc
							(start 0.2794 -0.1778)
							(mid 0.249642 -0.249642)
							(end 0.1778 -0.2794)
						)
					)
					(width 0)
					(fill yes)
				)
			)
		)
		(pad "2" smd custom
			(at 0 0.4445 180)
			(size 0.1397 0.1397)
			(layers "F.Cu" "F.Mask" "F.Paste")
			(net "GND")
			(options
				(clearance outline)
				(anchor circle)
			)
			(primitives
				(gr_poly
					(pts
						(arc
							(start -0.1778 -0.2794)
							(mid -0.249642 -0.249642)
							(end -0.2794 -0.1778)
						)
						(arc
							(start -0.2794 0.1778)
							(mid -0.249642 0.249642)
							(end -0.1778 0.2794)
						)
						(arc
							(start 0.1778 0.2794)
							(mid 0.249642 0.249642)
							(end 0.2794 0.1778)
						)
						(arc
							(start 0.2794 -0.1778)
							(mid 0.249642 -0.249642)
							(end 0.1778 -0.2794)
						)
					)
					(width 0)
					(fill yes)
				)
			)
		)
	)
	(footprint ""
		(layer "F.Cu")
		(at 37.6936 -105.8164)
		(property "Reference" "Q21"
			(at 0 0 0)
			(layer "F.SilkS")
			(hide yes)
			(effects
				(font
					(size 1.27 1.27)
				)
			)
		)
		(property "Value" "2N7002A-7-GP"
			(at 0.127 -8.9662 0)
			(unlocked yes)
			(layer "F.Fab")
			(hide yes)
			(effects
				(font
					(size 1.016 1.016)
					(thickness 0.1524)
				)
			)
		)
		(property "Device Type" "SOT23DGS2D4H48"
			(at 0.127 -10.4902 0)
			(unlocked yes)
			(layer "F.Fab")
			(hide yes)
			(effects
				(font
					(size 1.016 1.016)
					(thickness 0.1524)
				)
			)
		)
		(duplicate_pad_numbers_are_jumpers no)
		(fp_line
			(start -1.651 -1.778)
			(end -1.651 1.778)
			(stroke
				(width 0.1524)
				(type default)
			)
			(layer "F.SilkS")
		)
		(fp_line
			(start -1.651 1.778)
			(end 1.651 1.778)
			(stroke
				(width 0.1524)
				(type default)
			)
			(layer "F.SilkS")
		)
		(fp_line
			(start 1.651 -1.778)
			(end -1.651 -1.778)
			(stroke
				(width 0.1524)
				(type default)
			)
			(layer "F.SilkS")
		)
		(fp_line
			(start 1.651 1.778)
			(end 1.651 -1.778)
			(stroke
				(width 0.1524)
				(type default)
			)
			(layer "F.SilkS")
		)
		(fp_poly
			(pts
				(xy -1.778 1.8796) (xy -1.778 -1.8796) (xy 1.778 -1.8796) (xy 1.778 1.8796)
			)
			(stroke
				(width 0)
				(type default)
			)
			(fill no)
			(layer "F.CrtYd")
		)
		(fp_poly
			(pts
				(xy -1.778 1.8796) (xy -1.778 -1.8796) (xy 1.778 -1.8796) (xy 1.778 1.8796)
			)
			(stroke
				(width 0)
				(type default)
			)
			(fill no)
			(layer "F.Fab")
		)
		(pad "D" smd custom
			(at 0 -0.9525)
			(size 0.1905 0.1905)
			(layers "F.Cu" "F.Mask" "F.Paste")
			(net "SW_SSD13_R")
			(options
				(clearance outline)
				(anchor circle)
			)
			(primitives
				(gr_poly
					(pts
						(arc
							(start -0.1778 0.5715)
							(mid -0.321484 0.511984)
							(end -0.381 0.3683)
						)
						(arc
							(start -0.381 -0.3683)
							(mid -0.321484 -0.511984)
							(end -0.1778 -0.5715)
						)
						(arc
							(start 0.1778 -0.5715)
							(mid 0.321484 -0.511984)
							(end 0.381 -0.3683)
						)
						(arc
							(start 0.381 0.3683)
							(mid 0.321484 0.511984)
							(end 0.1778 0.5715)
						)
					)
					(width 0)
					(fill yes)
				)
			)
		)
		(pad "G" smd custom
			(at -0.98425 0.9525)
			(size 0.1905 0.1905)
			(layers "F.Cu" "F.Mask" "F.Paste")
			(net "SSD13_PWREN")
			(options
				(clearance outline)
				(anchor circle)
			)
			(primitives
				(gr_poly
					(pts
						(arc
							(start -0.1778 0.5715)
							(mid -0.321484 0.511984)
							(end -0.381 0.3683)
						)
						(arc
							(start -0.381 -0.3683)
							(mid -0.321484 -0.511984)
							(end -0.1778 -0.5715)
						)
						(arc
							(start 0.1778 -0.5715)
							(mid 0.321484 -0.511984)
							(end 0.381 -0.3683)
						)
						(arc
							(start 0.381 0.3683)
							(mid 0.321484 0.511984)
							(end 0.1778 0.5715)
						)
					)
					(width 0)
					(fill yes)
				)
			)
		)
		(pad "S" smd custom
			(at 0.98425 0.9525)
			(size 0.1905 0.1905)
			(layers "F.Cu" "F.Mask" "F.Paste")
			(net "GND")
			(options
				(clearance outline)
				(anchor circle)
			)
			(primitives
				(gr_poly
					(pts
						(arc
							(start -0.1778 0.5715)
							(mid -0.321484 0.511984)
							(end -0.381 0.3683)
						)
						(arc
							(start -0.381 -0.3683)
							(mid -0.321484 -0.511984)
							(end -0.1778 -0.5715)
						)
						(arc
							(start 0.1778 -0.5715)
							(mid 0.321484 -0.511984)
							(end 0.381 -0.3683)
						)
						(arc
							(start 0.381 0.3683)
							(mid 0.321484 0.511984)
							(end 0.1778 0.5715)
						)
					)
					(width 0)
					(fill yes)
				)
			)
		)
	)
	(footprint ""
		(layer "F.Cu")
		(at 210.693 -454.66)
		(property "Reference" "R324"
			(at 0 0 0)
			(layer "F.SilkS")
			(hide yes)
			(effects
				(font
					(size 1.27 1.27)
				)
			)
		)
		(property "Value" "4K7R2F-GP"
			(at 0.064008 -3.993896 0)
			(unlocked yes)
			(layer "F.Fab")
			(hide yes)
			(effects
				(font
					(size 1.016 1.016)
					(thickness 0.1524)
				)
			)
		)
		(property "Device Type" "R402H16"
			(at 0.064008 -5.517896 0)
			(unlocked yes)
			(layer "F.Fab")
			(hide yes)
			(effects
				(font
					(size 1.016 1.016)
					(thickness 0.1524)
				)
			)
		)
		(duplicate_pad_numbers_are_jumpers no)
		(fp_line
			(start -0.508 -0.9398)
			(end -0.508 0.9398)
			(stroke
				(width 0.1524)
				(type default)
			)
			(layer "F.SilkS")
		)
		(fp_line
			(start 0.508 -0.9398)
			(end -0.508 -0.9398)
			(stroke
				(width 0.1524)
				(type default)
			)
			(layer "F.SilkS")
		)
		(fp_rect
			(start -0.508 0.9398)
			(end 0.508 -0.9398)
			(stroke
				(width 0)
				(type default)
			)
			(fill no)
			(layer "F.CrtYd")
		)
		(fp_rect
			(start -0.508 0.9398)
			(end 0.508 -0.9398)
			(stroke
				(width 0)
				(type default)
			)
			(fill no)
			(layer "F.Fab")
		)
		(pad "1" smd custom
			(at 0 -0.4445)
			(size 0.1397 0.1397)
			(layers "F.Cu" "F.Mask" "F.Paste")
			(net "I2C_B_TMP2_A1")
			(options
				(clearance outline)
				(anchor circle)
			)
			(primitives
				(gr_poly
					(pts
						(arc
							(start -0.1778 -0.2794)
							(mid -0.249642 -0.249642)
							(end -0.2794 -0.1778)
						)
						(arc
							(start -0.2794 0.1778)
							(mid -0.249642 0.249642)
							(end -0.1778 0.2794)
						)
						(arc
							(start 0.1778 0.2794)
							(mid 0.249642 0.249642)
							(end 0.2794 0.1778)
						)
						(arc
							(start 0.2794 -0.1778)
							(mid 0.249642 -0.249642)
							(end 0.1778 -0.2794)
						)
					)
					(width 0)
					(fill yes)
				)
			)
		)
		(pad "2" smd custom
			(at 0 0.4445)
			(size 0.1397 0.1397)
			(layers "F.Cu" "F.Mask" "F.Paste")
			(net "GND")
			(options
				(clearance outline)
				(anchor circle)
			)
			(primitives
				(gr_poly
					(pts
						(arc
							(start -0.1778 -0.2794)
							(mid -0.249642 -0.249642)
							(end -0.2794 -0.1778)
						)
						(arc
							(start -0.2794 0.1778)
							(mid -0.249642 0.249642)
							(end -0.1778 0.2794)
						)
						(arc
							(start 0.1778 0.2794)
							(mid 0.249642 0.249642)
							(end 0.2794 0.1778)
						)
						(arc
							(start 0.2794 -0.1778)
							(mid 0.249642 -0.249642)
							(end 0.1778 -0.2794)
						)
					)
					(width 0)
					(fill yes)
				)
			)
		)
	)
	(footprint ""
		(layer "F.Cu")
		(at 70.739 -358.521 90)
		(property "Reference" "SR980"
			(at 0 0 90)
			(layer "F.SilkS")
			(hide yes)
			(effects
				(font
					(size 1.27 1.27)
				)
			)
		)
		(property "Value" "2KR2F-3-GP"
			(at 0.064008 -3.993896 90)
			(unlocked yes)
			(layer "F.Fab")
			(hide yes)
			(effects
				(font
					(size 1.016 1.016)
					(thickness 0.1524)
				)
			)
		)
		(property "Device Type" "R402H16"
			(at 0.064008 -5.517896 90)
			(unlocked yes)
			(layer "F.Fab")
			(hide yes)
			(effects
				(font
					(size 1.016 1.016)
					(thickness 0.1524)
				)
			)
		)
		(duplicate_pad_numbers_are_jumpers no)
		(fp_line
			(start 0.508 -0.9398)
			(end -0.508 -0.9398)
			(stroke
				(width 0.1524)
				(type default)
			)
			(layer "F.SilkS")
		)
		(fp_line
			(start -0.508 -0.9398)
			(end -0.508 0.9398)
			(stroke
				(width 0.1524)
				(type default)
			)
			(layer "F.SilkS")
		)
		(fp_rect
			(start -0.508 0.9398)
			(end 0.508 -0.9398)
			(stroke
				(width 0)
				(type default)
			)
			(fill no)
			(layer "F.CrtYd")
		)
		(fp_rect
			(start -0.508 0.9398)
			(end 0.508 -0.9398)
			(stroke
				(width 0)
				(type default)
			)
			(fill no)
			(layer "F.Fab")
		)
		(pad "1" smd custom
			(at 0 -0.4445 90)
			(size 0.1397 0.1397)
			(layers "F.Cu" "F.Mask" "F.Paste")
			(net "P3V3")
			(options
				(clearance outline)
				(anchor circle)
			)
			(primitives
				(gr_poly
					(pts
						(arc
							(start -0.1778 -0.2794)
							(mid -0.249642 -0.249642)
							(end -0.2794 -0.1778)
						)
						(arc
							(start -0.2794 0.1778)
							(mid -0.249642 0.249642)
							(end -0.1778 0.2794)
						)
						(arc
							(start 0.1778 0.2794)
							(mid 0.249642 0.249642)
							(end 0.2794 0.1778)
						)
						(arc
							(start 0.2794 -0.1778)
							(mid 0.249642 -0.249642)
							(end 0.1778 -0.2794)
						)
					)
					(width 0)
					(fill yes)
				)
			)
		)
		(pad "2" smd custom
			(at 0 0.4445 90)
			(size 0.1397 0.1397)
			(layers "F.Cu" "F.Mask" "F.Paste")
			(net "SCL_DR7")
			(options
				(clearance outline)
				(anchor circle)
			)
			(primitives
				(gr_poly
					(pts
						(arc
							(start -0.1778 -0.2794)
							(mid -0.249642 -0.249642)
							(end -0.2794 -0.1778)
						)
						(arc
							(start -0.2794 0.1778)
							(mid -0.249642 0.249642)
							(end -0.1778 0.2794)
						)
						(arc
							(start 0.1778 0.2794)
							(mid 0.249642 0.249642)
							(end 0.2794 0.1778)
						)
						(arc
							(start 0.2794 -0.1778)
							(mid 0.249642 -0.249642)
							(end 0.1778 -0.2794)
						)
					)
					(width 0)
					(fill yes)
				)
			)
		)
	)
	(footprint ""
		(layer "F.Cu")
		(at 207.391 -44.704 180)
		(property "Reference" "R327"
			(at 0 0 180)
			(layer "F.SilkS")
			(hide yes)
			(effects
				(font
					(size 1.27 1.27)
				)
			)
		)
		(property "Value" "4K7R2F-GP"
			(at 0.064008 -3.993896 180)
			(unlocked yes)
			(layer "F.Fab")
			(hide yes)
			(effects
				(font
					(size 1.016 1.016)
					(thickness 0.1524)
				)
			)
		)
		(property "Device Type" "R402H16"
			(at 0.064008 -5.517896 180)
			(unlocked yes)
			(layer "F.Fab")
			(hide yes)
			(effects
				(font
					(size 1.016 1.016)
					(thickness 0.1524)
				)
			)
		)
		(duplicate_pad_numbers_are_jumpers no)
		(fp_line
			(start 0.508 -0.9398)
			(end -0.508 -0.9398)
			(stroke
				(width 0.1524)
				(type default)
			)
			(layer "F.SilkS")
		)
		(fp_line
			(start -0.508 -0.9398)
			(end -0.508 0.9398)
			(stroke
				(width 0.1524)
				(type default)
			)
			(layer "F.SilkS")
		)
		(fp_rect
			(start -0.508 0.9398)
			(end 0.508 -0.9398)
			(stroke
				(width 0)
				(type default)
			)
			(fill no)
			(layer "F.CrtYd")
		)
		(fp_rect
			(start -0.508 0.9398)
			(end 0.508 -0.9398)
			(stroke
				(width 0)
				(type default)
			)
			(fill no)
			(layer "F.Fab")
		)
		(pad "1" smd custom
			(at 0 -0.4445 180)
			(size 0.1397 0.1397)
			(layers "F.Cu" "F.Mask" "F.Paste")
			(net "P3V3")
			(options
				(clearance outline)
				(anchor circle)
			)
			(primitives
				(gr_poly
					(pts
						(arc
							(start -0.1778 -0.2794)
							(mid -0.249642 -0.249642)
							(end -0.2794 -0.1778)
						)
						(arc
							(start -0.2794 0.1778)
							(mid -0.249642 0.249642)
							(end -0.1778 0.2794)
						)
						(arc
							(start 0.1778 0.2794)
							(mid 0.249642 0.249642)
							(end 0.2794 0.1778)
						)
						(arc
							(start 0.2794 -0.1778)
							(mid 0.249642 -0.249642)
							(end 0.1778 -0.2794)
						)
					)
					(width 0)
					(fill yes)
				)
			)
		)
		(pad "2" smd custom
			(at 0 0.4445 180)
			(size 0.1397 0.1397)
			(layers "F.Cu" "F.Mask" "F.Paste")
			(net "I2C_B_TMP3_A0")
			(options
				(clearance outline)
				(anchor circle)
			)
			(primitives
				(gr_poly
					(pts
						(arc
							(start -0.1778 -0.2794)
							(mid -0.249642 -0.249642)
							(end -0.2794 -0.1778)
						)
						(arc
							(start -0.2794 0.1778)
							(mid -0.249642 0.249642)
							(end -0.1778 0.2794)
						)
						(arc
							(start 0.1778 0.2794)
							(mid 0.249642 0.249642)
							(end 0.2794 0.1778)
						)
						(arc
							(start 0.2794 -0.1778)
							(mid 0.249642 -0.249642)
							(end 0.1778 -0.2794)
						)
					)
					(width 0)
					(fill yes)
				)
			)
		)
	)
	(footprint ""
		(layer "F.Cu")
		(at 245.491 -424.434 -90)
		(property "Reference" "C356"
			(at 0 0 270)
			(layer "F.SilkS")
			(hide yes)
			(effects
				(font
					(size 1.27 1.27)
				)
			)
		)
		(property "Value" "SC220P50V3JN-GP"
			(at 0 -2.8194 270)
			(unlocked yes)
			(layer "F.Fab")
			(hide yes)
			(effects
				(font
					(size 1.016 1.016)
					(thickness 0.1524)
				)
			)
		)
		(property "Device Type" "C603H36"
			(at 0 -4.3434 270)
			(unlocked yes)
			(layer "F.Fab")
			(hide yes)
			(effects
				(font
					(size 1.016 1.016)
					(thickness 0.1524)
				)
			)
		)
		(duplicate_pad_numbers_are_jumpers no)
		(fp_line
			(start 0.508 0)
			(end -0.508 0)
			(stroke
				(width 0.2032)
				(type default)
			)
			(layer "F.SilkS")
		)
		(fp_rect
			(start -0.5842 1.3335)
			(end 0.5842 -1.3335)
			(stroke
				(width 0)
				(type default)
			)
			(fill no)
			(layer "F.CrtYd")
		)
		(fp_rect
			(start -0.5842 1.3335)
			(end 0.5842 -1.3335)
			(stroke
				(width 0)
				(type default)
			)
			(fill no)
			(layer "F.Fab")
		)
		(pad "1" smd custom
			(at 0 -0.762 270)
			(size 0.2159 0.2159)
			(layers "F.Cu" "F.Mask" "F.Paste")
			(net "I2C_C_SCL")
			(options
				(clearance outline)
				(anchor circle)
			)
			(primitives
				(gr_poly
					(pts
						(arc
							(start -0.3302 -0.4318)
							(mid -0.402042 -0.402042)
							(end -0.4318 -0.3302)
						)
						(arc
							(start -0.4318 0.3302)
							(mid -0.402042 0.402042)
							(end -0.3302 0.4318)
						)
						(arc
							(start 0.3302 0.4318)
							(mid 0.402042 0.402042)
							(end 0.4318 0.3302)
						)
						(arc
							(start 0.4318 -0.3302)
							(mid 0.402042 -0.402042)
							(end 0.3302 -0.4318)
						)
					)
					(width 0)
					(fill yes)
				)
			)
		)
		(pad "2" smd custom
			(at 0 0.762 270)
			(size 0.2159 0.2159)
			(layers "F.Cu" "F.Mask" "F.Paste")
			(net "GND")
			(options
				(clearance outline)
				(anchor circle)
			)
			(primitives
				(gr_poly
					(pts
						(arc
							(start -0.3302 -0.4318)
							(mid -0.402042 -0.402042)
							(end -0.4318 -0.3302)
						)
						(arc
							(start -0.4318 0.3302)
							(mid -0.402042 0.402042)
							(end -0.3302 0.4318)
						)
						(arc
							(start 0.3302 0.4318)
							(mid 0.402042 0.402042)
							(end 0.4318 0.3302)
						)
						(arc
							(start 0.4318 -0.3302)
							(mid 0.402042 -0.402042)
							(end 0.3302 -0.4318)
						)
					)
					(width 0)
					(fill yes)
				)
			)
		)
	)
	(footprint ""
		(layer "F.Cu")
		(at 87.122 -215.519)
		(property "Reference" "C8913"
			(at 0 0 0)
			(layer "F.SilkS")
			(hide yes)
			(effects
				(font
					(size 1.27 1.27)
				)
			)
		)
		(property "Value" "SC1U10V2KX-7-GP"
			(at 1.1811 -2.7051 0)
			(unlocked yes)
			(layer "F.Fab")
			(hide yes)
			(effects
				(font
					(size 1.016 1.016)
					(thickness 0.1524)
				)
			)
		)
		(property "Device Type" "C402H22"
			(at 1.1811 -4.2291 0)
			(unlocked yes)
			(layer "F.Fab")
			(hide yes)
			(effects
				(font
					(size 1.016 1.016)
					(thickness 0.1524)
				)
			)
		)
		(duplicate_pad_numbers_are_jumpers no)
		(fp_rect
			(start -0.4318 0.9525)
			(end 0.4318 -0.9525)
			(stroke
				(width 0)
				(type default)
			)
			(fill no)
			(layer "F.CrtYd")
		)
		(fp_rect
			(start -0.4318 0.9525)
			(end 0.4318 -0.9525)
			(stroke
				(width 0)
				(type default)
			)
			(fill no)
			(layer "F.Fab")
		)
		(pad "1" smd custom
			(at 0 -0.4445)
			(size 0.1524 0.1524)
			(layers "F.Cu" "F.Mask" "F.Paste")
			(net "VDDA_3")
			(options
				(clearance outline)
				(anchor circle)
			)
			(primitives
				(gr_poly
					(pts
						(arc
							(start 0.3048 -0.2032)
							(mid 0.275042 -0.275042)
							(end 0.2032 -0.3048)
						)
						(arc
							(start -0.2032 -0.3048)
							(mid -0.275042 -0.275042)
							(end -0.3048 -0.2032)
						)
						(arc
							(start -0.3048 0.2032)
							(mid -0.275042 0.275042)
							(end -0.2032 0.3048)
						)
						(arc
							(start 0.2032 0.3048)
							(mid 0.275042 0.275042)
							(end 0.3048 0.2032)
						)
					)
					(width 0)
					(fill yes)
				)
			)
		)
		(pad "2" smd custom
			(at 0 0.4445)
			(size 0.1524 0.1524)
			(layers "F.Cu" "F.Mask" "F.Paste")
			(net "GND")
			(options
				(clearance outline)
				(anchor circle)
			)
			(primitives
				(gr_poly
					(pts
						(arc
							(start 0.3048 -0.2032)
							(mid 0.275042 -0.275042)
							(end 0.2032 -0.3048)
						)
						(arc
							(start -0.2032 -0.3048)
							(mid -0.275042 -0.275042)
							(end -0.3048 -0.2032)
						)
						(arc
							(start -0.3048 0.2032)
							(mid -0.275042 0.275042)
							(end -0.2032 0.3048)
						)
						(arc
							(start 0.2032 0.3048)
							(mid 0.275042 0.275042)
							(end 0.3048 0.2032)
						)
					)
					(width 0)
					(fill yes)
				)
			)
		)
	)
	(footprint ""
		(layer "F.Cu")
		(at 93.599 -93.853)
		(property "Reference" "C9517"
			(at 0 0 0)
			(layer "F.SilkS")
			(hide yes)
			(effects
				(font
					(size 1.27 1.27)
				)
			)
		)
		(property "Value" "SCD1U16V2KX-3GP"
			(at 1.1811 -2.7051 0)
			(unlocked yes)
			(layer "F.Fab")
			(hide yes)
			(effects
				(font
					(size 1.016 1.016)
					(thickness 0.1524)
				)
			)
		)
		(property "Device Type" "C402H22"
			(at 1.1811 -4.2291 0)
			(unlocked yes)
			(layer "F.Fab")
			(hide yes)
			(effects
				(font
					(size 1.016 1.016)
					(thickness 0.1524)
				)
			)
		)
		(duplicate_pad_numbers_are_jumpers no)
		(fp_rect
			(start -0.4318 0.9525)
			(end 0.4318 -0.9525)
			(stroke
				(width 0)
				(type default)
			)
			(fill no)
			(layer "F.CrtYd")
		)
		(fp_rect
			(start -0.4318 0.9525)
			(end 0.4318 -0.9525)
			(stroke
				(width 0)
				(type default)
			)
			(fill no)
			(layer "F.Fab")
		)
		(pad "1" smd custom
			(at 0 -0.4445)
			(size 0.1524 0.1524)
			(layers "F.Cu" "F.Mask" "F.Paste")
			(net "VDD_DIFF_4")
			(options
				(clearance outline)
				(anchor circle)
			)
			(primitives
				(gr_poly
					(pts
						(arc
							(start 0.3048 -0.2032)
							(mid 0.275042 -0.275042)
							(end 0.2032 -0.3048)
						)
						(arc
							(start -0.2032 -0.3048)
							(mid -0.275042 -0.275042)
							(end -0.3048 -0.2032)
						)
						(arc
							(start -0.3048 0.2032)
							(mid -0.275042 0.275042)
							(end -0.2032 0.3048)
						)
						(arc
							(start 0.2032 0.3048)
							(mid 0.275042 0.275042)
							(end 0.3048 0.2032)
						)
					)
					(width 0)
					(fill yes)
				)
			)
		)
		(pad "2" smd custom
			(at 0 0.4445)
			(size 0.1524 0.1524)
			(layers "F.Cu" "F.Mask" "F.Paste")
			(net "GND")
			(options
				(clearance outline)
				(anchor circle)
			)
			(primitives
				(gr_poly
					(pts
						(arc
							(start 0.3048 -0.2032)
							(mid 0.275042 -0.275042)
							(end 0.2032 -0.3048)
						)
						(arc
							(start -0.2032 -0.3048)
							(mid -0.275042 -0.275042)
							(end -0.3048 -0.2032)
						)
						(arc
							(start -0.3048 0.2032)
							(mid -0.275042 0.275042)
							(end -0.2032 0.3048)
						)
						(arc
							(start 0.2032 0.3048)
							(mid 0.275042 0.275042)
							(end 0.3048 0.2032)
						)
					)
					(width 0)
					(fill yes)
				)
			)
		)
	)
	(footprint ""
		(layer "F.Cu")
		(at 222.0468 -395.1478)
		(property "Reference" "PC1238"
			(at 0 0 0)
			(layer "F.SilkS")
			(hide yes)
			(effects
				(font
					(size 1.27 1.27)
				)
			)
		)
		(property "Value" "SCD01U50V2KX-1GP"
			(at 1.1811 -2.7051 0)
			(unlocked yes)
			(layer "F.Fab")
			(hide yes)
			(effects
				(font
					(size 1.016 1.016)
					(thickness 0.1524)
				)
			)
		)
		(property "Device Type" "C402H22"
			(at 1.1811 -4.2291 0)
			(unlocked yes)
			(layer "F.Fab")
			(hide yes)
			(effects
				(font
					(size 1.016 1.016)
					(thickness 0.1524)
				)
			)
		)
		(duplicate_pad_numbers_are_jumpers no)
		(fp_rect
			(start -0.4318 0.9525)
			(end 0.4318 -0.9525)
			(stroke
				(width 0)
				(type default)
			)
			(fill no)
			(layer "F.CrtYd")
		)
		(fp_rect
			(start -0.4318 0.9525)
			(end 0.4318 -0.9525)
			(stroke
				(width 0)
				(type default)
			)
			(fill no)
			(layer "F.Fab")
		)
		(pad "1" smd custom
			(at 0 -0.4445)
			(size 0.1524 0.1524)
			(layers "F.Cu" "F.Mask" "F.Paste")
			(net "P12V_SSD1")
			(options
				(clearance outline)
				(anchor circle)
			)
			(primitives
				(gr_poly
					(pts
						(arc
							(start 0.3048 -0.2032)
							(mid 0.275042 -0.275042)
							(end 0.2032 -0.3048)
						)
						(arc
							(start -0.2032 -0.3048)
							(mid -0.275042 -0.275042)
							(end -0.3048 -0.2032)
						)
						(arc
							(start -0.3048 0.2032)
							(mid -0.275042 0.275042)
							(end -0.2032 0.3048)
						)
						(arc
							(start 0.2032 0.3048)
							(mid 0.275042 0.275042)
							(end 0.3048 0.2032)
						)
					)
					(width 0)
					(fill yes)
				)
			)
		)
		(pad "2" smd custom
			(at 0 0.4445)
			(size 0.1524 0.1524)
			(layers "F.Cu" "F.Mask" "F.Paste")
			(net "GND")
			(options
				(clearance outline)
				(anchor circle)
			)
			(primitives
				(gr_poly
					(pts
						(arc
							(start 0.3048 -0.2032)
							(mid 0.275042 -0.275042)
							(end 0.2032 -0.3048)
						)
						(arc
							(start -0.2032 -0.3048)
							(mid -0.275042 -0.275042)
							(end -0.3048 -0.2032)
						)
						(arc
							(start -0.3048 0.2032)
							(mid -0.275042 0.275042)
							(end -0.2032 0.3048)
						)
						(arc
							(start 0.2032 0.3048)
							(mid 0.275042 0.275042)
							(end 0.3048 0.2032)
						)
					)
					(width 0)
					(fill yes)
				)
			)
		)
	)
	(footprint ""
		(layer "F.Cu")
		(at 88.011 -419.735 90)
		(property "Reference" "C131"
			(at 0 0 90)
			(layer "F.SilkS")
			(hide yes)
			(effects
				(font
					(size 1.27 1.27)
				)
			)
		)
		(property "Value" "SC1KP50V2KX-1GP"
			(at 1.1811 -2.7051 90)
			(unlocked yes)
			(layer "F.Fab")
			(hide yes)
			(effects
				(font
					(size 1.016 1.016)
					(thickness 0.1524)
				)
			)
		)
		(property "Device Type" "C402H22"
			(at 1.1811 -4.2291 90)
			(unlocked yes)
			(layer "F.Fab")
			(hide yes)
			(effects
				(font
					(size 1.016 1.016)
					(thickness 0.1524)
				)
			)
		)
		(duplicate_pad_numbers_are_jumpers no)
		(fp_rect
			(start -0.4318 0.9525)
			(end 0.4318 -0.9525)
			(stroke
				(width 0)
				(type default)
			)
			(fill no)
			(layer "F.CrtYd")
		)
		(fp_rect
			(start -0.4318 0.9525)
			(end 0.4318 -0.9525)
			(stroke
				(width 0)
				(type default)
			)
			(fill no)
			(layer "F.Fab")
		)
		(pad "1" smd custom
			(at 0 -0.4445 90)
			(size 0.1524 0.1524)
			(layers "F.Cu" "F.Mask" "F.Paste")
			(net "SSD_PRSNT10")
			(options
				(clearance outline)
				(anchor circle)
			)
			(primitives
				(gr_poly
					(pts
						(arc
							(start 0.3048 -0.2032)
							(mid 0.275042 -0.275042)
							(end 0.2032 -0.3048)
						)
						(arc
							(start -0.2032 -0.3048)
							(mid -0.275042 -0.275042)
							(end -0.3048 -0.2032)
						)
						(arc
							(start -0.3048 0.2032)
							(mid -0.275042 0.275042)
							(end -0.2032 0.3048)
						)
						(arc
							(start 0.2032 0.3048)
							(mid 0.275042 0.275042)
							(end 0.3048 0.2032)
						)
					)
					(width 0)
					(fill yes)
				)
			)
		)
		(pad "2" smd custom
			(at 0 0.4445 90)
			(size 0.1524 0.1524)
			(layers "F.Cu" "F.Mask" "F.Paste")
			(net "GND")
			(options
				(clearance outline)
				(anchor circle)
			)
			(primitives
				(gr_poly
					(pts
						(arc
							(start 0.3048 -0.2032)
							(mid 0.275042 -0.275042)
							(end 0.2032 -0.3048)
						)
						(arc
							(start -0.2032 -0.3048)
							(mid -0.275042 -0.275042)
							(end -0.3048 -0.2032)
						)
						(arc
							(start -0.3048 0.2032)
							(mid -0.275042 0.275042)
							(end -0.2032 0.3048)
						)
						(arc
							(start 0.2032 0.3048)
							(mid 0.275042 0.275042)
							(end 0.3048 0.2032)
						)
					)
					(width 0)
					(fill yes)
				)
			)
		)
	)
	(footprint ""
		(layer "F.Cu")
		(at 25.7556 -204.6478 90)
		(property "Reference" "R9858"
			(at 0 0 90)
			(layer "F.SilkS")
			(hide yes)
			(effects
				(font
					(size 1.27 1.27)
				)
			)
		)
		(property "Value" "2K2R5F-GP"
			(at 0 -8.9535 90)
			(unlocked yes)
			(layer "F.Fab")
			(hide yes)
			(effects
				(font
					(size 1.27 1.016)
					(thickness 0.1524)
				)
			)
		)
		(property "Device Type" "R805H24"
			(at 0 -10.6299 90)
			(unlocked yes)
			(layer "F.Fab")
			(hide yes)
			(effects
				(font
					(size 1.27 1.016)
					(thickness 0.1524)
				)
			)
		)
		(duplicate_pad_numbers_are_jumpers no)
		(fp_line
			(start 0.889 -1.7018)
			(end -0.889 -1.7018)
			(stroke
				(width 0.1524)
				(type default)
			)
			(layer "F.SilkS")
		)
		(fp_line
			(start 0.889 -1.7018)
			(end 0.889 -0.381)
			(stroke
				(width 0.1524)
				(type default)
			)
			(layer "F.SilkS")
		)
		(fp_line
			(start -0.889 -1.7018)
			(end -0.889 0.2794)
			(stroke
				(width 0.1524)
				(type default)
			)
			(layer "F.SilkS")
		)
		(fp_line
			(start -0.889 0.0762)
			(end -0.889 1.7018)
			(stroke
				(width 0.1524)
				(type default)
			)
			(layer "F.SilkS")
		)
		(fp_line
			(start 0.889 1.7018)
			(end 0.889 -0.508)
			(stroke
				(width 0.1524)
				(type default)
			)
			(layer "F.SilkS")
		)
		(fp_line
			(start -0.889 1.7018)
			(end 0.889 1.7018)
			(stroke
				(width 0.1524)
				(type default)
			)
			(layer "F.SilkS")
		)
		(fp_poly
			(pts
				(xy 0.9652 -1.778) (xy 0.9652 1.778) (xy -0.9652 1.778) (xy -0.9652 -1.778)
			)
			(stroke
				(width 0)
				(type default)
			)
			(fill no)
			(layer "F.CrtYd")
		)
		(fp_rect
			(start -0.9652 1.778)
			(end 0.9652 -1.778)
			(stroke
				(width 0)
				(type default)
			)
			(fill no)
			(layer "F.Fab")
		)
		(pad "1" smd rect
			(at 0 -0.9652 90)
			(size 1.397 1.143)
			(layers "F.Cu" "F.Mask" "F.Paste")
			(net "P12V_SSD12")
		)
		(pad "2" smd rect
			(at 0 0.9652 90)
			(size 1.397 1.143)
			(layers "F.Cu" "F.Mask" "F.Paste")
			(net "P12V_MOST12_GATE_D")
		)
	)
	(footprint ""
		(layer "F.Cu")
		(at 16.129 -370.332)
		(property "Reference" "Q83"
			(at 0 0 0)
			(layer "F.SilkS")
			(hide yes)
			(effects
				(font
					(size 1.27 1.27)
				)
			)
		)
		(property "Value" "2N7002A-7-GP"
			(at 0.127 -8.9662 0)
			(unlocked yes)
			(layer "F.Fab")
			(hide yes)
			(effects
				(font
					(size 1.016 1.016)
					(thickness 0.1524)
				)
			)
		)
		(property "Device Type" "SOT23DGS2D4H48"
			(at 0.127 -10.4902 0)
			(unlocked yes)
			(layer "F.Fab")
			(hide yes)
			(effects
				(font
					(size 1.016 1.016)
					(thickness 0.1524)
				)
			)
		)
		(duplicate_pad_numbers_are_jumpers no)
		(fp_line
			(start -1.651 -1.778)
			(end -1.651 1.778)
			(stroke
				(width 0.1524)
				(type default)
			)
			(layer "F.SilkS")
		)
		(fp_line
			(start -1.651 1.778)
			(end 1.651 1.778)
			(stroke
				(width 0.1524)
				(type default)
			)
			(layer "F.SilkS")
		)
		(fp_line
			(start 1.651 -1.778)
			(end -1.651 -1.778)
			(stroke
				(width 0.1524)
				(type default)
			)
			(layer "F.SilkS")
		)
		(fp_line
			(start 1.651 1.778)
			(end 1.651 -1.778)
			(stroke
				(width 0.1524)
				(type default)
			)
			(layer "F.SilkS")
		)
		(fp_poly
			(pts
				(xy -1.778 1.8796) (xy -1.778 -1.8796) (xy 1.778 -1.8796) (xy 1.778 1.8796)
			)
			(stroke
				(width 0)
				(type default)
			)
			(fill no)
			(layer "F.CrtYd")
		)
		(fp_poly
			(pts
				(xy -1.778 1.8796) (xy -1.778 -1.8796) (xy 1.778 -1.8796) (xy 1.778 1.8796)
			)
			(stroke
				(width 0)
				(type default)
			)
			(fill no)
			(layer "F.Fab")
		)
		(pad "D" smd custom
			(at 0 -0.9525)
			(size 0.1905 0.1905)
			(layers "F.Cu" "F.Mask" "F.Paste")
			(net "SSD_ACT_DR11_MOS_N")
			(options
				(clearance outline)
				(anchor circle)
			)
			(primitives
				(gr_poly
					(pts
						(arc
							(start -0.1778 0.5715)
							(mid -0.321484 0.511984)
							(end -0.381 0.3683)
						)
						(arc
							(start -0.381 -0.3683)
							(mid -0.321484 -0.511984)
							(end -0.1778 -0.5715)
						)
						(arc
							(start 0.1778 -0.5715)
							(mid 0.321484 -0.511984)
							(end 0.381 -0.3683)
						)
						(arc
							(start 0.381 0.3683)
							(mid 0.321484 0.511984)
							(end 0.1778 0.5715)
						)
					)
					(width 0)
					(fill yes)
				)
			)
		)
		(pad "G" smd custom
			(at -0.98425 0.9525)
			(size 0.1905 0.1905)
			(layers "F.Cu" "F.Mask" "F.Paste")
			(net "ATTN_LED_DR11_AND_R")
			(options
				(clearance outline)
				(anchor circle)
			)
			(primitives
				(gr_poly
					(pts
						(arc
							(start -0.1778 0.5715)
							(mid -0.321484 0.511984)
							(end -0.381 0.3683)
						)
						(arc
							(start -0.381 -0.3683)
							(mid -0.321484 -0.511984)
							(end -0.1778 -0.5715)
						)
						(arc
							(start 0.1778 -0.5715)
							(mid 0.321484 -0.511984)
							(end 0.381 -0.3683)
						)
						(arc
							(start 0.381 0.3683)
							(mid 0.321484 0.511984)
							(end 0.1778 0.5715)
						)
					)
					(width 0)
					(fill yes)
				)
			)
		)
		(pad "S" smd custom
			(at 0.98425 0.9525)
			(size 0.1905 0.1905)
			(layers "F.Cu" "F.Mask" "F.Paste")
			(net "SSD_ACT_DR11_R")
			(options
				(clearance outline)
				(anchor circle)
			)
			(primitives
				(gr_poly
					(pts
						(arc
							(start -0.1778 0.5715)
							(mid -0.321484 0.511984)
							(end -0.381 0.3683)
						)
						(arc
							(start -0.381 -0.3683)
							(mid -0.321484 -0.511984)
							(end -0.1778 -0.5715)
						)
						(arc
							(start 0.1778 -0.5715)
							(mid 0.321484 -0.511984)
							(end 0.381 -0.3683)
						)
						(arc
							(start 0.381 0.3683)
							(mid 0.321484 0.511984)
							(end 0.1778 0.5715)
						)
					)
					(width 0)
					(fill yes)
				)
			)
		)
	)
	(footprint ""
		(layer "F.Cu")
		(at 229.67696 -344.118692)
		(property "Reference" "C9519"
			(at 0 0 0)
			(layer "F.SilkS")
			(hide yes)
			(effects
				(font
					(size 1.27 1.27)
				)
			)
		)
		(property "Value" "SCD1U16V2KX-3GP"
			(at 1.1811 -2.7051 0)
			(unlocked yes)
			(layer "F.Fab")
			(hide yes)
			(effects
				(font
					(size 1.016 1.016)
					(thickness 0.1524)
				)
			)
		)
		(property "Device Type" "C402H22"
			(at 1.1811 -4.2291 0)
			(unlocked yes)
			(layer "F.Fab")
			(hide yes)
			(effects
				(font
					(size 1.016 1.016)
					(thickness 0.1524)
				)
			)
		)
		(duplicate_pad_numbers_are_jumpers no)
		(fp_rect
			(start -0.4318 0.9525)
			(end 0.4318 -0.9525)
			(stroke
				(width 0)
				(type default)
			)
			(fill no)
			(layer "F.CrtYd")
		)
		(fp_rect
			(start -0.4318 0.9525)
			(end 0.4318 -0.9525)
			(stroke
				(width 0)
				(type default)
			)
			(fill no)
			(layer "F.Fab")
		)
		(pad "1" smd custom
			(at 0 -0.4445)
			(size 0.1524 0.1524)
			(layers "F.Cu" "F.Mask" "F.Paste")
			(net "P3V3")
			(options
				(clearance outline)
				(anchor circle)
			)
			(primitives
				(gr_poly
					(pts
						(arc
							(start 0.3048 -0.2032)
							(mid 0.275042 -0.275042)
							(end 0.2032 -0.3048)
						)
						(arc
							(start -0.2032 -0.3048)
							(mid -0.275042 -0.275042)
							(end -0.3048 -0.2032)
						)
						(arc
							(start -0.3048 0.2032)
							(mid -0.275042 0.275042)
							(end -0.2032 0.3048)
						)
						(arc
							(start 0.2032 0.3048)
							(mid 0.275042 0.275042)
							(end 0.3048 0.2032)
						)
					)
					(width 0)
					(fill yes)
				)
			)
		)
		(pad "2" smd custom
			(at 0 0.4445)
			(size 0.1524 0.1524)
			(layers "F.Cu" "F.Mask" "F.Paste")
			(net "GND")
			(options
				(clearance outline)
				(anchor circle)
			)
			(primitives
				(gr_poly
					(pts
						(arc
							(start 0.3048 -0.2032)
							(mid 0.275042 -0.275042)
							(end 0.2032 -0.3048)
						)
						(arc
							(start -0.2032 -0.3048)
							(mid -0.275042 -0.275042)
							(end -0.3048 -0.2032)
						)
						(arc
							(start -0.3048 0.2032)
							(mid -0.275042 0.275042)
							(end -0.2032 0.3048)
						)
						(arc
							(start 0.2032 0.3048)
							(mid 0.275042 0.275042)
							(end 0.3048 0.2032)
						)
					)
					(width 0)
					(fill yes)
				)
			)
		)
	)
	(footprint ""
		(layer "F.Cu")
		(at 37.7698 -311.8104)
		(property "Reference" "Q19"
			(at 0 0 0)
			(layer "F.SilkS")
			(hide yes)
			(effects
				(font
					(size 1.27 1.27)
				)
			)
		)
		(property "Value" "2N7002A-7-GP"
			(at 0.127 -8.9662 0)
			(unlocked yes)
			(layer "F.Fab")
			(hide yes)
			(effects
				(font
					(size 1.016 1.016)
					(thickness 0.1524)
				)
			)
		)
		(property "Device Type" "SOT23DGS2D4H48"
			(at 0.127 -10.4902 0)
			(unlocked yes)
			(layer "F.Fab")
			(hide yes)
			(effects
				(font
					(size 1.016 1.016)
					(thickness 0.1524)
				)
			)
		)
		(duplicate_pad_numbers_are_jumpers no)
		(fp_line
			(start -1.651 -1.778)
			(end -1.651 1.778)
			(stroke
				(width 0.1524)
				(type default)
			)
			(layer "F.SilkS")
		)
		(fp_line
			(start -1.651 1.778)
			(end 1.651 1.778)
			(stroke
				(width 0.1524)
				(type default)
			)
			(layer "F.SilkS")
		)
		(fp_line
			(start 1.651 -1.778)
			(end -1.651 -1.778)
			(stroke
				(width 0.1524)
				(type default)
			)
			(layer "F.SilkS")
		)
		(fp_line
			(start 1.651 1.778)
			(end 1.651 -1.778)
			(stroke
				(width 0.1524)
				(type default)
			)
			(layer "F.SilkS")
		)
		(fp_poly
			(pts
				(xy -1.778 1.8796) (xy -1.778 -1.8796) (xy 1.778 -1.8796) (xy 1.778 1.8796)
			)
			(stroke
				(width 0)
				(type default)
			)
			(fill no)
			(layer "F.CrtYd")
		)
		(fp_poly
			(pts
				(xy -1.778 1.8796) (xy -1.778 -1.8796) (xy 1.778 -1.8796) (xy 1.778 1.8796)
			)
			(stroke
				(width 0)
				(type default)
			)
			(fill no)
			(layer "F.Fab")
		)
		(pad "D" smd custom
			(at 0 -0.9525)
			(size 0.1905 0.1905)
			(layers "F.Cu" "F.Mask" "F.Paste")
			(net "SW_SSD11_R")
			(options
				(clearance outline)
				(anchor circle)
			)
			(primitives
				(gr_poly
					(pts
						(arc
							(start -0.1778 0.5715)
							(mid -0.321484 0.511984)
							(end -0.381 0.3683)
						)
						(arc
							(start -0.381 -0.3683)
							(mid -0.321484 -0.511984)
							(end -0.1778 -0.5715)
						)
						(arc
							(start 0.1778 -0.5715)
							(mid 0.321484 -0.511984)
							(end 0.381 -0.3683)
						)
						(arc
							(start 0.381 0.3683)
							(mid 0.321484 0.511984)
							(end 0.1778 0.5715)
						)
					)
					(width 0)
					(fill yes)
				)
			)
		)
		(pad "G" smd custom
			(at -0.98425 0.9525)
			(size 0.1905 0.1905)
			(layers "F.Cu" "F.Mask" "F.Paste")
			(net "SSD11_PWREN")
			(options
				(clearance outline)
				(anchor circle)
			)
			(primitives
				(gr_poly
					(pts
						(arc
							(start -0.1778 0.5715)
							(mid -0.321484 0.511984)
							(end -0.381 0.3683)
						)
						(arc
							(start -0.381 -0.3683)
							(mid -0.321484 -0.511984)
							(end -0.1778 -0.5715)
						)
						(arc
							(start 0.1778 -0.5715)
							(mid 0.321484 -0.511984)
							(end 0.381 -0.3683)
						)
						(arc
							(start 0.381 0.3683)
							(mid 0.321484 0.511984)
							(end 0.1778 0.5715)
						)
					)
					(width 0)
					(fill yes)
				)
			)
		)
		(pad "S" smd custom
			(at 0.98425 0.9525)
			(size 0.1905 0.1905)
			(layers "F.Cu" "F.Mask" "F.Paste")
			(net "GND")
			(options
				(clearance outline)
				(anchor circle)
			)
			(primitives
				(gr_poly
					(pts
						(arc
							(start -0.1778 0.5715)
							(mid -0.321484 0.511984)
							(end -0.381 0.3683)
						)
						(arc
							(start -0.381 -0.3683)
							(mid -0.321484 -0.511984)
							(end -0.1778 -0.5715)
						)
						(arc
							(start 0.1778 -0.5715)
							(mid 0.321484 -0.511984)
							(end 0.381 -0.3683)
						)
						(arc
							(start 0.381 0.3683)
							(mid 0.321484 0.511984)
							(end 0.1778 0.5715)
						)
					)
					(width 0)
					(fill yes)
				)
			)
		)
	)
	(footprint ""
		(layer "F.Cu")
		(at 228.2952 -449.834 180)
		(property "Reference" "SR1122"
			(at 0 0 180)
			(layer "F.SilkS")
			(hide yes)
			(effects
				(font
					(size 1.27 1.27)
				)
			)
		)
		(property "Value" "4K7R2J-2-GP"
			(at 0.064008 -3.993896 180)
			(unlocked yes)
			(layer "F.Fab")
			(hide yes)
			(effects
				(font
					(size 1.016 1.016)
					(thickness 0.1524)
				)
			)
		)
		(property "Device Type" "R402H16"
			(at 0.064008 -5.517896 180)
			(unlocked yes)
			(layer "F.Fab")
			(hide yes)
			(effects
				(font
					(size 1.016 1.016)
					(thickness 0.1524)
				)
			)
		)
		(duplicate_pad_numbers_are_jumpers no)
		(fp_line
			(start 0.508 -0.9398)
			(end -0.508 -0.9398)
			(stroke
				(width 0.1524)
				(type default)
			)
			(layer "F.SilkS")
		)
		(fp_line
			(start -0.508 -0.9398)
			(end -0.508 0.9398)
			(stroke
				(width 0.1524)
				(type default)
			)
			(layer "F.SilkS")
		)
		(fp_rect
			(start -0.508 0.9398)
			(end 0.508 -0.9398)
			(stroke
				(width 0)
				(type default)
			)
			(fill no)
			(layer "F.CrtYd")
		)
		(fp_rect
			(start -0.508 0.9398)
			(end 0.508 -0.9398)
			(stroke
				(width 0)
				(type default)
			)
			(fill no)
			(layer "F.Fab")
		)
		(pad "1" smd custom
			(at 0 -0.4445 180)
			(size 0.1397 0.1397)
			(layers "F.Cu" "F.Mask" "F.Paste")
			(net "P3V3")
			(options
				(clearance outline)
				(anchor circle)
			)
			(primitives
				(gr_poly
					(pts
						(arc
							(start -0.1778 -0.2794)
							(mid -0.249642 -0.249642)
							(end -0.2794 -0.1778)
						)
						(arc
							(start -0.2794 0.1778)
							(mid -0.249642 0.249642)
							(end -0.1778 0.2794)
						)
						(arc
							(start 0.1778 0.2794)
							(mid 0.249642 0.249642)
							(end 0.2794 0.1778)
						)
						(arc
							(start 0.2794 -0.1778)
							(mid 0.249642 -0.249642)
							(end 0.1778 -0.2794)
						)
					)
					(width 0)
					(fill yes)
				)
			)
		)
		(pad "2" smd custom
			(at 0 0.4445 180)
			(size 0.1397 0.1397)
			(layers "F.Cu" "F.Mask" "F.Paste")
			(net "SSD_ACT_DR0")
			(options
				(clearance outline)
				(anchor circle)
			)
			(primitives
				(gr_poly
					(pts
						(arc
							(start -0.1778 -0.2794)
							(mid -0.249642 -0.249642)
							(end -0.2794 -0.1778)
						)
						(arc
							(start -0.2794 0.1778)
							(mid -0.249642 0.249642)
							(end -0.1778 0.2794)
						)
						(arc
							(start 0.1778 0.2794)
							(mid 0.249642 0.249642)
							(end 0.2794 0.1778)
						)
						(arc
							(start 0.2794 -0.1778)
							(mid 0.249642 -0.249642)
							(end 0.1778 -0.2794)
						)
					)
					(width 0)
					(fill yes)
				)
			)
		)
	)
	(footprint ""
		(layer "F.Cu")
		(at 93.98 -305.181 90)
		(property "Reference" "EU2"
			(at 0 0 90)
			(layer "F.SilkS")
			(hide yes)
			(effects
				(font
					(size 1.27 1.27)
				)
			)
		)
		(property "Value" "9ZXL1231AKLFT-GP"
			(at -6.5278 -7.2009 90)
			(unlocked yes)
			(layer "F.Fab")
			(hide yes)
			(effects
				(font
					(size 1.016 1.016)
					(thickness 0.1524)
				)
			)
		)
		(property "Device Type" "QFN64G9-G6D25H40"
			(at -6.5278 -8.7249 90)
			(unlocked yes)
			(layer "F.Fab")
			(hide yes)
			(effects
				(font
					(size 1.016 1.016)
					(thickness 0.1524)
				)
			)
		)
		(duplicate_pad_numbers_are_jumpers no)
		(fp_line
			(start 1.7526 -5.71881)
			(end 1.7526 -5.21081)
			(stroke
				(width 0.1524)
				(type default)
			)
			(layer "F.SilkS")
		)
		(fp_line
			(start -3.2639 -5.71881)
			(end -3.2639 -5.21081)
			(stroke
				(width 0.1524)
				(type default)
			)
			(layer "F.SilkS")
		)
		(fp_line
			(start -3.9878 -5.5118)
			(end -5.5118 -5.5118)
			(stroke
				(width 0.1524)
				(type default)
			)
			(layer "F.SilkS")
		)
		(fp_line
			(start -5.5118 -5.5118)
			(end -5.5118 -3.9243)
			(stroke
				(width 0.1524)
				(type default)
			)
			(layer "F.SilkS")
		)
		(fp_line
			(start -0.74041 -5.21081)
			(end -0.74041 -5.97281)
			(stroke
				(width 0.1524)
				(type default)
			)
			(layer "F.SilkS")
		)
		(fp_line
			(start -5.97281 -2.2606)
			(end -5.21081 -2.2606)
			(stroke
				(width 0.1524)
				(type default)
			)
			(layer "F.SilkS")
		)
		(fp_line
			(start 5.21081 -1.778)
			(end 5.97281 -1.778)
			(stroke
				(width 0.1524)
				(type default)
			)
			(layer "F.SilkS")
		)
		(fp_line
			(start -5.21081 0.254)
			(end -5.71881 0.254)
			(stroke
				(width 0.1524)
				(type default)
			)
			(layer "F.SilkS")
		)
		(fp_line
			(start 5.71881 0.7112)
			(end 5.21081 0.7112)
			(stroke
				(width 0.1524)
				(type default)
			)
			(layer "F.SilkS")
		)
		(fp_line
			(start -5.97281 2.7432)
			(end -5.21081 2.7432)
			(stroke
				(width 0.1524)
				(type default)
			)
			(layer "F.SilkS")
		)
		(fp_line
			(start 5.21081 3.22961)
			(end 5.97281 3.22961)
			(stroke
				(width 0.1524)
				(type default)
			)
			(layer "F.SilkS")
		)
		(fp_line
			(start -5.4991 4.1148)
			(end -5.4991 5.5118)
			(stroke
				(width 0.1524)
				(type default)
			)
			(layer "F.SilkS")
		)
		(fp_line
			(start 2.2352 5.21081)
			(end 2.2352 5.71881)
			(stroke
				(width 0.1524)
				(type default)
			)
			(layer "F.SilkS")
		)
		(fp_line
			(start -2.7432 5.21081)
			(end -2.7432 5.71881)
			(stroke
				(width 0.1524)
				(type default)
			)
			(layer "F.SilkS")
		)
		(fp_line
			(start 5.5118 5.4991)
			(end 5.5118 3.9878)
			(stroke
				(width 0.1524)
				(type default)
			)
			(layer "F.SilkS")
		)
		(fp_line
			(start 4.0767 5.4991)
			(end 5.5118 5.4991)
			(stroke
				(width 0.1524)
				(type default)
			)
			(layer "F.SilkS")
		)
		(fp_line
			(start -5.4991 5.5118)
			(end -4.2037 5.5118)
			(stroke
				(width 0.1524)
				(type default)
			)
			(layer "F.SilkS")
		)
		(fp_line
			(start -0.7366 5.97281)
			(end -0.7366 5.21081)
			(stroke
				(width 0.1524)
				(type default)
			)
			(layer "F.SilkS")
		)
		(fp_poly
			(pts
				(xy 5.405628 -4.161028) (xy 4.05511 -5.5118) (xy 5.405628 -5.5118)
			)
			(stroke
				(width 0)
				(type default)
			)
			(fill yes)
			(layer "F.SilkS")
		)
		(fp_rect
			(start -4.4958 4.4958)
			(end 4.4958 -4.4958)
			(stroke
				(width 0)
				(type default)
			)
			(fill no)
			(layer "F.CrtYd")
		)
		(fp_poly
			(pts
				(xy -5.5118 5.5118) (xy -5.5118 -5.5118) (xy 5.5118 -5.5118) (xy 5.5118 -0.5461) (xy 4.4958 -0.5461)
				(xy 4.4958 -4.4958) (xy -4.4958 -4.4958) (xy -4.4958 4.4958) (xy 4.4958 4.4958) (xy 4.4958 -0.5334)
				(xy 5.5118 -0.5334) (xy 5.5118 5.5118)
			)
			(stroke
				(width 0)
				(type default)
			)
			(fill no)
			(layer "F.CrtYd")
		)
		(fp_rect
			(start -5.5118 5.5118)
			(end 5.5118 -5.5118)
			(stroke
				(width 0)
				(type default)
			)
			(fill no)
			(layer "F.Fab")
		)
		(pad "1" smd rect
			(at 3.75031 -4.550918 90)
			(size 0.3048 0.9144)
			(layers "F.Cu" "F.Mask" "F.Paste")
			(net "VDDA_2")
		)
		(pad "2" smd rect
			(at 3.24993 -4.42341 90)
			(size 0.3048 1.1684)
			(layers "F.Cu" "F.Mask" "F.Paste")
			(net "GND")
		)
		(pad "3" smd rect
			(at 2.74955 -4.42341 90)
			(size 0.3048 1.1684)
			(layers "F.Cu" "F.Mask" "F.Paste")
			(net "Net_1329")
		)
		(pad "4" smd rect
			(at 2.25044 -4.42341 90)
			(size 0.3048 1.1684)
			(layers "F.Cu" "F.Mask" "F.Paste")
			(net "CLK_BUF_EU2_100M_133M#")
		)
		(pad "5" smd rect
			(at 1.75006 -4.42341 90)
			(size 0.3048 1.1684)
			(layers "F.Cu" "F.Mask" "F.Paste")
			(net "CLK_BUF_EU2_HIBW_BYPM_LOBW#")
		)
		(pad "6" smd rect
			(at 1.24968 -4.42341 90)
			(size 0.3048 1.1684)
			(layers "F.Cu" "F.Mask" "F.Paste")
			(net "P3V3_PG")
		)
		(pad "7" smd rect
			(at 0.75057 -4.42341 90)
			(size 0.3048 1.1684)
			(layers "F.Cu" "F.Mask" "F.Paste")
			(net "GND")
		)
		(pad "8" smd rect
			(at 0.25019 -4.42341 90)
			(size 0.3048 1.1684)
			(layers "F.Cu" "F.Mask" "F.Paste")
			(net "VDDR_2")
		)
		(pad "9" smd rect
			(at -0.25019 -4.42341 90)
			(size 0.3048 1.1684)
			(layers "F.Cu" "F.Mask" "F.Paste")
			(net "PE_100M_CLK3_P")
		)
		(pad "10" smd rect
			(at -0.75057 -4.42341 90)
			(size 0.3048 1.1684)
			(layers "F.Cu" "F.Mask" "F.Paste")
			(net "PE_100M_CLK3_N")
		)
		(pad "11" smd rect
			(at -1.24968 -4.42341 90)
			(size 0.3048 1.1684)
			(layers "F.Cu" "F.Mask" "F.Paste")
			(net "CLK_BUF_EU2_SMB_A0_TRI")
		)
		(pad "12" smd rect
			(at -1.75006 -4.42341 90)
			(size 0.3048 1.1684)
			(layers "F.Cu" "F.Mask" "F.Paste")
			(net "I2C_SDA_BUF_9_EU2_R")
		)
		(pad "13" smd rect
			(at -2.25044 -4.42341 90)
			(size 0.3048 1.1684)
			(layers "F.Cu" "F.Mask" "F.Paste")
			(net "I2C_SCL_BUF_9_EU2_R")
		)
		(pad "14" smd rect
			(at -2.74955 -4.42341 90)
			(size 0.3048 1.1684)
			(layers "F.Cu" "F.Mask" "F.Paste")
			(net "CLK_BUF_EU2_SMB_A1_TRI")
		)
		(pad "15" smd rect
			(at -3.24993 -4.42341 90)
			(size 0.3048 1.1684)
			(layers "F.Cu" "F.Mask" "F.Paste")
			(net "Net_1331")
		)
		(pad "16" smd rect
			(at -3.75031 -4.550918 90)
			(size 0.3048 0.9144)
			(layers "F.Cu" "F.Mask" "F.Paste")
			(net "Net_1330")
		)
		(pad "17" smd rect
			(at -4.550918 -3.75031 90)
			(size 0.9144 0.3048)
			(layers "F.Cu" "F.Mask" "F.Paste")
			(net "Net_315")
		)
		(pad "18" smd rect
			(at -4.42341 -3.24993 90)
			(size 1.1684 0.3048)
			(layers "F.Cu" "F.Mask" "F.Paste")
			(net "Net_314")
		)
		(pad "19" smd rect
			(at -4.42341 -2.74955 90)
			(size 1.1684 0.3048)
			(layers "F.Cu" "F.Mask" "F.Paste")
			(net "CLK_BUFFER_EU2_VOE_N")
		)
		(pad "20" smd rect
			(at -4.42341 -2.25044 90)
			(size 1.1684 0.3048)
			(layers "F.Cu" "F.Mask" "F.Paste")
			(net "CLK_BUFFER_EU2_VOE_N")
		)
		(pad "21" smd rect
			(at -4.42341 -1.75006 90)
			(size 1.1684 0.3048)
			(layers "F.Cu" "F.Mask" "F.Paste")
			(net "Net_313")
		)
		(pad "22" smd rect
			(at -4.42341 -1.24968 90)
			(size 1.1684 0.3048)
			(layers "F.Cu" "F.Mask" "F.Paste")
			(net "Net_312")
		)
		(pad "23" smd rect
			(at -4.42341 -0.75057 90)
			(size 1.1684 0.3048)
			(layers "F.Cu" "F.Mask" "F.Paste")
			(net "GND")
		)
		(pad "24" smd rect
			(at -4.42341 -0.25019 90)
			(size 1.1684 0.3048)
			(layers "F.Cu" "F.Mask" "F.Paste")
			(net "VDD_DIFF_2")
		)
		(pad "25" smd rect
			(at -4.42341 0.25019 90)
			(size 1.1684 0.3048)
			(layers "F.Cu" "F.Mask" "F.Paste")
			(net "VDD_IO_2")
		)
		(pad "26" smd rect
			(at -4.42341 0.75057 90)
			(size 1.1684 0.3048)
			(layers "F.Cu" "F.Mask" "F.Paste")
			(net "PE_CLK_100M_DR2_2_R_P")
		)
		(pad "27" smd rect
			(at -4.42341 1.24968 90)
			(size 1.1684 0.3048)
			(layers "F.Cu" "F.Mask" "F.Paste")
			(net "PE_CLK_100M_DR2_2_R_N")
		)
		(pad "28" smd rect
			(at -4.42341 1.75006 90)
			(size 1.1684 0.3048)
			(layers "F.Cu" "F.Mask" "F.Paste")
			(net "SSD_PRSNT2")
		)
		(pad "29" smd rect
			(at -4.42341 2.25044 90)
			(size 1.1684 0.3048)
			(layers "F.Cu" "F.Mask" "F.Paste")
			(net "SSD2_CLK0_OE_R_N")
		)
		(pad "30" smd rect
			(at -4.42341 2.74955 90)
			(size 1.1684 0.3048)
			(layers "F.Cu" "F.Mask" "F.Paste")
			(net "PE_CLK_100M_DR2_1_R_P")
		)
		(pad "31" smd rect
			(at -4.42341 3.24993 90)
			(size 1.1684 0.3048)
			(layers "F.Cu" "F.Mask" "F.Paste")
			(net "PE_CLK_100M_DR2_1_R_N")
		)
		(pad "32" smd rect
			(at -4.550918 3.75031 90)
			(size 0.9144 0.3048)
			(layers "F.Cu" "F.Mask" "F.Paste")
			(net "VDD_IO_2")
		)
		(pad "33" smd rect
			(at -3.75031 4.550918 90)
			(size 0.3048 0.9144)
			(layers "F.Cu" "F.Mask" "F.Paste")
			(net "GND")
		)
		(pad "34" smd rect
			(at -3.24993 4.42341 90)
			(size 0.3048 1.1684)
			(layers "F.Cu" "F.Mask" "F.Paste")
			(net "Net_327")
		)
		(pad "35" smd rect
			(at -2.74955 4.42341 90)
			(size 0.3048 1.1684)
			(layers "F.Cu" "F.Mask" "F.Paste")
			(net "Net_326")
		)
		(pad "36" smd rect
			(at -2.25044 4.42341 90)
			(size 0.3048 1.1684)
			(layers "F.Cu" "F.Mask" "F.Paste")
			(net "CLK_BUFFER_EU2_VOE_N")
		)
		(pad "37" smd rect
			(at -1.75006 4.42341 90)
			(size 0.3048 1.1684)
			(layers "F.Cu" "F.Mask" "F.Paste")
			(net "CLK_BUFFER_EU2_VOE_N")
		)
		(pad "38" smd rect
			(at -1.24968 4.42341 90)
			(size 0.3048 1.1684)
			(layers "F.Cu" "F.Mask" "F.Paste")
			(net "Net_325")
		)
		(pad "39" smd rect
			(at -0.75057 4.42341 90)
			(size 0.3048 1.1684)
			(layers "F.Cu" "F.Mask" "F.Paste")
			(net "Net_324")
		)
		(pad "40" smd rect
			(at -0.25019 4.42341 90)
			(size 0.3048 1.1684)
			(layers "F.Cu" "F.Mask" "F.Paste")
			(net "VDD_DIFF_2")
		)
		(pad "41" smd rect
			(at 0.25019 4.42341 90)
			(size 0.3048 1.1684)
			(layers "F.Cu" "F.Mask" "F.Paste")
			(net "GND")
		)
		(pad "42" smd rect
			(at 0.75057 4.42341 90)
			(size 0.3048 1.1684)
			(layers "F.Cu" "F.Mask" "F.Paste")
			(net "PE_CLK_100M_DR1_2_R_P")
		)
		(pad "43" smd rect
			(at 1.24968 4.42341 90)
			(size 0.3048 1.1684)
			(layers "F.Cu" "F.Mask" "F.Paste")
			(net "PE_CLK_100M_DR1_2_R_N")
		)
		(pad "44" smd rect
			(at 1.75006 4.42341 90)
			(size 0.3048 1.1684)
			(layers "F.Cu" "F.Mask" "F.Paste")
			(net "SSD_PRSNT1")
		)
		(pad "45" smd rect
			(at 2.25044 4.42341 90)
			(size 0.3048 1.1684)
			(layers "F.Cu" "F.Mask" "F.Paste")
			(net "SSD1_CLK0_OE_R_N")
		)
		(pad "46" smd rect
			(at 2.74955 4.42341 90)
			(size 0.3048 1.1684)
			(layers "F.Cu" "F.Mask" "F.Paste")
			(net "PE_CLK_100M_DR1_1_R_P")
		)
		(pad "47" smd rect
			(at 3.24993 4.42341 90)
			(size 0.3048 1.1684)
			(layers "F.Cu" "F.Mask" "F.Paste")
			(net "PE_CLK_100M_DR1_1_R_N")
		)
		(pad "48" smd rect
			(at 3.75031 4.550918 90)
			(size 0.3048 0.9144)
			(layers "F.Cu" "F.Mask" "F.Paste")
			(net "GND")
		)
		(pad "49" smd rect
			(at 4.550918 3.75031 90)
			(size 0.9144 0.3048)
			(layers "F.Cu" "F.Mask" "F.Paste")
			(net "VDD_IO_2")
		)
		(pad "50" smd rect
			(at 4.42341 3.24993 90)
			(size 1.1684 0.3048)
			(layers "F.Cu" "F.Mask" "F.Paste")
			(net "PE_CLK_100M_DR6_2_R_P")
		)
		(pad "51" smd rect
			(at 4.42341 2.74955 90)
			(size 1.1684 0.3048)
			(layers "F.Cu" "F.Mask" "F.Paste")
			(net "PE_CLK_100M_DR6_2_R_N")
		)
		(pad "52" smd rect
			(at 4.42341 2.25044 90)
			(size 1.1684 0.3048)
			(layers "F.Cu" "F.Mask" "F.Paste")
			(net "SSD_PRSNT6")
		)
		(pad "53" smd rect
			(at 4.42341 1.75006 90)
			(size 1.1684 0.3048)
			(layers "F.Cu" "F.Mask" "F.Paste")
			(net "SSD6_CLK0_OE_R_N")
		)
		(pad "54" smd rect
			(at 4.42341 1.24968 90)
			(size 1.1684 0.3048)
			(layers "F.Cu" "F.Mask" "F.Paste")
			(net "PE_CLK_100M_DR6_1_R_P")
		)
		(pad "55" smd rect
			(at 4.42341 0.75057 90)
			(size 1.1684 0.3048)
			(layers "F.Cu" "F.Mask" "F.Paste")
			(net "PE_CLK_100M_DR6_1_R_N")
		)
		(pad "56" smd rect
			(at 4.42341 0.25019 90)
			(size 1.1684 0.3048)
			(layers "F.Cu" "F.Mask" "F.Paste")
			(net "VDD_IO_2")
		)
		(pad "57" smd rect
			(at 4.42341 -0.25019 90)
			(size 1.1684 0.3048)
			(layers "F.Cu" "F.Mask" "F.Paste")
			(net "VDD_DIFF_2")
		)
		(pad "58" smd rect
			(at 4.42341 -0.75057 90)
			(size 1.1684 0.3048)
			(layers "F.Cu" "F.Mask" "F.Paste")
			(net "GND")
		)
		(pad "59" smd rect
			(at 4.42341 -1.24968 90)
			(size 1.1684 0.3048)
			(layers "F.Cu" "F.Mask" "F.Paste")
			(net "PE_CLK_100M_DR11_2_R_P")
		)
		(pad "60" smd rect
			(at 4.42341 -1.75006 90)
			(size 1.1684 0.3048)
			(layers "F.Cu" "F.Mask" "F.Paste")
			(net "PE_CLK_100M_DR11_2_R_N")
		)
		(pad "61" smd rect
			(at 4.42341 -2.25044 90)
			(size 1.1684 0.3048)
			(layers "F.Cu" "F.Mask" "F.Paste")
			(net "SSD_PRSNT11")
		)
		(pad "62" smd rect
			(at 4.42341 -2.74955 90)
			(size 1.1684 0.3048)
			(layers "F.Cu" "F.Mask" "F.Paste")
			(net "SSD11_CLK0_OE_R_N")
		)
		(pad "63" smd rect
			(at 4.42341 -3.24993 90)
			(size 1.1684 0.3048)
			(layers "F.Cu" "F.Mask" "F.Paste")
			(net "PE_CLK_100M_DR11_1_R_P")
		)
		(pad "64" smd rect
			(at 4.550918 -3.75031 90)
			(size 0.9144 0.3048)
			(layers "F.Cu" "F.Mask" "F.Paste")
			(net "PE_CLK_100M_DR11_1_R_N")
		)
		(pad "65" smd rect
			(at 0 0 90)
			(size 6.2484 6.2484)
			(layers "F.Cu" "F.Mask" "F.Paste")
			(net "GND")
		)
	)
	(footprint ""
		(layer "F.Cu")
		(at 251.587 -360.553)
		(property "Reference" "PC1291"
			(at 0 0 0)
			(layer "F.SilkS")
			(hide yes)
			(effects
				(font
					(size 1.27 1.27)
				)
			)
		)
		(property "Value" "SCD1U25V3KX-GP"
			(at 0 -2.8194 0)
			(unlocked yes)
			(layer "F.Fab")
			(hide yes)
			(effects
				(font
					(size 1.016 1.016)
					(thickness 0.1524)
				)
			)
		)
		(property "Device Type" "C603H36"
			(at 0 -4.3434 0)
			(unlocked yes)
			(layer "F.Fab")
			(hide yes)
			(effects
				(font
					(size 1.016 1.016)
					(thickness 0.1524)
				)
			)
		)
		(duplicate_pad_numbers_are_jumpers no)
		(fp_line
			(start 0.508 0)
			(end -0.508 0)
			(stroke
				(width 0.2032)
				(type default)
			)
			(layer "F.SilkS")
		)
		(fp_rect
			(start -0.5842 1.3335)
			(end 0.5842 -1.3335)
			(stroke
				(width 0)
				(type default)
			)
			(fill no)
			(layer "F.CrtYd")
		)
		(fp_rect
			(start -0.5842 1.3335)
			(end 0.5842 -1.3335)
			(stroke
				(width 0)
				(type default)
			)
			(fill no)
			(layer "F.Fab")
		)
		(pad "1" smd custom
			(at 0 -0.762)
			(size 0.2159 0.2159)
			(layers "F.Cu" "F.Mask" "F.Paste")
			(net "P12V")
			(options
				(clearance outline)
				(anchor circle)
			)
			(primitives
				(gr_poly
					(pts
						(arc
							(start -0.3302 -0.4318)
							(mid -0.402042 -0.402042)
							(end -0.4318 -0.3302)
						)
						(arc
							(start -0.4318 0.3302)
							(mid -0.402042 0.402042)
							(end -0.3302 0.4318)
						)
						(arc
							(start 0.3302 0.4318)
							(mid 0.402042 0.402042)
							(end 0.4318 0.3302)
						)
						(arc
							(start 0.4318 -0.3302)
							(mid 0.402042 -0.402042)
							(end 0.3302 -0.4318)
						)
					)
					(width 0)
					(fill yes)
				)
			)
		)
		(pad "2" smd custom
			(at 0 0.762)
			(size 0.2159 0.2159)
			(layers "F.Cu" "F.Mask" "F.Paste")
			(net "GND")
			(options
				(clearance outline)
				(anchor circle)
			)
			(primitives
				(gr_poly
					(pts
						(arc
							(start -0.3302 -0.4318)
							(mid -0.402042 -0.402042)
							(end -0.4318 -0.3302)
						)
						(arc
							(start -0.4318 0.3302)
							(mid -0.402042 0.402042)
							(end -0.3302 0.4318)
						)
						(arc
							(start 0.3302 0.4318)
							(mid 0.402042 0.402042)
							(end 0.4318 0.3302)
						)
						(arc
							(start 0.4318 -0.3302)
							(mid 0.402042 -0.402042)
							(end 0.3302 -0.4318)
						)
					)
					(width 0)
					(fill yes)
				)
			)
		)
	)
	(footprint ""
		(layer "F.Cu")
		(at 233.807 -447.802 180)
		(property "Reference" "Q29"
			(at 0 0 180)
			(layer "F.SilkS")
			(hide yes)
			(effects
				(font
					(size 1.27 1.27)
				)
			)
		)
		(property "Value" "2N7002A-7-GP"
			(at 0.127 -8.9662 180)
			(unlocked yes)
			(layer "F.Fab")
			(hide yes)
			(effects
				(font
					(size 1.016 1.016)
					(thickness 0.1524)
				)
			)
		)
		(property "Device Type" "SOT23DGS2D4H48"
			(at 0.127 -10.4902 180)
			(unlocked yes)
			(layer "F.Fab")
			(hide yes)
			(effects
				(font
					(size 1.016 1.016)
					(thickness 0.1524)
				)
			)
		)
		(duplicate_pad_numbers_are_jumpers no)
		(fp_line
			(start 1.651 1.778)
			(end 1.651 -1.778)
			(stroke
				(width 0.1524)
				(type default)
			)
			(layer "F.SilkS")
		)
		(fp_line
			(start 1.651 -1.778)
			(end -1.651 -1.778)
			(stroke
				(width 0.1524)
				(type default)
			)
			(layer "F.SilkS")
		)
		(fp_line
			(start -1.651 1.778)
			(end 1.651 1.778)
			(stroke
				(width 0.1524)
				(type default)
			)
			(layer "F.SilkS")
		)
		(fp_line
			(start -1.651 -1.778)
			(end -1.651 1.778)
			(stroke
				(width 0.1524)
				(type default)
			)
			(layer "F.SilkS")
		)
		(fp_poly
			(pts
				(xy -1.778 1.8796) (xy -1.778 -1.8796) (xy 1.778 -1.8796) (xy 1.778 1.8796)
			)
			(stroke
				(width 0)
				(type default)
			)
			(fill no)
			(layer "F.CrtYd")
		)
		(fp_poly
			(pts
				(xy -1.778 1.8796) (xy -1.778 -1.8796) (xy 1.778 -1.8796) (xy 1.778 1.8796)
			)
			(stroke
				(width 0)
				(type default)
			)
			(fill no)
			(layer "F.Fab")
		)
		(pad "D" smd custom
			(at 0 -0.9525 180)
			(size 0.1905 0.1905)
			(layers "F.Cu" "F.Mask" "F.Paste")
			(net "SSD_ACT_DR0_MOS_N")
			(options
				(clearance outline)
				(anchor circle)
			)
			(primitives
				(gr_poly
					(pts
						(arc
							(start -0.1778 0.5715)
							(mid -0.321484 0.511984)
							(end -0.381 0.3683)
						)
						(arc
							(start -0.381 -0.3683)
							(mid -0.321484 -0.511984)
							(end -0.1778 -0.5715)
						)
						(arc
							(start 0.1778 -0.5715)
							(mid 0.321484 -0.511984)
							(end 0.381 -0.3683)
						)
						(arc
							(start 0.381 0.3683)
							(mid 0.321484 0.511984)
							(end 0.1778 0.5715)
						)
					)
					(width 0)
					(fill yes)
				)
			)
		)
		(pad "G" smd custom
			(at -0.98425 0.9525 180)
			(size 0.1905 0.1905)
			(layers "F.Cu" "F.Mask" "F.Paste")
			(net "ATTN_LED_DR0_AND_R")
			(options
				(clearance outline)
				(anchor circle)
			)
			(primitives
				(gr_poly
					(pts
						(arc
							(start -0.1778 0.5715)
							(mid -0.321484 0.511984)
							(end -0.381 0.3683)
						)
						(arc
							(start -0.381 -0.3683)
							(mid -0.321484 -0.511984)
							(end -0.1778 -0.5715)
						)
						(arc
							(start 0.1778 -0.5715)
							(mid 0.321484 -0.511984)
							(end 0.381 -0.3683)
						)
						(arc
							(start 0.381 0.3683)
							(mid 0.321484 0.511984)
							(end 0.1778 0.5715)
						)
					)
					(width 0)
					(fill yes)
				)
			)
		)
		(pad "S" smd custom
			(at 0.98425 0.9525 180)
			(size 0.1905 0.1905)
			(layers "F.Cu" "F.Mask" "F.Paste")
			(net "SSD_ACT_DR0_R")
			(options
				(clearance outline)
				(anchor circle)
			)
			(primitives
				(gr_poly
					(pts
						(arc
							(start -0.1778 0.5715)
							(mid -0.321484 0.511984)
							(end -0.381 0.3683)
						)
						(arc
							(start -0.381 -0.3683)
							(mid -0.321484 -0.511984)
							(end -0.1778 -0.5715)
						)
						(arc
							(start 0.1778 -0.5715)
							(mid 0.321484 -0.511984)
							(end 0.381 -0.3683)
						)
						(arc
							(start 0.381 0.3683)
							(mid 0.321484 0.511984)
							(end 0.1778 0.5715)
						)
					)
					(width 0)
					(fill yes)
				)
			)
		)
	)
	(footprint ""
		(layer "F.Cu")
		(at 92.837 -203.708)
		(property "Reference" "C8864"
			(at 0 0 0)
			(layer "F.SilkS")
			(hide yes)
			(effects
				(font
					(size 1.27 1.27)
				)
			)
		)
		(property "Value" "SCD1U16V2KX-3GP"
			(at 1.1811 -2.7051 0)
			(unlocked yes)
			(layer "F.Fab")
			(hide yes)
			(effects
				(font
					(size 1.016 1.016)
					(thickness 0.1524)
				)
			)
		)
		(property "Device Type" "C402H22"
			(at 1.1811 -4.2291 0)
			(unlocked yes)
			(layer "F.Fab")
			(hide yes)
			(effects
				(font
					(size 1.016 1.016)
					(thickness 0.1524)
				)
			)
		)
		(duplicate_pad_numbers_are_jumpers no)
		(fp_rect
			(start -0.4318 0.9525)
			(end 0.4318 -0.9525)
			(stroke
				(width 0)
				(type default)
			)
			(fill no)
			(layer "F.CrtYd")
		)
		(fp_rect
			(start -0.4318 0.9525)
			(end 0.4318 -0.9525)
			(stroke
				(width 0)
				(type default)
			)
			(fill no)
			(layer "F.Fab")
		)
		(pad "1" smd custom
			(at 0 -0.4445)
			(size 0.1524 0.1524)
			(layers "F.Cu" "F.Mask" "F.Paste")
			(net "VDD_IO_3")
			(options
				(clearance outline)
				(anchor circle)
			)
			(primitives
				(gr_poly
					(pts
						(arc
							(start 0.3048 -0.2032)
							(mid 0.275042 -0.275042)
							(end 0.2032 -0.3048)
						)
						(arc
							(start -0.2032 -0.3048)
							(mid -0.275042 -0.275042)
							(end -0.3048 -0.2032)
						)
						(arc
							(start -0.3048 0.2032)
							(mid -0.275042 0.275042)
							(end -0.2032 0.3048)
						)
						(arc
							(start 0.2032 0.3048)
							(mid 0.275042 0.275042)
							(end 0.3048 0.2032)
						)
					)
					(width 0)
					(fill yes)
				)
			)
		)
		(pad "2" smd custom
			(at 0 0.4445)
			(size 0.1524 0.1524)
			(layers "F.Cu" "F.Mask" "F.Paste")
			(net "GND")
			(options
				(clearance outline)
				(anchor circle)
			)
			(primitives
				(gr_poly
					(pts
						(arc
							(start 0.3048 -0.2032)
							(mid 0.275042 -0.275042)
							(end 0.2032 -0.3048)
						)
						(arc
							(start -0.2032 -0.3048)
							(mid -0.275042 -0.275042)
							(end -0.3048 -0.2032)
						)
						(arc
							(start -0.3048 0.2032)
							(mid -0.275042 0.275042)
							(end -0.2032 0.3048)
						)
						(arc
							(start 0.2032 0.3048)
							(mid 0.275042 0.275042)
							(end 0.3048 0.2032)
						)
					)
					(width 0)
					(fill yes)
				)
			)
		)
	)
	(footprint ""
		(layer "F.Cu")
		(at 234.061 -136.00811 90)
		(property "Reference" "R9801"
			(at 0 0 90)
			(layer "F.SilkS")
			(hide yes)
			(effects
				(font
					(size 1.27 1.27)
				)
			)
		)
		(property "Value" "0R2J-2-GP"
			(at 0.064008 -3.993896 90)
			(unlocked yes)
			(layer "F.Fab")
			(hide yes)
			(effects
				(font
					(size 1.016 1.016)
					(thickness 0.1524)
				)
			)
		)
		(property "Device Type" "R402H16"
			(at 0.064008 -5.517896 90)
			(unlocked yes)
			(layer "F.Fab")
			(hide yes)
			(effects
				(font
					(size 1.016 1.016)
					(thickness 0.1524)
				)
			)
		)
		(duplicate_pad_numbers_are_jumpers no)
		(fp_line
			(start 0.508 -0.9398)
			(end -0.508 -0.9398)
			(stroke
				(width 0.1524)
				(type default)
			)
			(layer "F.SilkS")
		)
		(fp_line
			(start -0.508 -0.9398)
			(end -0.508 0.9398)
			(stroke
				(width 0.1524)
				(type default)
			)
			(layer "F.SilkS")
		)
		(fp_rect
			(start -0.508 0.9398)
			(end 0.508 -0.9398)
			(stroke
				(width 0)
				(type default)
			)
			(fill no)
			(layer "F.CrtYd")
		)
		(fp_rect
			(start -0.508 0.9398)
			(end 0.508 -0.9398)
			(stroke
				(width 0)
				(type default)
			)
			(fill no)
			(layer "F.Fab")
		)
		(pad "1" smd custom
			(at 0 -0.4445 90)
			(size 0.1397 0.1397)
			(layers "F.Cu" "F.Mask" "F.Paste")
			(net "ATTN_LED_DR3_AND")
			(options
				(clearance outline)
				(anchor circle)
			)
			(primitives
				(gr_poly
					(pts
						(arc
							(start -0.1778 -0.2794)
							(mid -0.249642 -0.249642)
							(end -0.2794 -0.1778)
						)
						(arc
							(start -0.2794 0.1778)
							(mid -0.249642 0.249642)
							(end -0.1778 0.2794)
						)
						(arc
							(start 0.1778 0.2794)
							(mid 0.249642 0.249642)
							(end 0.2794 0.1778)
						)
						(arc
							(start 0.2794 -0.1778)
							(mid 0.249642 -0.249642)
							(end 0.1778 -0.2794)
						)
					)
					(width 0)
					(fill yes)
				)
			)
		)
		(pad "2" smd custom
			(at 0 0.4445 90)
			(size 0.1397 0.1397)
			(layers "F.Cu" "F.Mask" "F.Paste")
			(net "ATTN_LED_DR3_AND_R")
			(options
				(clearance outline)
				(anchor circle)
			)
			(primitives
				(gr_poly
					(pts
						(arc
							(start -0.1778 -0.2794)
							(mid -0.249642 -0.249642)
							(end -0.2794 -0.1778)
						)
						(arc
							(start -0.2794 0.1778)
							(mid -0.249642 0.249642)
							(end -0.1778 0.2794)
						)
						(arc
							(start 0.1778 0.2794)
							(mid 0.249642 0.249642)
							(end 0.2794 0.1778)
						)
						(arc
							(start 0.2794 -0.1778)
							(mid 0.249642 -0.249642)
							(end 0.1778 -0.2794)
						)
					)
					(width 0)
					(fill yes)
				)
			)
		)
	)
	(footprint ""
		(layer "F.Cu")
		(at 210.185 -439.674 180)
		(property "Reference" "PC1282"
			(at 0 0 180)
			(layer "F.SilkS")
			(hide yes)
			(effects
				(font
					(size 1.27 1.27)
				)
			)
		)
		(property "Value" "SC47U10V5MX-GP-U"
			(at -0.0762 -2.9972 180)
			(unlocked yes)
			(layer "F.Fab")
			(hide yes)
			(effects
				(font
					(size 1.016 1.016)
					(thickness 0.1524)
				)
			)
		)
		(property "Device Type" "C805H62"
			(at -0.0762 -4.5212 180)
			(unlocked yes)
			(layer "F.Fab")
			(hide yes)
			(effects
				(font
					(size 1.016 1.016)
					(thickness 0.1524)
				)
			)
		)
		(duplicate_pad_numbers_are_jumpers no)
		(fp_line
			(start 0.635 0)
			(end -0.635 0)
			(stroke
				(width 0.508)
				(type default)
			)
			(layer "F.SilkS")
		)
		(fp_rect
			(start -0.6223 1.0033)
			(end 0.6223 -1.0033)
			(stroke
				(width 0)
				(type default)
			)
			(fill no)
			(layer "F.CrtYd")
		)
		(fp_poly
			(pts
				(xy -0.9652 1.778) (xy -0.9652 -1.778) (xy 0.9652 -1.778) (xy 0.9652 0.39116) (xy 0.6223 0.39116)
				(xy 0.6223 -1.0033) (xy -0.6223 -1.0033) (xy -0.6223 1.0033) (xy 0.6223 1.0033) (xy 0.6223 0.3937)
				(xy 0.9652 0.3937) (xy 0.9652 1.778)
			)
			(stroke
				(width 0)
				(type default)
			)
			(fill no)
			(layer "F.CrtYd")
		)
		(fp_rect
			(start -0.9652 1.778)
			(end 0.9652 -1.778)
			(stroke
				(width 0)
				(type default)
			)
			(fill no)
			(layer "F.Fab")
		)
		(pad "1" smd rect
			(at 0 -0.9652 180)
			(size 1.397 1.143)
			(layers "F.Cu" "F.Mask" "F.Paste")
			(net "P3V3_OUT")
		)
		(pad "2" smd rect
			(at 0 0.9652 180)
			(size 1.397 1.143)
			(layers "F.Cu" "F.Mask" "F.Paste")
			(net "GND")
		)
	)
	(footprint ""
		(layer "F.Cu")
		(at 86.487 -110.236 180)
		(property "Reference" "R9060"
			(at 0 0 180)
			(layer "F.SilkS")
			(hide yes)
			(effects
				(font
					(size 1.27 1.27)
				)
			)
		)
		(property "Value" "27R2F-GP"
			(at 0.064008 -3.993896 180)
			(unlocked yes)
			(layer "F.Fab")
			(hide yes)
			(effects
				(font
					(size 1.016 1.016)
					(thickness 0.1524)
				)
			)
		)
		(property "Device Type" "R402H16"
			(at 0.064008 -5.517896 180)
			(unlocked yes)
			(layer "F.Fab")
			(hide yes)
			(effects
				(font
					(size 1.016 1.016)
					(thickness 0.1524)
				)
			)
		)
		(duplicate_pad_numbers_are_jumpers no)
		(fp_line
			(start 0.508 -0.9398)
			(end -0.508 -0.9398)
			(stroke
				(width 0.1524)
				(type default)
			)
			(layer "F.SilkS")
		)
		(fp_line
			(start -0.508 -0.9398)
			(end -0.508 0.9398)
			(stroke
				(width 0.1524)
				(type default)
			)
			(layer "F.SilkS")
		)
		(fp_rect
			(start -0.508 0.9398)
			(end 0.508 -0.9398)
			(stroke
				(width 0)
				(type default)
			)
			(fill no)
			(layer "F.CrtYd")
		)
		(fp_rect
			(start -0.508 0.9398)
			(end 0.508 -0.9398)
			(stroke
				(width 0)
				(type default)
			)
			(fill no)
			(layer "F.Fab")
		)
		(pad "1" smd custom
			(at 0 -0.4445 180)
			(size 0.1397 0.1397)
			(layers "F.Cu" "F.Mask" "F.Paste")
			(net "PE_CLK_100M_DR13_1_R_N")
			(options
				(clearance outline)
				(anchor circle)
			)
			(primitives
				(gr_poly
					(pts
						(arc
							(start -0.1778 -0.2794)
							(mid -0.249642 -0.249642)
							(end -0.2794 -0.1778)
						)
						(arc
							(start -0.2794 0.1778)
							(mid -0.249642 0.249642)
							(end -0.1778 0.2794)
						)
						(arc
							(start 0.1778 0.2794)
							(mid 0.249642 0.249642)
							(end 0.2794 0.1778)
						)
						(arc
							(start 0.2794 -0.1778)
							(mid 0.249642 -0.249642)
							(end 0.1778 -0.2794)
						)
					)
					(width 0)
					(fill yes)
				)
			)
		)
		(pad "2" smd custom
			(at 0 0.4445 180)
			(size 0.1397 0.1397)
			(layers "F.Cu" "F.Mask" "F.Paste")
			(net "PE_CLK100M_DR13_1_N")
			(options
				(clearance outline)
				(anchor circle)
			)
			(primitives
				(gr_poly
					(pts
						(arc
							(start -0.1778 -0.2794)
							(mid -0.249642 -0.249642)
							(end -0.2794 -0.1778)
						)
						(arc
							(start -0.2794 0.1778)
							(mid -0.249642 0.249642)
							(end -0.1778 0.2794)
						)
						(arc
							(start 0.1778 0.2794)
							(mid 0.249642 0.249642)
							(end 0.2794 0.1778)
						)
						(arc
							(start 0.2794 -0.1778)
							(mid 0.249642 -0.249642)
							(end 0.1778 -0.2794)
						)
					)
					(width 0)
					(fill yes)
				)
			)
		)
	)
	(footprint ""
		(layer "F.Cu")
		(at 86.614 -432.943 180)
		(property "Reference" "C8895"
			(at 0 0 180)
			(layer "F.SilkS")
			(hide yes)
			(effects
				(font
					(size 1.27 1.27)
				)
			)
		)
		(property "Value" "SC1U10V2KX-7-GP"
			(at 1.1811 -2.7051 180)
			(unlocked yes)
			(layer "F.Fab")
			(hide yes)
			(effects
				(font
					(size 1.016 1.016)
					(thickness 0.1524)
				)
			)
		)
		(property "Device Type" "C402H22"
			(at 1.1811 -4.2291 180)
			(unlocked yes)
			(layer "F.Fab")
			(hide yes)
			(effects
				(font
					(size 1.016 1.016)
					(thickness 0.1524)
				)
			)
		)
		(duplicate_pad_numbers_are_jumpers no)
		(fp_rect
			(start -0.4318 0.9525)
			(end 0.4318 -0.9525)
			(stroke
				(width 0)
				(type default)
			)
			(fill no)
			(layer "F.CrtYd")
		)
		(fp_rect
			(start -0.4318 0.9525)
			(end 0.4318 -0.9525)
			(stroke
				(width 0)
				(type default)
			)
			(fill no)
			(layer "F.Fab")
		)
		(pad "1" smd custom
			(at 0 -0.4445 180)
			(size 0.1524 0.1524)
			(layers "F.Cu" "F.Mask" "F.Paste")
			(net "VDDR_1")
			(options
				(clearance outline)
				(anchor circle)
			)
			(primitives
				(gr_poly
					(pts
						(arc
							(start 0.3048 -0.2032)
							(mid 0.275042 -0.275042)
							(end 0.2032 -0.3048)
						)
						(arc
							(start -0.2032 -0.3048)
							(mid -0.275042 -0.275042)
							(end -0.3048 -0.2032)
						)
						(arc
							(start -0.3048 0.2032)
							(mid -0.275042 0.275042)
							(end -0.2032 0.3048)
						)
						(arc
							(start 0.2032 0.3048)
							(mid 0.275042 0.275042)
							(end 0.3048 0.2032)
						)
					)
					(width 0)
					(fill yes)
				)
			)
		)
		(pad "2" smd custom
			(at 0 0.4445 180)
			(size 0.1524 0.1524)
			(layers "F.Cu" "F.Mask" "F.Paste")
			(net "GND")
			(options
				(clearance outline)
				(anchor circle)
			)
			(primitives
				(gr_poly
					(pts
						(arc
							(start 0.3048 -0.2032)
							(mid 0.275042 -0.275042)
							(end 0.2032 -0.3048)
						)
						(arc
							(start -0.2032 -0.3048)
							(mid -0.275042 -0.275042)
							(end -0.3048 -0.2032)
						)
						(arc
							(start -0.3048 0.2032)
							(mid -0.275042 0.275042)
							(end -0.2032 0.3048)
						)
						(arc
							(start 0.2032 0.3048)
							(mid 0.275042 0.275042)
							(end 0.3048 0.2032)
						)
					)
					(width 0)
					(fill yes)
				)
			)
		)
	)
	(footprint ""
		(layer "F.Cu")
		(at 91.186 -30.607 -90)
		(property "Reference" "C352"
			(at 0 0 270)
			(layer "F.SilkS")
			(hide yes)
			(effects
				(font
					(size 1.27 1.27)
				)
			)
		)
		(property "Value" "SCD1U16V2KX-3GP"
			(at 1.1811 -2.7051 270)
			(unlocked yes)
			(layer "F.Fab")
			(hide yes)
			(effects
				(font
					(size 1.016 1.016)
					(thickness 0.1524)
				)
			)
		)
		(property "Device Type" "C402H22"
			(at 1.1811 -4.2291 270)
			(unlocked yes)
			(layer "F.Fab")
			(hide yes)
			(effects
				(font
					(size 1.016 1.016)
					(thickness 0.1524)
				)
			)
		)
		(duplicate_pad_numbers_are_jumpers no)
		(fp_rect
			(start -0.4318 0.9525)
			(end 0.4318 -0.9525)
			(stroke
				(width 0)
				(type default)
			)
			(fill no)
			(layer "F.CrtYd")
		)
		(fp_rect
			(start -0.4318 0.9525)
			(end 0.4318 -0.9525)
			(stroke
				(width 0)
				(type default)
			)
			(fill no)
			(layer "F.Fab")
		)
		(pad "1" smd custom
			(at 0 -0.4445 270)
			(size 0.1524 0.1524)
			(layers "F.Cu" "F.Mask" "F.Paste")
			(net "P3V3")
			(options
				(clearance outline)
				(anchor circle)
			)
			(primitives
				(gr_poly
					(pts
						(arc
							(start 0.3048 -0.2032)
							(mid 0.275042 -0.275042)
							(end 0.2032 -0.3048)
						)
						(arc
							(start -0.2032 -0.3048)
							(mid -0.275042 -0.275042)
							(end -0.3048 -0.2032)
						)
						(arc
							(start -0.3048 0.2032)
							(mid -0.275042 0.275042)
							(end -0.2032 0.3048)
						)
						(arc
							(start 0.2032 0.3048)
							(mid 0.275042 0.275042)
							(end 0.3048 0.2032)
						)
					)
					(width 0)
					(fill yes)
				)
			)
		)
		(pad "2" smd custom
			(at 0 0.4445 270)
			(size 0.1524 0.1524)
			(layers "F.Cu" "F.Mask" "F.Paste")
			(net "GND")
			(options
				(clearance outline)
				(anchor circle)
			)
			(primitives
				(gr_poly
					(pts
						(arc
							(start 0.3048 -0.2032)
							(mid 0.275042 -0.275042)
							(end 0.2032 -0.3048)
						)
						(arc
							(start -0.2032 -0.3048)
							(mid -0.275042 -0.275042)
							(end -0.3048 -0.2032)
						)
						(arc
							(start -0.3048 0.2032)
							(mid -0.275042 0.275042)
							(end -0.2032 0.3048)
						)
						(arc
							(start 0.2032 0.3048)
							(mid 0.275042 0.275042)
							(end 0.3048 0.2032)
						)
					)
					(width 0)
					(fill yes)
				)
			)
		)
	)
	(footprint ""
		(layer "F.Cu")
		(at 213.3981 -300.5201 180)
		(property "Reference" "R9794"
			(at 0 0 180)
			(layer "F.SilkS")
			(hide yes)
			(effects
				(font
					(size 1.27 1.27)
				)
			)
		)
		(property "Value" "47KR2J-2-GP"
			(at 0.064008 -3.993896 180)
			(unlocked yes)
			(layer "F.Fab")
			(hide yes)
			(effects
				(font
					(size 1.016 1.016)
					(thickness 0.1524)
				)
			)
		)
		(property "Device Type" "R402H16"
			(at 0.064008 -5.517896 180)
			(unlocked yes)
			(layer "F.Fab")
			(hide yes)
			(effects
				(font
					(size 1.016 1.016)
					(thickness 0.1524)
				)
			)
		)
		(duplicate_pad_numbers_are_jumpers no)
		(fp_line
			(start 0.508 -0.9398)
			(end -0.508 -0.9398)
			(stroke
				(width 0.1524)
				(type default)
			)
			(layer "F.SilkS")
		)
		(fp_line
			(start -0.508 -0.9398)
			(end -0.508 0.9398)
			(stroke
				(width 0.1524)
				(type default)
			)
			(layer "F.SilkS")
		)
		(fp_rect
			(start -0.508 0.9398)
			(end 0.508 -0.9398)
			(stroke
				(width 0)
				(type default)
			)
			(fill no)
			(layer "F.CrtYd")
		)
		(fp_rect
			(start -0.508 0.9398)
			(end 0.508 -0.9398)
			(stroke
				(width 0)
				(type default)
			)
			(fill no)
			(layer "F.Fab")
		)
		(pad "1" smd custom
			(at 0 -0.4445 180)
			(size 0.1397 0.1397)
			(layers "F.Cu" "F.Mask" "F.Paste")
			(net "P12V")
			(options
				(clearance outline)
				(anchor circle)
			)
			(primitives
				(gr_poly
					(pts
						(arc
							(start -0.1778 -0.2794)
							(mid -0.249642 -0.249642)
							(end -0.2794 -0.1778)
						)
						(arc
							(start -0.2794 0.1778)
							(mid -0.249642 0.249642)
							(end -0.1778 0.2794)
						)
						(arc
							(start 0.1778 0.2794)
							(mid 0.249642 0.249642)
							(end 0.2794 0.1778)
						)
						(arc
							(start 0.2794 -0.1778)
							(mid 0.249642 -0.249642)
							(end 0.1778 -0.2794)
						)
					)
					(width 0)
					(fill yes)
				)
			)
		)
		(pad "2" smd custom
			(at 0 0.4445 180)
			(size 0.1397 0.1397)
			(layers "F.Cu" "F.Mask" "F.Paste")
			(net "P12V_MOST2_GATE")
			(options
				(clearance outline)
				(anchor circle)
			)
			(primitives
				(gr_poly
					(pts
						(arc
							(start -0.1778 -0.2794)
							(mid -0.249642 -0.249642)
							(end -0.2794 -0.1778)
						)
						(arc
							(start -0.2794 0.1778)
							(mid -0.249642 0.249642)
							(end -0.1778 0.2794)
						)
						(arc
							(start 0.1778 0.2794)
							(mid 0.249642 0.249642)
							(end 0.2794 0.1778)
						)
						(arc
							(start 0.2794 -0.1778)
							(mid 0.249642 -0.249642)
							(end 0.1778 -0.2794)
						)
					)
					(width 0)
					(fill yes)
				)
			)
		)
	)
	(footprint ""
		(layer "F.Cu")
		(at 31.877 -142.24)
		(property "Reference" "Q70"
			(at 0 0 0)
			(layer "F.SilkS")
			(hide yes)
			(effects
				(font
					(size 1.27 1.27)
				)
			)
		)
		(property "Value" "2N7002A-7-GP"
			(at 0.127 -8.9662 0)
			(unlocked yes)
			(layer "F.Fab")
			(hide yes)
			(effects
				(font
					(size 1.016 1.016)
					(thickness 0.1524)
				)
			)
		)
		(property "Device Type" "SOT23DGS2D4H48"
			(at 0.127 -10.4902 0)
			(unlocked yes)
			(layer "F.Fab")
			(hide yes)
			(effects
				(font
					(size 1.016 1.016)
					(thickness 0.1524)
				)
			)
		)
		(duplicate_pad_numbers_are_jumpers no)
		(fp_line
			(start -1.651 -1.778)
			(end -1.651 1.778)
			(stroke
				(width 0.1524)
				(type default)
			)
			(layer "F.SilkS")
		)
		(fp_line
			(start -1.651 1.778)
			(end 1.651 1.778)
			(stroke
				(width 0.1524)
				(type default)
			)
			(layer "F.SilkS")
		)
		(fp_line
			(start 1.651 -1.778)
			(end -1.651 -1.778)
			(stroke
				(width 0.1524)
				(type default)
			)
			(layer "F.SilkS")
		)
		(fp_line
			(start 1.651 1.778)
			(end 1.651 -1.778)
			(stroke
				(width 0.1524)
				(type default)
			)
			(layer "F.SilkS")
		)
		(fp_poly
			(pts
				(xy -1.778 1.8796) (xy -1.778 -1.8796) (xy 1.778 -1.8796) (xy 1.778 1.8796)
			)
			(stroke
				(width 0)
				(type default)
			)
			(fill no)
			(layer "F.CrtYd")
		)
		(fp_poly
			(pts
				(xy -1.778 1.8796) (xy -1.778 -1.8796) (xy 1.778 -1.8796) (xy 1.778 1.8796)
			)
			(stroke
				(width 0)
				(type default)
			)
			(fill no)
			(layer "F.Fab")
		)
		(pad "D" smd custom
			(at 0 -0.9525)
			(size 0.1905 0.1905)
			(layers "F.Cu" "F.Mask" "F.Paste")
			(net "ATTN_LED_DR8_MOS_N")
			(options
				(clearance outline)
				(anchor circle)
			)
			(primitives
				(gr_poly
					(pts
						(arc
							(start -0.1778 0.5715)
							(mid -0.321484 0.511984)
							(end -0.381 0.3683)
						)
						(arc
							(start -0.381 -0.3683)
							(mid -0.321484 -0.511984)
							(end -0.1778 -0.5715)
						)
						(arc
							(start 0.1778 -0.5715)
							(mid 0.321484 -0.511984)
							(end 0.381 -0.3683)
						)
						(arc
							(start 0.381 0.3683)
							(mid 0.321484 0.511984)
							(end 0.1778 0.5715)
						)
					)
					(width 0)
					(fill yes)
				)
			)
		)
		(pad "G" smd custom
			(at -0.98425 0.9525)
			(size 0.1905 0.1905)
			(layers "F.Cu" "F.Mask" "F.Paste")
			(net "SSD8_CLK0_OE_MOS_N")
			(options
				(clearance outline)
				(anchor circle)
			)
			(primitives
				(gr_poly
					(pts
						(arc
							(start -0.1778 0.5715)
							(mid -0.321484 0.511984)
							(end -0.381 0.3683)
						)
						(arc
							(start -0.381 -0.3683)
							(mid -0.321484 -0.511984)
							(end -0.1778 -0.5715)
						)
						(arc
							(start 0.1778 -0.5715)
							(mid 0.321484 -0.511984)
							(end 0.381 -0.3683)
						)
						(arc
							(start 0.381 0.3683)
							(mid 0.321484 0.511984)
							(end 0.1778 0.5715)
						)
					)
					(width 0)
					(fill yes)
				)
			)
		)
		(pad "S" smd custom
			(at 0.98425 0.9525)
			(size 0.1905 0.1905)
			(layers "F.Cu" "F.Mask" "F.Paste")
			(net "ATTN_LED_DR8_R")
			(options
				(clearance outline)
				(anchor circle)
			)
			(primitives
				(gr_poly
					(pts
						(arc
							(start -0.1778 0.5715)
							(mid -0.321484 0.511984)
							(end -0.381 0.3683)
						)
						(arc
							(start -0.381 -0.3683)
							(mid -0.321484 -0.511984)
							(end -0.1778 -0.5715)
						)
						(arc
							(start 0.1778 -0.5715)
							(mid 0.321484 -0.511984)
							(end 0.381 -0.3683)
						)
						(arc
							(start 0.381 0.3683)
							(mid 0.321484 0.511984)
							(end 0.1778 0.5715)
						)
					)
					(width 0)
					(fill yes)
				)
			)
		)
	)
	(footprint ""
		(layer "F.Cu")
		(at 228.009704 -145.903188 -90)
		(property "Reference" "R9933"
			(at 0 0 270)
			(layer "F.SilkS")
			(hide yes)
			(effects
				(font
					(size 1.27 1.27)
				)
			)
		)
		(property "Value" "4K7R2J-2-GP"
			(at 0.064008 -3.993896 270)
			(unlocked yes)
			(layer "F.Fab")
			(hide yes)
			(effects
				(font
					(size 1.016 1.016)
					(thickness 0.1524)
				)
			)
		)
		(property "Device Type" "R402H16"
			(at 0.064008 -5.517896 270)
			(unlocked yes)
			(layer "F.Fab")
			(hide yes)
			(effects
				(font
					(size 1.016 1.016)
					(thickness 0.1524)
				)
			)
		)
		(duplicate_pad_numbers_are_jumpers no)
		(fp_line
			(start -0.508 -0.9398)
			(end -0.508 0.9398)
			(stroke
				(width 0.1524)
				(type default)
			)
			(layer "F.SilkS")
		)
		(fp_line
			(start 0.508 -0.9398)
			(end -0.508 -0.9398)
			(stroke
				(width 0.1524)
				(type default)
			)
			(layer "F.SilkS")
		)
		(fp_rect
			(start -0.508 0.9398)
			(end 0.508 -0.9398)
			(stroke
				(width 0)
				(type default)
			)
			(fill no)
			(layer "F.CrtYd")
		)
		(fp_rect
			(start -0.508 0.9398)
			(end 0.508 -0.9398)
			(stroke
				(width 0)
				(type default)
			)
			(fill no)
			(layer "F.Fab")
		)
		(pad "1" smd custom
			(at 0 -0.4445 270)
			(size 0.1397 0.1397)
			(layers "F.Cu" "F.Mask" "F.Paste")
			(net "P3V3")
			(options
				(clearance outline)
				(anchor circle)
			)
			(primitives
				(gr_poly
					(pts
						(arc
							(start -0.1778 -0.2794)
							(mid -0.249642 -0.249642)
							(end -0.2794 -0.1778)
						)
						(arc
							(start -0.2794 0.1778)
							(mid -0.249642 0.249642)
							(end -0.1778 0.2794)
						)
						(arc
							(start 0.1778 0.2794)
							(mid 0.249642 0.249642)
							(end 0.2794 0.1778)
						)
						(arc
							(start 0.2794 -0.1778)
							(mid 0.249642 -0.249642)
							(end 0.1778 -0.2794)
						)
					)
					(width 0)
					(fill yes)
				)
			)
		)
		(pad "2" smd custom
			(at 0 0.4445 270)
			(size 0.1397 0.1397)
			(layers "F.Cu" "F.Mask" "F.Paste")
			(net "ATTN_LED_DR3_MOS_N")
			(options
				(clearance outline)
				(anchor circle)
			)
			(primitives
				(gr_poly
					(pts
						(arc
							(start -0.1778 -0.2794)
							(mid -0.249642 -0.249642)
							(end -0.2794 -0.1778)
						)
						(arc
							(start -0.2794 0.1778)
							(mid -0.249642 0.249642)
							(end -0.1778 0.2794)
						)
						(arc
							(start 0.1778 0.2794)
							(mid 0.249642 0.249642)
							(end 0.2794 0.1778)
						)
						(arc
							(start 0.2794 -0.1778)
							(mid 0.249642 -0.249642)
							(end 0.1778 -0.2794)
						)
					)
					(width 0)
					(fill yes)
				)
			)
		)
	)
	(footprint ""
		(layer "F.Cu")
		(at 22.247606 -368.1095 180)
		(property "Reference" "R9854"
			(at 0 0 180)
			(layer "F.SilkS")
			(hide yes)
			(effects
				(font
					(size 1.27 1.27)
				)
			)
		)
		(property "Value" "0R2J-2-GP"
			(at 0.064008 -3.993896 180)
			(unlocked yes)
			(layer "F.Fab")
			(hide yes)
			(effects
				(font
					(size 1.016 1.016)
					(thickness 0.1524)
				)
			)
		)
		(property "Device Type" "R402H16"
			(at 0.064008 -5.517896 180)
			(unlocked yes)
			(layer "F.Fab")
			(hide yes)
			(effects
				(font
					(size 1.016 1.016)
					(thickness 0.1524)
				)
			)
		)
		(duplicate_pad_numbers_are_jumpers no)
		(fp_line
			(start 0.508 -0.9398)
			(end -0.508 -0.9398)
			(stroke
				(width 0.1524)
				(type default)
			)
			(layer "F.SilkS")
		)
		(fp_line
			(start -0.508 -0.9398)
			(end -0.508 0.9398)
			(stroke
				(width 0.1524)
				(type default)
			)
			(layer "F.SilkS")
		)
		(fp_rect
			(start -0.508 0.9398)
			(end 0.508 -0.9398)
			(stroke
				(width 0)
				(type default)
			)
			(fill no)
			(layer "F.CrtYd")
		)
		(fp_rect
			(start -0.508 0.9398)
			(end 0.508 -0.9398)
			(stroke
				(width 0)
				(type default)
			)
			(fill no)
			(layer "F.Fab")
		)
		(pad "1" smd custom
			(at 0 -0.4445 180)
			(size 0.1397 0.1397)
			(layers "F.Cu" "F.Mask" "F.Paste")
			(net "ATTN_LED_DR11_R")
			(options
				(clearance outline)
				(anchor circle)
			)
			(primitives
				(gr_poly
					(pts
						(arc
							(start -0.1778 -0.2794)
							(mid -0.249642 -0.249642)
							(end -0.2794 -0.1778)
						)
						(arc
							(start -0.2794 0.1778)
							(mid -0.249642 0.249642)
							(end -0.1778 0.2794)
						)
						(arc
							(start 0.1778 0.2794)
							(mid 0.249642 0.249642)
							(end 0.2794 0.1778)
						)
						(arc
							(start 0.2794 -0.1778)
							(mid 0.249642 -0.249642)
							(end 0.1778 -0.2794)
						)
					)
					(width 0)
					(fill yes)
				)
			)
		)
		(pad "2" smd custom
			(at 0 0.4445 180)
			(size 0.1397 0.1397)
			(layers "F.Cu" "F.Mask" "F.Paste")
			(net "ATTN_LED_DR11_N")
			(options
				(clearance outline)
				(anchor circle)
			)
			(primitives
				(gr_poly
					(pts
						(arc
							(start -0.1778 -0.2794)
							(mid -0.249642 -0.249642)
							(end -0.2794 -0.1778)
						)
						(arc
							(start -0.2794 0.1778)
							(mid -0.249642 0.249642)
							(end -0.1778 0.2794)
						)
						(arc
							(start 0.1778 0.2794)
							(mid 0.249642 0.249642)
							(end 0.2794 0.1778)
						)
						(arc
							(start 0.2794 -0.1778)
							(mid 0.249642 -0.249642)
							(end 0.1778 -0.2794)
						)
					)
					(width 0)
					(fill yes)
				)
			)
		)
	)
	(footprint ""
		(layer "F.Cu")
		(at 226.149916 -273.670014 90)
		(property "Reference" "J2"
			(at 0 0 90)
			(layer "F.SilkS")
			(hide yes)
			(effects
				(font
					(size 1.27 1.27)
				)
			)
		)
		(property "Value" "PCISLT68-14-GP-U1"
			(at -22.225 12.7508 90)
			(unlocked yes)
			(layer "F.Fab")
			(hide yes)
			(effects
				(font
					(size 1.016 1.016)
					(thickness 0.1524)
				)
			)
		)
		(property "Device Type" "SD-78827-0001"
			(at -22.225 11.2268 90)
			(unlocked yes)
			(layer "F.Fab")
			(hide yes)
			(effects
				(font
					(size 1.016 1.016)
					(thickness 0.1524)
				)
			)
		)
		(duplicate_pad_numbers_are_jumpers no)
		(fp_line
			(start 20.4724 -3.4036)
			(end 20.4724 0.0254)
			(stroke
				(width 0.1524)
				(type default)
			)
			(layer "F.SilkS")
		)
		(fp_line
			(start -20.4724 -3.4036)
			(end 20.4724 -3.4036)
			(stroke
				(width 0.1524)
				(type default)
			)
			(layer "F.SilkS")
		)
		(fp_line
			(start 23.749 0.0254)
			(end 23.749 4.6736)
			(stroke
				(width 0.1524)
				(type default)
			)
			(layer "F.SilkS")
		)
		(fp_line
			(start 20.4724 0.0254)
			(end 23.749 0.0254)
			(stroke
				(width 0.1524)
				(type default)
			)
			(layer "F.SilkS")
		)
		(fp_line
			(start -20.4724 0.0254)
			(end -20.4724 -3.4036)
			(stroke
				(width 0.1524)
				(type default)
			)
			(layer "F.SilkS")
		)
		(fp_line
			(start -23.749 0.0254)
			(end -20.4724 0.0254)
			(stroke
				(width 0.1524)
				(type default)
			)
			(layer "F.SilkS")
		)
		(fp_line
			(start 23.117556 1.803908)
			(end 23.117556 2.896108)
			(stroke
				(width 0.3048)
				(type default)
			)
			(layer "F.SilkS")
		)
		(fp_line
			(start -20.882356 1.803908)
			(end -20.882356 2.896108)
			(stroke
				(width 0.3048)
				(type default)
			)
			(layer "F.SilkS")
		)
		(fp_line
			(start 20.882356 2.896108)
			(end 20.882356 1.803908)
			(stroke
				(width 0.3048)
				(type default)
			)
			(layer "F.SilkS")
		)
		(fp_line
			(start -23.117556 2.896108)
			(end -23.117556 1.803908)
			(stroke
				(width 0.3048)
				(type default)
			)
			(layer "F.SilkS")
		)
		(fp_line
			(start 23.749 4.6736)
			(end 20.4724 4.6736)
			(stroke
				(width 0.1524)
				(type default)
			)
			(layer "F.SilkS")
		)
		(fp_line
			(start 20.4724 4.6736)
			(end 20.4724 12.0142)
			(stroke
				(width 0.1524)
				(type default)
			)
			(layer "F.SilkS")
		)
		(fp_line
			(start -20.4724 4.6736)
			(end -23.749 4.6736)
			(stroke
				(width 0.1524)
				(type default)
			)
			(layer "F.SilkS")
		)
		(fp_line
			(start -23.749 4.6736)
			(end -23.749 0.0254)
			(stroke
				(width 0.1524)
				(type default)
			)
			(layer "F.SilkS")
		)
		(fp_line
			(start 17.8435 10.3124)
			(end -17.8435 10.3124)
			(stroke
				(width 0.1524)
				(type default)
			)
			(layer "F.SilkS")
		)
		(fp_line
			(start -17.8435 10.3124)
			(end -17.8435 12.0142)
			(stroke
				(width 0.1524)
				(type default)
			)
			(layer "F.SilkS")
		)
		(fp_line
			(start 20.4724 12.0142)
			(end 17.8435 12.0142)
			(stroke
				(width 0.1524)
				(type default)
			)
			(layer "F.SilkS")
		)
		(fp_line
			(start 17.8435 12.0142)
			(end 17.8435 10.3124)
			(stroke
				(width 0.1524)
				(type default)
			)
			(layer "F.SilkS")
		)
		(fp_line
			(start -17.8435 12.0142)
			(end -20.4724 12.0142)
			(stroke
				(width 0.1524)
				(type default)
			)
			(layer "F.SilkS")
		)
		(fp_line
			(start -20.4724 12.0142)
			(end -20.4724 4.6736)
			(stroke
				(width 0.1524)
				(type default)
			)
			(layer "F.SilkS")
		)
		(fp_arc
			(start 20.882356 1.803908)
			(mid 21.999956 0.686308)
			(end 23.117556 1.803908)
			(stroke
				(width 0.3048)
				(type default)
			)
			(layer "F.SilkS")
		)
		(fp_arc
			(start -23.117556 1.803908)
			(mid -21.999956 0.686308)
			(end -20.882356 1.803908)
			(stroke
				(width 0.3048)
				(type default)
			)
			(layer "F.SilkS")
		)
		(fp_arc
			(start 23.117556 2.896108)
			(mid 21.999956 4.013708)
			(end 20.882356 2.896108)
			(stroke
				(width 0.3048)
				(type default)
			)
			(layer "F.SilkS")
		)
		(fp_arc
			(start -20.882356 2.896108)
			(mid -21.999956 4.013708)
			(end -23.117556 2.896108)
			(stroke
				(width 0.3048)
				(type default)
			)
			(layer "F.SilkS")
		)
		(fp_poly
			(pts
				(xy -20.2184 11.7602) (xy -20.2184 4.4196) (xy -23.495 4.4196) (xy -23.495 0.2794) (xy -20.2184 0.2794)
				(xy -20.2184 -3.1496) (xy 20.2184 -3.1496) (xy 20.2184 0.2794) (xy 23.495 0.2794) (xy 23.495 4.4196)
				(xy 20.2184 4.4196) (xy 20.2184 11.7602) (xy 18.0975 11.7602) (xy 18.0975 10.0584) (xy -18.0975 10.0584)
				(xy -18.0975 11.7602)
			)
			(stroke
				(width 0)
				(type default)
			)
			(fill no)
			(layer "F.CrtYd")
		)
		(fp_poly
			(pts
				(xy -21.2471 16.256) (xy -21.2471 4.9276) (xy -24.003 4.9276) (xy -24.003 -0.2286) (xy -20.7264 -0.2286)
				(xy -20.7264 -3.6576) (xy 20.7264 -3.6576) (xy 20.7264 -0.2286) (xy 24.003 -0.2286) (xy 24.003 -0.00635)
				(xy 20.2184 -0.00635) (xy 20.2184 -3.1496) (xy -20.2184 -3.1496) (xy -20.2184 0.2794) (xy -23.495 0.2794)
				(xy -23.495 4.4196) (xy -20.2184 4.4196) (xy -20.2184 11.7602) (xy -18.0975 11.7602) (xy -18.0975 10.0584)
				(xy 18.0975 10.0584) (xy 18.0975 11.7602) (xy 20.2184 11.7602) (xy 20.2184 4.4196) (xy 23.495 4.4196)
				(xy 23.495 0.2794) (xy 20.2184 0.2794) (xy 20.2184 0.00635) (xy 24.003 0.00635) (xy 24.003 4.9276)
				(xy 21.2471 4.9276) (xy 21.2471 16.256)
			)
			(stroke
				(width 0)
				(type default)
			)
			(fill no)
			(layer "F.CrtYd")
		)
		(fp_poly
			(pts
				(xy -21.2471 16.256) (xy -21.2471 4.9276) (xy -24.003 4.9276) (xy -24.003 -0.2286) (xy -20.7264 -0.2286)
				(xy -20.7264 -3.6576) (xy 20.7264 -3.6576) (xy 20.7264 -0.2286) (xy 24.003 -0.2286) (xy 24.003 4.9276)
				(xy 21.2471 4.9276) (xy 21.2471 16.256)
			)
			(stroke
				(width 0)
				(type default)
			)
			(fill no)
			(layer "F.Fab")
		)
		(pad "" np_thru_hole circle
			(at -18.999962 0 90)
			(size 0.254 0.254)
			(drill 1.8542)
			(layers "*.Cu" "*.Mask")
			(clearance 1.1557)
			(thermal_gap 1.1557)
		)
		(pad "" np_thru_hole circle
			(at 18.999962 0 90)
			(size 0.254 0.254)
			(drill 1.8542)
			(layers "*.Cu" "*.Mask")
			(clearance 1.1557)
			(thermal_gap 1.1557)
		)
		(pad "E1" smd rect
			(at -7.079996 1.240028 90)
			(size 0.508 2.0066)
			(layers "F.Cu" "F.Mask" "F.Paste")
			(net "PE_CLK100M_DR2_2_P")
		)
		(pad "E2" smd rect
			(at -6.279896 1.240028 90)
			(size 0.508 2.0066)
			(layers "F.Cu" "F.Mask" "F.Paste")
			(net "PE_CLK100M_DR2_2_N")
		)
		(pad "E3" smd rect
			(at -5.48005 1.240028 90)
			(size 0.508 2.0066)
			(layers "F.Cu" "F.Mask" "F.Paste")
			(net "P3V3")
		)
		(pad "E4" smd rect
			(at -4.67995 1.240028 90)
			(size 0.508 2.0066)
			(layers "F.Cu" "F.Mask" "F.Paste")
			(net "SSD2_PERST_N")
		)
		(pad "E5" smd rect
			(at -3.880104 1.240028 90)
			(size 0.508 2.0066)
			(layers "F.Cu" "F.Mask" "F.Paste")
			(net "SSD2_PERST_N")
		)
		(pad "E6" smd rect
			(at -3.080004 1.240028 90)
			(size 0.508 2.0066)
			(layers "F.Cu" "F.Mask" "F.Paste")
			(net "Net_1197")
		)
		(pad "E7" smd rect
			(at -15.48003 -1.949958 90)
			(size 0.508 2.0066)
			(layers "F.Cu" "F.Mask" "F.Paste")
			(net "PE_CLK100M_DR2_1_P")
		)
		(pad "E8" smd rect
			(at -14.67993 -1.949958 90)
			(size 0.508 2.0066)
			(layers "F.Cu" "F.Mask" "F.Paste")
			(net "PE_CLK100M_DR2_1_N")
		)
		(pad "E9" smd rect
			(at -13.880084 -1.949958 90)
			(size 0.508 2.0066)
			(layers "F.Cu" "F.Mask" "F.Paste")
			(net "GND")
		)
		(pad "E10" smd rect
			(at -13.079984 -1.949958 90)
			(size 0.508 2.0066)
			(layers "F.Cu" "F.Mask" "F.Paste")
			(net "PE_TX1_DR2_N")
		)
		(pad "E11" smd rect
			(at -12.279884 -1.949958 90)
			(size 0.508 2.0066)
			(layers "F.Cu" "F.Mask" "F.Paste")
			(net "PE_TX1_DR2_P")
		)
		(pad "E12" smd rect
			(at -11.480038 -1.949958 90)
			(size 0.508 2.0066)
			(layers "F.Cu" "F.Mask" "F.Paste")
			(net "GND")
		)
		(pad "E13" smd rect
			(at -10.679938 -1.949958 90)
			(size 0.508 2.0066)
			(layers "F.Cu" "F.Mask" "F.Paste")
			(net "PE_RX1_DR2_N")
		)
		(pad "E14" smd rect
			(at -9.880092 -1.949958 90)
			(size 0.508 2.0066)
			(layers "F.Cu" "F.Mask" "F.Paste")
			(net "PE_RX1_DR2_P")
		)
		(pad "E15" smd rect
			(at -9.079992 -1.949958 90)
			(size 0.508 2.0066)
			(layers "F.Cu" "F.Mask" "F.Paste")
			(net "GND")
		)
		(pad "E16" smd rect
			(at -8.279892 -1.949958 90)
			(size 0.508 2.0066)
			(layers "F.Cu" "F.Mask" "F.Paste")
			(net "Net_1204")
		)
		(pad "E17" smd rect
			(at 9.320022 -1.949958 90)
			(size 0.508 2.0066)
			(layers "F.Cu" "F.Mask" "F.Paste")
			(net "PE_TX4_DR2_N")
		)
		(pad "E18" smd rect
			(at 10.120122 -1.949958 90)
			(size 0.508 2.0066)
			(layers "F.Cu" "F.Mask" "F.Paste")
			(net "PE_TX4_DR2_P")
		)
		(pad "E19" smd rect
			(at 10.919968 -1.949958 90)
			(size 0.508 2.0066)
			(layers "F.Cu" "F.Mask" "F.Paste")
			(net "GND")
		)
		(pad "E20" smd rect
			(at 11.720068 -1.949958 90)
			(size 0.508 2.0066)
			(layers "F.Cu" "F.Mask" "F.Paste")
			(net "PE_RX4_DR2_N")
		)
		(pad "E21" smd rect
			(at 12.519914 -1.949958 90)
			(size 0.508 2.0066)
			(layers "F.Cu" "F.Mask" "F.Paste")
			(net "PE_RX4_DR2_P")
		)
		(pad "E22" smd rect
			(at 13.320014 -1.949958 90)
			(size 0.508 2.0066)
			(layers "F.Cu" "F.Mask" "F.Paste")
			(net "GND")
		)
		(pad "E23" smd rect
			(at 14.120114 -1.949958 90)
			(size 0.508 2.0066)
			(layers "F.Cu" "F.Mask" "F.Paste")
			(net "SCL_DR2_R")
		)
		(pad "E24" smd rect
			(at 14.91996 -1.949958 90)
			(size 0.508 2.0066)
			(layers "F.Cu" "F.Mask" "F.Paste")
			(net "SDA_DR2_R")
		)
		(pad "E25" smd rect
			(at 15.72006 -1.949958 90)
			(size 0.508 2.0066)
			(layers "F.Cu" "F.Mask" "F.Paste")
			(net "DUALPORTEN#2")
		)
		(pad "P1" smd rect
			(at -1.905 0.824992 90)
			(size 0.6604 2.0574)
			(layers "F.Cu" "F.Mask" "F.Paste")
			(net "Net_1200")
		)
		(pad "P2" smd rect
			(at -0.635 0.824992 90)
			(size 0.6604 2.0574)
			(layers "F.Cu" "F.Mask" "F.Paste")
			(net "Net_1199")
		)
		(pad "P3" smd rect
			(at 0.635 0.824992 90)
			(size 0.6604 2.0574)
			(layers "F.Cu" "F.Mask" "F.Paste")
			(net "Net_1198")
		)
		(pad "P4" smd rect
			(at 1.905 0.824992 90)
			(size 0.6604 2.0574)
			(layers "F.Cu" "F.Mask" "F.Paste")
			(net "SSD2_CLK0_OE_N")
		)
		(pad "P5" smd rect
			(at 3.175 0.824992 90)
			(size 0.6604 2.0574)
			(layers "F.Cu" "F.Mask" "F.Paste")
			(net "GND")
		)
		(pad "P6" smd rect
			(at 4.445 0.824992 90)
			(size 0.6604 2.0574)
			(layers "F.Cu" "F.Mask" "F.Paste")
			(net "GND")
		)
		(pad "P7" smd rect
			(at 5.715 0.824992 90)
			(size 0.6604 2.0574)
			(layers "F.Cu" "F.Mask" "F.Paste")
			(net "Net_93")
		)
		(pad "P8" smd rect
			(at 6.985 0.824992 90)
			(size 0.6604 2.0574)
			(layers "F.Cu" "F.Mask" "F.Paste")
			(net "Net_65")
		)
		(pad "P9" smd rect
			(at 8.255 0.824992 90)
			(size 0.6604 2.0574)
			(layers "F.Cu" "F.Mask" "F.Paste")
			(net "Net_79")
		)
		(pad "P10" smd rect
			(at 9.525 0.824992 90)
			(size 0.6604 2.0574)
			(layers "F.Cu" "F.Mask" "F.Paste")
			(net "SSD_PRSNT_NET2")
		)
		(pad "P11" smd rect
			(at 10.795 0.824992 90)
			(size 0.6604 2.0574)
			(layers "F.Cu" "F.Mask" "F.Paste")
			(net "SSD_ACT_DR2")
		)
		(pad "P12" smd rect
			(at 12.065 0.824992 90)
			(size 0.6604 2.0574)
			(layers "F.Cu" "F.Mask" "F.Paste")
			(net "GND")
		)
		(pad "P13" smd rect
			(at 13.335 0.824992 90)
			(size 0.6604 2.0574)
			(layers "F.Cu" "F.Mask" "F.Paste")
			(net "12V_PRECH_SSD2")
		)
		(pad "P14" smd rect
			(at 14.605 0.824992 90)
			(size 0.6604 2.0574)
			(layers "F.Cu" "F.Mask" "F.Paste")
			(net "P12V_SSD2")
		)
		(pad "P15" smd rect
			(at 15.875 0.824992 90)
			(size 0.6604 2.0574)
			(layers "F.Cu" "F.Mask" "F.Paste")
			(net "P12V_SSD2")
		)
		(pad "PTH1" thru_hole oval
			(at -21.999956 2.350008 90)
			(size 1.524 2.6162)
			(drill oval 0.8128 1.905)
			(layers "*.Cu" "*.Mask")
			(remove_unused_layers no)
			(net "Net_1209")
			(clearance 0.1524)
			(thermal_gap 0.1524)
		)
		(pad "PTH2" thru_hole oval
			(at 21.999956 2.350008 90)
			(size 1.524 2.6162)
			(drill oval 0.8128 1.905)
			(layers "*.Cu" "*.Mask")
			(remove_unused_layers no)
			(net "Net_1193")
			(clearance 0.1524)
			(thermal_gap 0.1524)
		)
		(pad "S1" smd rect
			(at -15.875 0.824992 90)
			(size 0.6604 2.0574)
			(layers "F.Cu" "F.Mask" "F.Paste")
			(net "GND")
		)
		(pad "S2" smd rect
			(at -14.605 0.824992 90)
			(size 0.6604 2.0574)
			(layers "F.Cu" "F.Mask" "F.Paste")
			(net "Net_1208")
		)
		(pad "S3" smd rect
			(at -13.335 0.824992 90)
			(size 0.6604 2.0574)
			(layers "F.Cu" "F.Mask" "F.Paste")
			(net "Net_1207")
		)
		(pad "S4" smd rect
			(at -12.065 0.824992 90)
			(size 0.6604 2.0574)
			(layers "F.Cu" "F.Mask" "F.Paste")
			(net "GND")
		)
		(pad "S5" smd rect
			(at -10.795 0.824992 90)
			(size 0.6604 2.0574)
			(layers "F.Cu" "F.Mask" "F.Paste")
			(net "Net_1206")
		)
		(pad "S6" smd rect
			(at -9.525 0.824992 90)
			(size 0.6604 2.0574)
			(layers "F.Cu" "F.Mask" "F.Paste")
			(net "Net_1205")
		)
		(pad "S7" smd rect
			(at -8.255 0.824992 90)
			(size 0.6604 2.0574)
			(layers "F.Cu" "F.Mask" "F.Paste")
			(net "GND")
		)
		(pad "S8" smd rect
			(at -7.480046 -1.949958 90)
			(size 0.508 2.0066)
			(layers "F.Cu" "F.Mask" "F.Paste")
			(net "GND")
		)
		(pad "S9" smd rect
			(at -6.679946 -1.949958 90)
			(size 0.508 2.0066)
			(layers "F.Cu" "F.Mask" "F.Paste")
			(net "Net_1203")
		)
		(pad "S10" smd rect
			(at -5.8801 -1.949958 90)
			(size 0.508 2.0066)
			(layers "F.Cu" "F.Mask" "F.Paste")
			(net "Net_1202")
		)
		(pad "S11" smd rect
			(at -5.08 -1.949958 90)
			(size 0.508 2.0066)
			(layers "F.Cu" "F.Mask" "F.Paste")
			(net "GND")
		)
		(pad "S12" smd rect
			(at -4.2799 -1.949958 90)
			(size 0.508 2.0066)
			(layers "F.Cu" "F.Mask" "F.Paste")
			(net "Net_1201")
		)
		(pad "S13" smd rect
			(at -3.480054 -1.949958 90)
			(size 0.508 2.0066)
			(layers "F.Cu" "F.Mask" "F.Paste")
			(net "Net_1196")
		)
		(pad "S14" smd rect
			(at -2.679954 -1.949958 90)
			(size 0.508 2.0066)
			(layers "F.Cu" "F.Mask" "F.Paste")
			(net "GND")
		)
		(pad "S15" smd rect
			(at -1.880108 -1.949958 90)
			(size 0.508 2.0066)
			(layers "F.Cu" "F.Mask" "F.Paste")
			(net "Net_1195")
		)
		(pad "S16" smd rect
			(at -1.080008 -1.949958 90)
			(size 0.508 2.0066)
			(layers "F.Cu" "F.Mask" "F.Paste")
			(net "GND")
		)
		(pad "S17" smd rect
			(at -0.279908 -1.949958 90)
			(size 0.508 2.0066)
			(layers "F.Cu" "F.Mask" "F.Paste")
			(net "PE_TX2_DR2_N")
		)
		(pad "S18" smd rect
			(at 0.519938 -1.949958 90)
			(size 0.508 2.0066)
			(layers "F.Cu" "F.Mask" "F.Paste")
			(net "PE_TX2_DR2_P")
		)
		(pad "S19" smd rect
			(at 1.320038 -1.949958 90)
			(size 0.508 2.0066)
			(layers "F.Cu" "F.Mask" "F.Paste")
			(net "GND")
		)
		(pad "S20" smd rect
			(at 2.119884 -1.949958 90)
			(size 0.508 2.0066)
			(layers "F.Cu" "F.Mask" "F.Paste")
			(net "PE_RX2_DR2_N")
		)
		(pad "S21" smd rect
			(at 2.919984 -1.949958 90)
			(size 0.508 2.0066)
			(layers "F.Cu" "F.Mask" "F.Paste")
			(net "PE_RX2_DR2_P")
		)
		(pad "S22" smd rect
			(at 3.720084 -1.949958 90)
			(size 0.508 2.0066)
			(layers "F.Cu" "F.Mask" "F.Paste")
			(net "GND")
		)
		(pad "S23" smd rect
			(at 4.51993 -1.949958 90)
			(size 0.508 2.0066)
			(layers "F.Cu" "F.Mask" "F.Paste")
			(net "PE_TX3_DR2_N")
		)
		(pad "S24" smd rect
			(at 5.32003 -1.949958 90)
			(size 0.508 2.0066)
			(layers "F.Cu" "F.Mask" "F.Paste")
			(net "PE_TX3_DR2_P")
		)
		(pad "S25" smd rect
			(at 6.119876 -1.949958 90)
			(size 0.508 2.0066)
			(layers "F.Cu" "F.Mask" "F.Paste")
			(net "GND")
		)
		(pad "S26" smd rect
			(at 6.919976 -1.949958 90)
			(size 0.508 2.0066)
			(layers "F.Cu" "F.Mask" "F.Paste")
			(net "PE_RX3_DR2_N")
		)
		(pad "S27" smd rect
			(at 7.720076 -1.949958 90)
			(size 0.508 2.0066)
			(layers "F.Cu" "F.Mask" "F.Paste")
			(net "PE_RX3_DR2_P")
		)
		(pad "S28" smd rect
			(at 8.519922 -1.949958 90)
			(size 0.508 2.0066)
			(layers "F.Cu" "F.Mask" "F.Paste")
			(net "GND")
		)
		(zone
			(layers "F.Cu" "B.Cu" "In1.Cu" "In2.Cu" "In3.Cu" "In4.Cu" "In5.Cu" "In6.Cu")
			(hatch none 0.5)
			(connect_pads
				(clearance 0)
			)
			(min_thickness 0.25)
			(keepout
				(tracks not_allowed)
				(vias allowed)
				(pads allowed)
				(copperpour not_allowed)
				(footprints allowed)
			)
			(placement
				(enabled no)
				(sheetname "")
			)
			(fill
				(thermal_gap 0.5)
				(thermal_bridge_width 0.5)
				(island_removal_mode 0)
			)
			(polygon
				(pts
					(arc
						(start 227.381816 -292.669976)
						(mid 224.918016 -292.669976)
						(end 227.381816 -292.669976)
					)
				)
			)
		)
		(zone
			(layers "F.Cu" "B.Cu" "In1.Cu" "In2.Cu" "In3.Cu" "In4.Cu" "In5.Cu" "In6.Cu")
			(hatch none 0.5)
			(connect_pads
				(clearance 0)
			)
			(min_thickness 0.25)
			(keepout
				(tracks not_allowed)
				(vias allowed)
				(pads allowed)
				(copperpour not_allowed)
				(footprints allowed)
			)
			(placement
				(enabled no)
				(sheetname "")
			)
			(fill
				(thermal_gap 0.5)
				(thermal_bridge_width 0.5)
				(island_removal_mode 0)
			)
			(polygon
				(pts
					(arc
						(start 227.381816 -254.670052)
						(mid 224.918016 -254.670052)
						(end 227.381816 -254.670052)
					)
				)
			)
		)
	)
	(footprint ""
		(layer "F.Cu")
		(at 44.677076 -344.118692)
		(property "Reference" "C9524"
			(at 0 0 0)
			(layer "F.SilkS")
			(hide yes)
			(effects
				(font
					(size 1.27 1.27)
				)
			)
		)
		(property "Value" "SCD1U16V2KX-3GP"
			(at 1.1811 -2.7051 0)
			(unlocked yes)
			(layer "F.Fab")
			(hide yes)
			(effects
				(font
					(size 1.016 1.016)
					(thickness 0.1524)
				)
			)
		)
		(property "Device Type" "C402H22"
			(at 1.1811 -4.2291 0)
			(unlocked yes)
			(layer "F.Fab")
			(hide yes)
			(effects
				(font
					(size 1.016 1.016)
					(thickness 0.1524)
				)
			)
		)
		(duplicate_pad_numbers_are_jumpers no)
		(fp_rect
			(start -0.4318 0.9525)
			(end 0.4318 -0.9525)
			(stroke
				(width 0)
				(type default)
			)
			(fill no)
			(layer "F.CrtYd")
		)
		(fp_rect
			(start -0.4318 0.9525)
			(end 0.4318 -0.9525)
			(stroke
				(width 0)
				(type default)
			)
			(fill no)
			(layer "F.Fab")
		)
		(pad "1" smd custom
			(at 0 -0.4445)
			(size 0.1524 0.1524)
			(layers "F.Cu" "F.Mask" "F.Paste")
			(net "P3V3")
			(options
				(clearance outline)
				(anchor circle)
			)
			(primitives
				(gr_poly
					(pts
						(arc
							(start 0.3048 -0.2032)
							(mid 0.275042 -0.275042)
							(end 0.2032 -0.3048)
						)
						(arc
							(start -0.2032 -0.3048)
							(mid -0.275042 -0.275042)
							(end -0.3048 -0.2032)
						)
						(arc
							(start -0.3048 0.2032)
							(mid -0.275042 0.275042)
							(end -0.2032 0.3048)
						)
						(arc
							(start 0.2032 0.3048)
							(mid 0.275042 0.275042)
							(end 0.3048 0.2032)
						)
					)
					(width 0)
					(fill yes)
				)
			)
		)
		(pad "2" smd custom
			(at 0 0.4445)
			(size 0.1524 0.1524)
			(layers "F.Cu" "F.Mask" "F.Paste")
			(net "GND")
			(options
				(clearance outline)
				(anchor circle)
			)
			(primitives
				(gr_poly
					(pts
						(arc
							(start 0.3048 -0.2032)
							(mid 0.275042 -0.275042)
							(end 0.2032 -0.3048)
						)
						(arc
							(start -0.2032 -0.3048)
							(mid -0.275042 -0.275042)
							(end -0.3048 -0.2032)
						)
						(arc
							(start -0.3048 0.2032)
							(mid -0.275042 0.275042)
							(end -0.2032 0.3048)
						)
						(arc
							(start 0.2032 0.3048)
							(mid 0.275042 0.275042)
							(end 0.3048 0.2032)
						)
					)
					(width 0)
					(fill yes)
				)
			)
		)
	)
	(footprint ""
		(layer "F.Cu")
		(at 106.045 -310.261 180)
		(property "Reference" "C9365"
			(at 0 0 180)
			(layer "F.SilkS")
			(hide yes)
			(effects
				(font
					(size 1.27 1.27)
				)
			)
		)
		(property "Value" "SC1KP50V2KX-1GP"
			(at 1.1811 -2.7051 180)
			(unlocked yes)
			(layer "F.Fab")
			(hide yes)
			(effects
				(font
					(size 1.016 1.016)
					(thickness 0.1524)
				)
			)
		)
		(property "Device Type" "C402H22"
			(at 1.1811 -4.2291 180)
			(unlocked yes)
			(layer "F.Fab")
			(hide yes)
			(effects
				(font
					(size 1.016 1.016)
					(thickness 0.1524)
				)
			)
		)
		(duplicate_pad_numbers_are_jumpers no)
		(fp_rect
			(start -0.4318 0.9525)
			(end 0.4318 -0.9525)
			(stroke
				(width 0)
				(type default)
			)
			(fill no)
			(layer "F.CrtYd")
		)
		(fp_rect
			(start -0.4318 0.9525)
			(end 0.4318 -0.9525)
			(stroke
				(width 0)
				(type default)
			)
			(fill no)
			(layer "F.Fab")
		)
		(pad "1" smd custom
			(at 0 -0.4445 180)
			(size 0.1524 0.1524)
			(layers "F.Cu" "F.Mask" "F.Paste")
			(net "SSD1_CLK0_OE_R_N")
			(options
				(clearance outline)
				(anchor circle)
			)
			(primitives
				(gr_poly
					(pts
						(arc
							(start 0.3048 -0.2032)
							(mid 0.275042 -0.275042)
							(end 0.2032 -0.3048)
						)
						(arc
							(start -0.2032 -0.3048)
							(mid -0.275042 -0.275042)
							(end -0.3048 -0.2032)
						)
						(arc
							(start -0.3048 0.2032)
							(mid -0.275042 0.275042)
							(end -0.2032 0.3048)
						)
						(arc
							(start 0.2032 0.3048)
							(mid 0.275042 0.275042)
							(end 0.3048 0.2032)
						)
					)
					(width 0)
					(fill yes)
				)
			)
		)
		(pad "2" smd custom
			(at 0 0.4445 180)
			(size 0.1524 0.1524)
			(layers "F.Cu" "F.Mask" "F.Paste")
			(net "GND")
			(options
				(clearance outline)
				(anchor circle)
			)
			(primitives
				(gr_poly
					(pts
						(arc
							(start 0.3048 -0.2032)
							(mid 0.275042 -0.275042)
							(end 0.2032 -0.3048)
						)
						(arc
							(start -0.2032 -0.3048)
							(mid -0.275042 -0.275042)
							(end -0.3048 -0.2032)
						)
						(arc
							(start -0.3048 0.2032)
							(mid -0.275042 0.275042)
							(end -0.2032 0.3048)
						)
						(arc
							(start 0.2032 0.3048)
							(mid 0.275042 0.275042)
							(end 0.3048 0.2032)
						)
					)
					(width 0)
					(fill yes)
				)
			)
		)
	)
	(footprint ""
		(layer "F.Cu")
		(at 38.989 -142.24 180)
		(property "Reference" "U205"
			(at 0 0 180)
			(layer "F.SilkS")
			(hide yes)
			(effects
				(font
					(size 1.27 1.27)
				)
			)
		)
		(property "Value" "SN74LVC1G08DCKR-GP"
			(at -2.3368 -8.6868 180)
			(unlocked yes)
			(layer "F.Fab")
			(hide yes)
			(effects
				(font
					(size 1.016 1.016)
					(thickness 0.1524)
				)
			)
		)
		(property "Device Type" "SC70-5H44"
			(at -2.3114 -10.414 180)
			(unlocked yes)
			(layer "F.Fab")
			(hide yes)
			(effects
				(font
					(size 1.016 1.016)
					(thickness 0.1524)
				)
			)
		)
		(duplicate_pad_numbers_are_jumpers no)
		(fp_line
			(start 1.3843 -1.8034)
			(end 1.3843 -1.1176)
			(stroke
				(width 0.3302)
				(type default)
			)
			(layer "F.SilkS")
		)
		(fp_line
			(start 1.27 1.7018)
			(end -1.27 1.7018)
			(stroke
				(width 0.1524)
				(type default)
			)
			(layer "F.SilkS")
		)
		(fp_line
			(start 1.27 -1.7018)
			(end 1.27 1.7018)
			(stroke
				(width 0.1524)
				(type default)
			)
			(layer "F.SilkS")
		)
		(fp_line
			(start 0.6604 -1.8034)
			(end 1.3843 -1.8034)
			(stroke
				(width 0.3302)
				(type default)
			)
			(layer "F.SilkS")
		)
		(fp_line
			(start -1.27 1.7018)
			(end -1.27 -1.7018)
			(stroke
				(width 0.1524)
				(type default)
			)
			(layer "F.SilkS")
		)
		(fp_line
			(start -1.27 -1.7018)
			(end 1.27 -1.7018)
			(stroke
				(width 0.1524)
				(type default)
			)
			(layer "F.SilkS")
		)
		(fp_rect
			(start -1.524 1.9558)
			(end 1.524 -1.9558)
			(stroke
				(width 0)
				(type default)
			)
			(fill no)
			(layer "F.CrtYd")
		)
		(fp_poly
			(pts
				(xy -1.524 -1.9558) (xy 1.524 -1.9558) (xy 1.524 1.9558) (xy -1.524 1.9558)
			)
			(stroke
				(width 0)
				(type default)
			)
			(fill no)
			(layer "F.Fab")
		)
		(pad "1" smd rect
			(at 0.65024 -0.8255 180)
			(size 0.4064 1.2192)
			(layers "F.Cu" "F.Mask" "F.Paste")
			(net "SSD8_CLK0_OE_MOS_N")
		)
		(pad "2" smd rect
			(at 0 -0.8255 180)
			(size 0.4064 1.2192)
			(layers "F.Cu" "F.Mask" "F.Paste")
			(net "ATTN_LED_DR8_N")
		)
		(pad "3" smd rect
			(at -0.65024 -0.8255 180)
			(size 0.4064 1.2192)
			(layers "F.Cu" "F.Mask" "F.Paste")
			(net "GND")
		)
		(pad "4" smd rect
			(at -0.65024 0.8255 180)
			(size 0.4064 1.2192)
			(layers "F.Cu" "F.Mask" "F.Paste")
			(net "ATTN_LED_DR8_AND")
		)
		(pad "5" smd rect
			(at 0.65024 0.8255 180)
			(size 0.4064 1.2192)
			(layers "F.Cu" "F.Mask" "F.Paste")
			(net "P3V3")
		)
	)
	(footprint ""
		(layer "F.Cu")
		(at 200.365106 -491.110778 180)
		(property "Reference" "R566"
			(at 0 0 180)
			(layer "F.SilkS")
			(hide yes)
			(effects
				(font
					(size 1.27 1.27)
				)
			)
		)
		(property "Value" "300KR2F-GP"
			(at 0.064008 -3.993896 180)
			(unlocked yes)
			(layer "F.Fab")
			(hide yes)
			(effects
				(font
					(size 1.016 1.016)
					(thickness 0.1524)
				)
			)
		)
		(property "Device Type" "R402H16"
			(at 0.064008 -5.517896 180)
			(unlocked yes)
			(layer "F.Fab")
			(hide yes)
			(effects
				(font
					(size 1.016 1.016)
					(thickness 0.1524)
				)
			)
		)
		(duplicate_pad_numbers_are_jumpers no)
		(fp_line
			(start 0.508 -0.9398)
			(end -0.508 -0.9398)
			(stroke
				(width 0.1524)
				(type default)
			)
			(layer "F.SilkS")
		)
		(fp_line
			(start -0.508 -0.9398)
			(end -0.508 0.9398)
			(stroke
				(width 0.1524)
				(type default)
			)
			(layer "F.SilkS")
		)
		(fp_rect
			(start -0.508 0.9398)
			(end 0.508 -0.9398)
			(stroke
				(width 0)
				(type default)
			)
			(fill no)
			(layer "F.CrtYd")
		)
		(fp_rect
			(start -0.508 0.9398)
			(end 0.508 -0.9398)
			(stroke
				(width 0)
				(type default)
			)
			(fill no)
			(layer "F.Fab")
		)
		(pad "1" smd custom
			(at 0 -0.4445 180)
			(size 0.1397 0.1397)
			(layers "F.Cu" "F.Mask" "F.Paste")
			(net "SW_SSD0_N")
			(options
				(clearance outline)
				(anchor circle)
			)
			(primitives
				(gr_poly
					(pts
						(arc
							(start -0.1778 -0.2794)
							(mid -0.249642 -0.249642)
							(end -0.2794 -0.1778)
						)
						(arc
							(start -0.2794 0.1778)
							(mid -0.249642 0.249642)
							(end -0.1778 0.2794)
						)
						(arc
							(start 0.1778 0.2794)
							(mid 0.249642 0.249642)
							(end 0.2794 0.1778)
						)
						(arc
							(start 0.2794 -0.1778)
							(mid 0.249642 -0.249642)
							(end 0.1778 -0.2794)
						)
					)
					(width 0)
					(fill yes)
				)
			)
		)
		(pad "2" smd custom
			(at 0 0.4445 180)
			(size 0.1397 0.1397)
			(layers "F.Cu" "F.Mask" "F.Paste")
			(net "P12V")
			(options
				(clearance outline)
				(anchor circle)
			)
			(primitives
				(gr_poly
					(pts
						(arc
							(start -0.1778 -0.2794)
							(mid -0.249642 -0.249642)
							(end -0.2794 -0.1778)
						)
						(arc
							(start -0.2794 0.1778)
							(mid -0.249642 0.249642)
							(end -0.1778 0.2794)
						)
						(arc
							(start 0.1778 0.2794)
							(mid 0.249642 0.249642)
							(end 0.2794 0.1778)
						)
						(arc
							(start 0.2794 -0.1778)
							(mid 0.249642 -0.249642)
							(end 0.1778 -0.2794)
						)
					)
					(width 0)
					(fill yes)
				)
			)
		)
	)
	(footprint ""
		(layer "F.Cu")
		(at 35.0266 -91.3384 180)
		(property "Reference" "PC1195"
			(at 0 0 180)
			(layer "F.SilkS")
			(hide yes)
			(effects
				(font
					(size 1.27 1.27)
				)
			)
		)
		(property "Value" "SC22U25V6KX-GP-U"
			(at -2.860802 -5.279644 180)
			(unlocked yes)
			(layer "F.Fab")
			(hide yes)
			(effects
				(font
					(size 1.016 1.016)
					(thickness 0.1524)
				)
			)
		)
		(property "Device Type" "C1206-TO0D3H75"
			(at -2.860802 -6.803644 180)
			(unlocked yes)
			(layer "F.Fab")
			(hide yes)
			(effects
				(font
					(size 1.016 1.016)
					(thickness 0.1524)
				)
			)
		)
		(duplicate_pad_numbers_are_jumpers no)
		(fp_line
			(start 1.3081 2.3749)
			(end -1.3081 2.3749)
			(stroke
				(width 0.1524)
				(type default)
			)
			(layer "F.SilkS")
		)
		(fp_line
			(start 1.3081 -2.3749)
			(end 1.3081 2.3749)
			(stroke
				(width 0.1524)
				(type default)
			)
			(layer "F.SilkS")
		)
		(fp_line
			(start -1.3081 2.3749)
			(end -1.3081 -2.3749)
			(stroke
				(width 0.1524)
				(type default)
			)
			(layer "F.SilkS")
		)
		(fp_line
			(start -1.3081 -2.3749)
			(end 1.3081 -2.3749)
			(stroke
				(width 0.1524)
				(type default)
			)
			(layer "F.SilkS")
		)
		(fp_rect
			(start -0.8001 1.6002)
			(end 0.8001 -1.6002)
			(stroke
				(width 0)
				(type default)
			)
			(fill no)
			(layer "F.CrtYd")
		)
		(fp_poly
			(pts
				(xy -1.5621 2.4511) (xy -1.5621 1.6002) (xy 0.8001 1.6002) (xy 0.8001 -1.6002) (xy -0.8001 -1.6002)
				(xy -0.8001 1.5875) (xy -1.5621 1.5875) (xy -1.5621 -2.4511) (xy 1.5621 -2.4511) (xy 1.5621 2.4511)
			)
			(stroke
				(width 0)
				(type default)
			)
			(fill no)
			(layer "F.CrtYd")
		)
		(fp_rect
			(start -1.5621 2.4511)
			(end 1.5621 -2.4511)
			(stroke
				(width 0)
				(type default)
			)
			(fill no)
			(layer "F.Fab")
		)
		(pad "1" smd rect
			(at 0 -1.392936 180)
			(size 2.1082 1.4478)
			(layers "F.Cu" "F.Mask" "F.Paste")
			(net "P12V_SSD9")
		)
		(pad "2" smd rect
			(at 0 1.392936 180)
			(size 2.1082 1.4478)
			(layers "F.Cu" "F.Mask" "F.Paste")
			(net "GND")
		)
	)
	(footprint ""
		(layer "F.Cu")
		(at 8.499856 -261.500112)
		(property "Reference" "H6"
			(at 0 0 0)
			(layer "F.SilkS")
			(hide yes)
			(effects
				(font
					(size 1.27 1.27)
				)
			)
		)
		(property "Value" "HOLE315R140-GP"
			(at 0 -7.5692 0)
			(unlocked yes)
			(layer "F.Fab")
			(hide yes)
			(effects
				(font
					(size 1.016 1.016)
					(thickness 0.1524)
				)
			)
		)
		(property "Device Type" "HOLE315R140"
			(at 0 -9.0932 0)
			(unlocked yes)
			(layer "F.Fab")
			(hide yes)
			(effects
				(font
					(size 1.016 1.016)
					(thickness 0.1524)
				)
			)
		)
		(duplicate_pad_numbers_are_jumpers no)
		(fp_poly
			(pts
				(arc
					(start 4.3053 0)
					(mid -4.3053 0)
					(end 4.3053 0)
				)
			)
			(stroke
				(width 0)
				(type default)
			)
			(fill no)
			(layer "F.CrtYd")
		)
		(fp_poly
			(pts
				(arc
					(start 4.3053 0)
					(mid -4.3053 0)
					(end 4.3053 0)
				)
			)
			(stroke
				(width 0)
				(type default)
			)
			(fill no)
			(layer "F.Fab")
		)
		(pad "1" thru_hole circle
			(at 0.00127 0.00127)
			(size 8.001 8.001)
			(drill 3.556)
			(layers "*.Cu" "*.Mask")
			(remove_unused_layers no)
			(net "GND")
			(clearance -1.7145)
			(thermal_gap 0.3048)
			(padstack
				(mode front_inner_back)
				(layer "Inner"
					(shape circle)
					(size 3.9624 3.9624)
					(clearance 0.3048)
				)
				(layer "B.Cu"
					(shape circle)
					(size 8.001 8.001)
					(clearance -1.7145)
				)
			)
		)
	)
	(footprint ""
		(layer "F.Cu")
		(at 24.003 -258.191 -90)
		(property "Reference" "R9478"
			(at 0 0 270)
			(layer "F.SilkS")
			(hide yes)
			(effects
				(font
					(size 1.27 1.27)
				)
			)
		)
		(property "Value" "100R2J-2-GP"
			(at 0.064008 -3.993896 270)
			(unlocked yes)
			(layer "F.Fab")
			(hide yes)
			(effects
				(font
					(size 1.016 1.016)
					(thickness 0.1524)
				)
			)
		)
		(property "Device Type" "R402H14"
			(at 0.064008 -5.517896 270)
			(unlocked yes)
			(layer "F.Fab")
			(hide yes)
			(effects
				(font
					(size 1.016 1.016)
					(thickness 0.1524)
				)
			)
		)
		(duplicate_pad_numbers_are_jumpers no)
		(fp_line
			(start -0.508 -0.9398)
			(end -0.508 0.9398)
			(stroke
				(width 0.1524)
				(type default)
			)
			(layer "F.SilkS")
		)
		(fp_line
			(start 0.508 -0.9398)
			(end -0.508 -0.9398)
			(stroke
				(width 0.1524)
				(type default)
			)
			(layer "F.SilkS")
		)
		(fp_rect
			(start -0.508 0.9398)
			(end 0.508 -0.9398)
			(stroke
				(width 0)
				(type default)
			)
			(fill no)
			(layer "F.CrtYd")
		)
		(fp_rect
			(start -0.508 0.9398)
			(end 0.508 -0.9398)
			(stroke
				(width 0)
				(type default)
			)
			(fill no)
			(layer "F.Fab")
		)
		(pad "1" smd custom
			(at 0 -0.4445 270)
			(size 0.1397 0.1397)
			(layers "F.Cu" "F.Mask" "F.Paste")
			(net "P3V3")
			(options
				(clearance outline)
				(anchor circle)
			)
			(primitives
				(gr_poly
					(pts
						(arc
							(start -0.1778 -0.2794)
							(mid -0.249642 -0.249642)
							(end -0.2794 -0.1778)
						)
						(arc
							(start -0.2794 0.1778)
							(mid -0.249642 0.249642)
							(end -0.1778 0.2794)
						)
						(arc
							(start 0.1778 0.2794)
							(mid 0.249642 0.249642)
							(end 0.2794 0.1778)
						)
						(arc
							(start 0.2794 -0.1778)
							(mid 0.249642 -0.249642)
							(end 0.1778 -0.2794)
						)
					)
					(width 0)
					(fill yes)
				)
			)
		)
		(pad "2" smd custom
			(at 0 0.4445 270)
			(size 0.1397 0.1397)
			(layers "F.Cu" "F.Mask" "F.Paste")
			(net "DRV_ACT_12")
			(options
				(clearance outline)
				(anchor circle)
			)
			(primitives
				(gr_poly
					(pts
						(arc
							(start -0.1778 -0.2794)
							(mid -0.249642 -0.249642)
							(end -0.2794 -0.1778)
						)
						(arc
							(start -0.2794 0.1778)
							(mid -0.249642 0.249642)
							(end -0.1778 0.2794)
						)
						(arc
							(start 0.1778 0.2794)
							(mid 0.249642 0.249642)
							(end 0.2794 0.1778)
						)
						(arc
							(start 0.2794 -0.1778)
							(mid 0.249642 -0.249642)
							(end 0.1778 -0.2794)
						)
					)
					(width 0)
					(fill yes)
				)
			)
		)
	)
	(footprint ""
		(layer "F.Cu")
		(at 22.987 -393.827)
		(property "Reference" "R557"
			(at 0 0 0)
			(layer "F.SilkS")
			(hide yes)
			(effects
				(font
					(size 1.27 1.27)
				)
			)
		)
		(property "Value" "200KR2F-L-GP"
			(at 0.064008 -3.993896 0)
			(unlocked yes)
			(layer "F.Fab")
			(hide yes)
			(effects
				(font
					(size 1.016 1.016)
					(thickness 0.1524)
				)
			)
		)
		(property "Device Type" "R402H16"
			(at 0.064008 -5.517896 0)
			(unlocked yes)
			(layer "F.Fab")
			(hide yes)
			(effects
				(font
					(size 1.016 1.016)
					(thickness 0.1524)
				)
			)
		)
		(duplicate_pad_numbers_are_jumpers no)
		(fp_line
			(start -0.508 -0.9398)
			(end -0.508 0.9398)
			(stroke
				(width 0.1524)
				(type default)
			)
			(layer "F.SilkS")
		)
		(fp_line
			(start 0.508 -0.9398)
			(end -0.508 -0.9398)
			(stroke
				(width 0.1524)
				(type default)
			)
			(layer "F.SilkS")
		)
		(fp_rect
			(start -0.508 0.9398)
			(end 0.508 -0.9398)
			(stroke
				(width 0)
				(type default)
			)
			(fill no)
			(layer "F.CrtYd")
		)
		(fp_rect
			(start -0.508 0.9398)
			(end 0.508 -0.9398)
			(stroke
				(width 0)
				(type default)
			)
			(fill no)
			(layer "F.Fab")
		)
		(pad "1" smd custom
			(at 0 -0.4445)
			(size 0.1397 0.1397)
			(layers "F.Cu" "F.Mask" "F.Paste")
			(net "SW_SSD6_R")
			(options
				(clearance outline)
				(anchor circle)
			)
			(primitives
				(gr_poly
					(pts
						(arc
							(start -0.1778 -0.2794)
							(mid -0.249642 -0.249642)
							(end -0.2794 -0.1778)
						)
						(arc
							(start -0.2794 0.1778)
							(mid -0.249642 0.249642)
							(end -0.1778 0.2794)
						)
						(arc
							(start 0.1778 0.2794)
							(mid 0.249642 0.249642)
							(end 0.2794 0.1778)
						)
						(arc
							(start 0.2794 -0.1778)
							(mid 0.249642 -0.249642)
							(end 0.1778 -0.2794)
						)
					)
					(width 0)
					(fill yes)
				)
			)
		)
		(pad "2" smd custom
			(at 0 0.4445)
			(size 0.1397 0.1397)
			(layers "F.Cu" "F.Mask" "F.Paste")
			(net "SW_SSD6_N")
			(options
				(clearance outline)
				(anchor circle)
			)
			(primitives
				(gr_poly
					(pts
						(arc
							(start -0.1778 -0.2794)
							(mid -0.249642 -0.249642)
							(end -0.2794 -0.1778)
						)
						(arc
							(start -0.2794 0.1778)
							(mid -0.249642 0.249642)
							(end -0.1778 0.2794)
						)
						(arc
							(start 0.1778 0.2794)
							(mid 0.249642 0.249642)
							(end 0.2794 0.1778)
						)
						(arc
							(start 0.2794 -0.1778)
							(mid 0.249642 -0.249642)
							(end 0.1778 -0.2794)
						)
					)
					(width 0)
					(fill yes)
				)
			)
		)
	)
	(footprint ""
		(layer "F.Cu")
		(at 24.003 -300.228)
		(property "Reference" "R9767"
			(at 0 0 0)
			(layer "F.SilkS")
			(hide yes)
			(effects
				(font
					(size 1.27 1.27)
				)
			)
		)
		(property "Value" "4K7R2J-2-GP"
			(at 0.064008 -3.993896 0)
			(unlocked yes)
			(layer "F.Fab")
			(hide yes)
			(effects
				(font
					(size 1.016 1.016)
					(thickness 0.1524)
				)
			)
		)
		(property "Device Type" "R402H16"
			(at 0.064008 -5.517896 0)
			(unlocked yes)
			(layer "F.Fab")
			(hide yes)
			(effects
				(font
					(size 1.016 1.016)
					(thickness 0.1524)
				)
			)
		)
		(duplicate_pad_numbers_are_jumpers no)
		(fp_line
			(start -0.508 -0.9398)
			(end -0.508 0.9398)
			(stroke
				(width 0.1524)
				(type default)
			)
			(layer "F.SilkS")
		)
		(fp_line
			(start 0.508 -0.9398)
			(end -0.508 -0.9398)
			(stroke
				(width 0.1524)
				(type default)
			)
			(layer "F.SilkS")
		)
		(fp_rect
			(start -0.508 0.9398)
			(end 0.508 -0.9398)
			(stroke
				(width 0)
				(type default)
			)
			(fill no)
			(layer "F.CrtYd")
		)
		(fp_rect
			(start -0.508 0.9398)
			(end 0.508 -0.9398)
			(stroke
				(width 0)
				(type default)
			)
			(fill no)
			(layer "F.Fab")
		)
		(pad "1" smd custom
			(at 0 -0.4445)
			(size 0.1397 0.1397)
			(layers "F.Cu" "F.Mask" "F.Paste")
			(net "SSD7_PWREN")
			(options
				(clearance outline)
				(anchor circle)
			)
			(primitives
				(gr_poly
					(pts
						(arc
							(start -0.1778 -0.2794)
							(mid -0.249642 -0.249642)
							(end -0.2794 -0.1778)
						)
						(arc
							(start -0.2794 0.1778)
							(mid -0.249642 0.249642)
							(end -0.1778 0.2794)
						)
						(arc
							(start 0.1778 0.2794)
							(mid 0.249642 0.249642)
							(end 0.2794 0.1778)
						)
						(arc
							(start 0.2794 -0.1778)
							(mid 0.249642 -0.249642)
							(end 0.1778 -0.2794)
						)
					)
					(width 0)
					(fill yes)
				)
			)
		)
		(pad "2" smd custom
			(at 0 0.4445)
			(size 0.1397 0.1397)
			(layers "F.Cu" "F.Mask" "F.Paste")
			(net "GND")
			(options
				(clearance outline)
				(anchor circle)
			)
			(primitives
				(gr_poly
					(pts
						(arc
							(start -0.1778 -0.2794)
							(mid -0.249642 -0.249642)
							(end -0.2794 -0.1778)
						)
						(arc
							(start -0.2794 0.1778)
							(mid -0.249642 0.249642)
							(end -0.1778 0.2794)
						)
						(arc
							(start 0.1778 0.2794)
							(mid 0.249642 0.249642)
							(end 0.2794 0.1778)
						)
						(arc
							(start 0.2794 -0.1778)
							(mid 0.249642 -0.249642)
							(end 0.1778 -0.2794)
						)
					)
					(width 0)
					(fill yes)
				)
			)
		)
	)
	(footprint ""
		(layer "F.Cu")
		(at 41.150032 -479.67011 90)
		(property "Reference" "J5"
			(at 0 0 90)
			(layer "F.SilkS")
			(hide yes)
			(effects
				(font
					(size 1.27 1.27)
				)
			)
		)
		(property "Value" "PCISLT68-14-GP-U1"
			(at -22.225 12.7508 90)
			(unlocked yes)
			(layer "F.Fab")
			(hide yes)
			(effects
				(font
					(size 1.016 1.016)
					(thickness 0.1524)
				)
			)
		)
		(property "Device Type" "SD-78827-0001"
			(at -22.225 11.2268 90)
			(unlocked yes)
			(layer "F.Fab")
			(hide yes)
			(effects
				(font
					(size 1.016 1.016)
					(thickness 0.1524)
				)
			)
		)
		(duplicate_pad_numbers_are_jumpers no)
		(fp_line
			(start 20.4724 -3.4036)
			(end 20.4724 0.0254)
			(stroke
				(width 0.1524)
				(type default)
			)
			(layer "F.SilkS")
		)
		(fp_line
			(start -20.4724 -3.4036)
			(end 20.4724 -3.4036)
			(stroke
				(width 0.1524)
				(type default)
			)
			(layer "F.SilkS")
		)
		(fp_line
			(start 23.749 0.0254)
			(end 23.749 4.6736)
			(stroke
				(width 0.1524)
				(type default)
			)
			(layer "F.SilkS")
		)
		(fp_line
			(start 20.4724 0.0254)
			(end 23.749 0.0254)
			(stroke
				(width 0.1524)
				(type default)
			)
			(layer "F.SilkS")
		)
		(fp_line
			(start -20.4724 0.0254)
			(end -20.4724 -3.4036)
			(stroke
				(width 0.1524)
				(type default)
			)
			(layer "F.SilkS")
		)
		(fp_line
			(start -23.749 0.0254)
			(end -20.4724 0.0254)
			(stroke
				(width 0.1524)
				(type default)
			)
			(layer "F.SilkS")
		)
		(fp_line
			(start 23.117556 1.803908)
			(end 23.117556 2.896108)
			(stroke
				(width 0.3048)
				(type default)
			)
			(layer "F.SilkS")
		)
		(fp_line
			(start -20.882356 1.803908)
			(end -20.882356 2.896108)
			(stroke
				(width 0.3048)
				(type default)
			)
			(layer "F.SilkS")
		)
		(fp_line
			(start 20.882356 2.896108)
			(end 20.882356 1.803908)
			(stroke
				(width 0.3048)
				(type default)
			)
			(layer "F.SilkS")
		)
		(fp_line
			(start -23.117556 2.896108)
			(end -23.117556 1.803908)
			(stroke
				(width 0.3048)
				(type default)
			)
			(layer "F.SilkS")
		)
		(fp_line
			(start 23.749 4.6736)
			(end 20.4724 4.6736)
			(stroke
				(width 0.1524)
				(type default)
			)
			(layer "F.SilkS")
		)
		(fp_line
			(start 20.4724 4.6736)
			(end 20.4724 12.0142)
			(stroke
				(width 0.1524)
				(type default)
			)
			(layer "F.SilkS")
		)
		(fp_line
			(start -20.4724 4.6736)
			(end -23.749 4.6736)
			(stroke
				(width 0.1524)
				(type default)
			)
			(layer "F.SilkS")
		)
		(fp_line
			(start -23.749 4.6736)
			(end -23.749 0.0254)
			(stroke
				(width 0.1524)
				(type default)
			)
			(layer "F.SilkS")
		)
		(fp_line
			(start 17.8435 10.3124)
			(end -17.8435 10.3124)
			(stroke
				(width 0.1524)
				(type default)
			)
			(layer "F.SilkS")
		)
		(fp_line
			(start -17.8435 10.3124)
			(end -17.8435 12.0142)
			(stroke
				(width 0.1524)
				(type default)
			)
			(layer "F.SilkS")
		)
		(fp_line
			(start 20.4724 12.0142)
			(end 17.8435 12.0142)
			(stroke
				(width 0.1524)
				(type default)
			)
			(layer "F.SilkS")
		)
		(fp_line
			(start 17.8435 12.0142)
			(end 17.8435 10.3124)
			(stroke
				(width 0.1524)
				(type default)
			)
			(layer "F.SilkS")
		)
		(fp_line
			(start -17.8435 12.0142)
			(end -20.4724 12.0142)
			(stroke
				(width 0.1524)
				(type default)
			)
			(layer "F.SilkS")
		)
		(fp_line
			(start -20.4724 12.0142)
			(end -20.4724 4.6736)
			(stroke
				(width 0.1524)
				(type default)
			)
			(layer "F.SilkS")
		)
		(fp_arc
			(start 20.882356 1.803908)
			(mid 21.999956 0.686308)
			(end 23.117556 1.803908)
			(stroke
				(width 0.3048)
				(type default)
			)
			(layer "F.SilkS")
		)
		(fp_arc
			(start -23.117556 1.803908)
			(mid -21.999956 0.686308)
			(end -20.882356 1.803908)
			(stroke
				(width 0.3048)
				(type default)
			)
			(layer "F.SilkS")
		)
		(fp_arc
			(start 23.117556 2.896108)
			(mid 21.999956 4.013708)
			(end 20.882356 2.896108)
			(stroke
				(width 0.3048)
				(type default)
			)
			(layer "F.SilkS")
		)
		(fp_arc
			(start -20.882356 2.896108)
			(mid -21.999956 4.013708)
			(end -23.117556 2.896108)
			(stroke
				(width 0.3048)
				(type default)
			)
			(layer "F.SilkS")
		)
		(fp_poly
			(pts
				(xy -20.2184 11.7602) (xy -20.2184 4.4196) (xy -23.495 4.4196) (xy -23.495 0.2794) (xy -20.2184 0.2794)
				(xy -20.2184 -3.1496) (xy 20.2184 -3.1496) (xy 20.2184 0.2794) (xy 23.495 0.2794) (xy 23.495 4.4196)
				(xy 20.2184 4.4196) (xy 20.2184 11.7602) (xy 18.0975 11.7602) (xy 18.0975 10.0584) (xy -18.0975 10.0584)
				(xy -18.0975 11.7602)
			)
			(stroke
				(width 0)
				(type default)
			)
			(fill no)
			(layer "F.CrtYd")
		)
		(fp_poly
			(pts
				(xy -21.2471 16.256) (xy -21.2471 4.9276) (xy -24.003 4.9276) (xy -24.003 -0.2286) (xy -20.7264 -0.2286)
				(xy -20.7264 -3.6576) (xy 20.7264 -3.6576) (xy 20.7264 -0.2286) (xy 24.003 -0.2286) (xy 24.003 -0.00635)
				(xy 20.2184 -0.00635) (xy 20.2184 -3.1496) (xy -20.2184 -3.1496) (xy -20.2184 0.2794) (xy -23.495 0.2794)
				(xy -23.495 4.4196) (xy -20.2184 4.4196) (xy -20.2184 11.7602) (xy -18.0975 11.7602) (xy -18.0975 10.0584)
				(xy 18.0975 10.0584) (xy 18.0975 11.7602) (xy 20.2184 11.7602) (xy 20.2184 4.4196) (xy 23.495 4.4196)
				(xy 23.495 0.2794) (xy 20.2184 0.2794) (xy 20.2184 0.00635) (xy 24.003 0.00635) (xy 24.003 4.9276)
				(xy 21.2471 4.9276) (xy 21.2471 16.256)
			)
			(stroke
				(width 0)
				(type default)
			)
			(fill no)
			(layer "F.CrtYd")
		)
		(fp_poly
			(pts
				(xy -21.2471 16.256) (xy -21.2471 4.9276) (xy -24.003 4.9276) (xy -24.003 -0.2286) (xy -20.7264 -0.2286)
				(xy -20.7264 -3.6576) (xy 20.7264 -3.6576) (xy 20.7264 -0.2286) (xy 24.003 -0.2286) (xy 24.003 4.9276)
				(xy 21.2471 4.9276) (xy 21.2471 16.256)
			)
			(stroke
				(width 0)
				(type default)
			)
			(fill no)
			(layer "F.Fab")
		)
		(pad "" np_thru_hole circle
			(at -18.999962 0 90)
			(size 0.254 0.254)
			(drill 1.8542)
			(layers "*.Cu" "*.Mask")
			(clearance 1.1557)
			(thermal_gap 1.1557)
		)
		(pad "" np_thru_hole circle
			(at 18.999962 0 90)
			(size 0.254 0.254)
			(drill 1.8542)
			(layers "*.Cu" "*.Mask")
			(clearance 1.1557)
			(thermal_gap 1.1557)
		)
		(pad "E1" smd rect
			(at -7.079996 1.240028 90)
			(size 0.508 2.0066)
			(layers "F.Cu" "F.Mask" "F.Paste")
			(net "PE_CLK100M_DR5_2_P")
		)
		(pad "E2" smd rect
			(at -6.279896 1.240028 90)
			(size 0.508 2.0066)
			(layers "F.Cu" "F.Mask" "F.Paste")
			(net "PE_CLK100M_DR5_2_N")
		)
		(pad "E3" smd rect
			(at -5.48005 1.240028 90)
			(size 0.508 2.0066)
			(layers "F.Cu" "F.Mask" "F.Paste")
			(net "P3V3")
		)
		(pad "E4" smd rect
			(at -4.67995 1.240028 90)
			(size 0.508 2.0066)
			(layers "F.Cu" "F.Mask" "F.Paste")
			(net "SSD5_PERST_N")
		)
		(pad "E5" smd rect
			(at -3.880104 1.240028 90)
			(size 0.508 2.0066)
			(layers "F.Cu" "F.Mask" "F.Paste")
			(net "SSD5_PERST_N")
		)
		(pad "E6" smd rect
			(at -3.080004 1.240028 90)
			(size 0.508 2.0066)
			(layers "F.Cu" "F.Mask" "F.Paste")
			(net "Net_1143")
		)
		(pad "E7" smd rect
			(at -15.48003 -1.949958 90)
			(size 0.508 2.0066)
			(layers "F.Cu" "F.Mask" "F.Paste")
			(net "PE_CLK100M_DR5_1_P")
		)
		(pad "E8" smd rect
			(at -14.67993 -1.949958 90)
			(size 0.508 2.0066)
			(layers "F.Cu" "F.Mask" "F.Paste")
			(net "PE_CLK100M_DR5_1_N")
		)
		(pad "E9" smd rect
			(at -13.880084 -1.949958 90)
			(size 0.508 2.0066)
			(layers "F.Cu" "F.Mask" "F.Paste")
			(net "GND")
		)
		(pad "E10" smd rect
			(at -13.079984 -1.949958 90)
			(size 0.508 2.0066)
			(layers "F.Cu" "F.Mask" "F.Paste")
			(net "PE_TX1_DR5_P")
		)
		(pad "E11" smd rect
			(at -12.279884 -1.949958 90)
			(size 0.508 2.0066)
			(layers "F.Cu" "F.Mask" "F.Paste")
			(net "PE_TX1_DR5_N")
		)
		(pad "E12" smd rect
			(at -11.480038 -1.949958 90)
			(size 0.508 2.0066)
			(layers "F.Cu" "F.Mask" "F.Paste")
			(net "GND")
		)
		(pad "E13" smd rect
			(at -10.679938 -1.949958 90)
			(size 0.508 2.0066)
			(layers "F.Cu" "F.Mask" "F.Paste")
			(net "PE_RX1_DR5_P")
		)
		(pad "E14" smd rect
			(at -9.880092 -1.949958 90)
			(size 0.508 2.0066)
			(layers "F.Cu" "F.Mask" "F.Paste")
			(net "PE_RX1_DR5_N")
		)
		(pad "E15" smd rect
			(at -9.079992 -1.949958 90)
			(size 0.508 2.0066)
			(layers "F.Cu" "F.Mask" "F.Paste")
			(net "GND")
		)
		(pad "E16" smd rect
			(at -8.279892 -1.949958 90)
			(size 0.508 2.0066)
			(layers "F.Cu" "F.Mask" "F.Paste")
			(net "Net_1150")
		)
		(pad "E17" smd rect
			(at 9.320022 -1.949958 90)
			(size 0.508 2.0066)
			(layers "F.Cu" "F.Mask" "F.Paste")
			(net "PE_TX4_DR5_P")
		)
		(pad "E18" smd rect
			(at 10.120122 -1.949958 90)
			(size 0.508 2.0066)
			(layers "F.Cu" "F.Mask" "F.Paste")
			(net "PE_TX4_DR5_N")
		)
		(pad "E19" smd rect
			(at 10.919968 -1.949958 90)
			(size 0.508 2.0066)
			(layers "F.Cu" "F.Mask" "F.Paste")
			(net "GND")
		)
		(pad "E20" smd rect
			(at 11.720068 -1.949958 90)
			(size 0.508 2.0066)
			(layers "F.Cu" "F.Mask" "F.Paste")
			(net "PE_RX4_DR5_P")
		)
		(pad "E21" smd rect
			(at 12.519914 -1.949958 90)
			(size 0.508 2.0066)
			(layers "F.Cu" "F.Mask" "F.Paste")
			(net "PE_RX4_DR5_N")
		)
		(pad "E22" smd rect
			(at 13.320014 -1.949958 90)
			(size 0.508 2.0066)
			(layers "F.Cu" "F.Mask" "F.Paste")
			(net "GND")
		)
		(pad "E23" smd rect
			(at 14.120114 -1.949958 90)
			(size 0.508 2.0066)
			(layers "F.Cu" "F.Mask" "F.Paste")
			(net "SCL_DR5_R")
		)
		(pad "E24" smd rect
			(at 14.91996 -1.949958 90)
			(size 0.508 2.0066)
			(layers "F.Cu" "F.Mask" "F.Paste")
			(net "SDA_DR5_R")
		)
		(pad "E25" smd rect
			(at 15.72006 -1.949958 90)
			(size 0.508 2.0066)
			(layers "F.Cu" "F.Mask" "F.Paste")
			(net "DUALPORTEN#5")
		)
		(pad "P1" smd rect
			(at -1.905 0.824992 90)
			(size 0.6604 2.0574)
			(layers "F.Cu" "F.Mask" "F.Paste")
			(net "Net_1146")
		)
		(pad "P2" smd rect
			(at -0.635 0.824992 90)
			(size 0.6604 2.0574)
			(layers "F.Cu" "F.Mask" "F.Paste")
			(net "Net_1145")
		)
		(pad "P3" smd rect
			(at 0.635 0.824992 90)
			(size 0.6604 2.0574)
			(layers "F.Cu" "F.Mask" "F.Paste")
			(net "Net_1144")
		)
		(pad "P4" smd rect
			(at 1.905 0.824992 90)
			(size 0.6604 2.0574)
			(layers "F.Cu" "F.Mask" "F.Paste")
			(net "SSD5_CLK0_OE_N")
		)
		(pad "P5" smd rect
			(at 3.175 0.824992 90)
			(size 0.6604 2.0574)
			(layers "F.Cu" "F.Mask" "F.Paste")
			(net "GND")
		)
		(pad "P6" smd rect
			(at 4.445 0.824992 90)
			(size 0.6604 2.0574)
			(layers "F.Cu" "F.Mask" "F.Paste")
			(net "GND")
		)
		(pad "P7" smd rect
			(at 5.715 0.824992 90)
			(size 0.6604 2.0574)
			(layers "F.Cu" "F.Mask" "F.Paste")
			(net "Net_90")
		)
		(pad "P8" smd rect
			(at 6.985 0.824992 90)
			(size 0.6604 2.0574)
			(layers "F.Cu" "F.Mask" "F.Paste")
			(net "Net_62")
		)
		(pad "P9" smd rect
			(at 8.255 0.824992 90)
			(size 0.6604 2.0574)
			(layers "F.Cu" "F.Mask" "F.Paste")
			(net "Net_76")
		)
		(pad "P10" smd rect
			(at 9.525 0.824992 90)
			(size 0.6604 2.0574)
			(layers "F.Cu" "F.Mask" "F.Paste")
			(net "SSD_PRSNT_NET5")
		)
		(pad "P11" smd rect
			(at 10.795 0.824992 90)
			(size 0.6604 2.0574)
			(layers "F.Cu" "F.Mask" "F.Paste")
			(net "SSD_ACT_DR5")
		)
		(pad "P12" smd rect
			(at 12.065 0.824992 90)
			(size 0.6604 2.0574)
			(layers "F.Cu" "F.Mask" "F.Paste")
			(net "GND")
		)
		(pad "P13" smd rect
			(at 13.335 0.824992 90)
			(size 0.6604 2.0574)
			(layers "F.Cu" "F.Mask" "F.Paste")
			(net "12V_PRECH_SSD5")
		)
		(pad "P14" smd rect
			(at 14.605 0.824992 90)
			(size 0.6604 2.0574)
			(layers "F.Cu" "F.Mask" "F.Paste")
			(net "P12V_SSD5")
		)
		(pad "P15" smd rect
			(at 15.875 0.824992 90)
			(size 0.6604 2.0574)
			(layers "F.Cu" "F.Mask" "F.Paste")
			(net "P12V_SSD5")
		)
		(pad "PTH1" thru_hole oval
			(at -21.999956 2.350008 90)
			(size 1.524 2.6162)
			(drill oval 0.8128 1.905)
			(layers "*.Cu" "*.Mask")
			(remove_unused_layers no)
			(net "Net_1155")
			(clearance 0.1524)
			(thermal_gap 0.1524)
		)
		(pad "PTH2" thru_hole oval
			(at 21.999956 2.350008 90)
			(size 1.524 2.6162)
			(drill oval 0.8128 1.905)
			(layers "*.Cu" "*.Mask")
			(remove_unused_layers no)
			(net "Net_1139")
			(clearance 0.1524)
			(thermal_gap 0.1524)
		)
		(pad "S1" smd rect
			(at -15.875 0.824992 90)
			(size 0.6604 2.0574)
			(layers "F.Cu" "F.Mask" "F.Paste")
			(net "GND")
		)
		(pad "S2" smd rect
			(at -14.605 0.824992 90)
			(size 0.6604 2.0574)
			(layers "F.Cu" "F.Mask" "F.Paste")
			(net "Net_1154")
		)
		(pad "S3" smd rect
			(at -13.335 0.824992 90)
			(size 0.6604 2.0574)
			(layers "F.Cu" "F.Mask" "F.Paste")
			(net "Net_1153")
		)
		(pad "S4" smd rect
			(at -12.065 0.824992 90)
			(size 0.6604 2.0574)
			(layers "F.Cu" "F.Mask" "F.Paste")
			(net "GND")
		)
		(pad "S5" smd rect
			(at -10.795 0.824992 90)
			(size 0.6604 2.0574)
			(layers "F.Cu" "F.Mask" "F.Paste")
			(net "Net_1152")
		)
		(pad "S6" smd rect
			(at -9.525 0.824992 90)
			(size 0.6604 2.0574)
			(layers "F.Cu" "F.Mask" "F.Paste")
			(net "Net_1151")
		)
		(pad "S7" smd rect
			(at -8.255 0.824992 90)
			(size 0.6604 2.0574)
			(layers "F.Cu" "F.Mask" "F.Paste")
			(net "GND")
		)
		(pad "S8" smd rect
			(at -7.480046 -1.949958 90)
			(size 0.508 2.0066)
			(layers "F.Cu" "F.Mask" "F.Paste")
			(net "GND")
		)
		(pad "S9" smd rect
			(at -6.679946 -1.949958 90)
			(size 0.508 2.0066)
			(layers "F.Cu" "F.Mask" "F.Paste")
			(net "Net_1149")
		)
		(pad "S10" smd rect
			(at -5.8801 -1.949958 90)
			(size 0.508 2.0066)
			(layers "F.Cu" "F.Mask" "F.Paste")
			(net "Net_1148")
		)
		(pad "S11" smd rect
			(at -5.08 -1.949958 90)
			(size 0.508 2.0066)
			(layers "F.Cu" "F.Mask" "F.Paste")
			(net "GND")
		)
		(pad "S12" smd rect
			(at -4.2799 -1.949958 90)
			(size 0.508 2.0066)
			(layers "F.Cu" "F.Mask" "F.Paste")
			(net "Net_1147")
		)
		(pad "S13" smd rect
			(at -3.480054 -1.949958 90)
			(size 0.508 2.0066)
			(layers "F.Cu" "F.Mask" "F.Paste")
			(net "Net_1142")
		)
		(pad "S14" smd rect
			(at -2.679954 -1.949958 90)
			(size 0.508 2.0066)
			(layers "F.Cu" "F.Mask" "F.Paste")
			(net "GND")
		)
		(pad "S15" smd rect
			(at -1.880108 -1.949958 90)
			(size 0.508 2.0066)
			(layers "F.Cu" "F.Mask" "F.Paste")
			(net "Net_1141")
		)
		(pad "S16" smd rect
			(at -1.080008 -1.949958 90)
			(size 0.508 2.0066)
			(layers "F.Cu" "F.Mask" "F.Paste")
			(net "GND")
		)
		(pad "S17" smd rect
			(at -0.279908 -1.949958 90)
			(size 0.508 2.0066)
			(layers "F.Cu" "F.Mask" "F.Paste")
			(net "PE_TX2_DR5_P")
		)
		(pad "S18" smd rect
			(at 0.519938 -1.949958 90)
			(size 0.508 2.0066)
			(layers "F.Cu" "F.Mask" "F.Paste")
			(net "PE_TX2_DR5_N")
		)
		(pad "S19" smd rect
			(at 1.320038 -1.949958 90)
			(size 0.508 2.0066)
			(layers "F.Cu" "F.Mask" "F.Paste")
			(net "GND")
		)
		(pad "S20" smd rect
			(at 2.119884 -1.949958 90)
			(size 0.508 2.0066)
			(layers "F.Cu" "F.Mask" "F.Paste")
			(net "PE_RX2_DR5_P")
		)
		(pad "S21" smd rect
			(at 2.919984 -1.949958 90)
			(size 0.508 2.0066)
			(layers "F.Cu" "F.Mask" "F.Paste")
			(net "PE_RX2_DR5_N")
		)
		(pad "S22" smd rect
			(at 3.720084 -1.949958 90)
			(size 0.508 2.0066)
			(layers "F.Cu" "F.Mask" "F.Paste")
			(net "GND")
		)
		(pad "S23" smd rect
			(at 4.51993 -1.949958 90)
			(size 0.508 2.0066)
			(layers "F.Cu" "F.Mask" "F.Paste")
			(net "PE_TX3_DR5_P")
		)
		(pad "S24" smd rect
			(at 5.32003 -1.949958 90)
			(size 0.508 2.0066)
			(layers "F.Cu" "F.Mask" "F.Paste")
			(net "PE_TX3_DR5_N")
		)
		(pad "S25" smd rect
			(at 6.119876 -1.949958 90)
			(size 0.508 2.0066)
			(layers "F.Cu" "F.Mask" "F.Paste")
			(net "GND")
		)
		(pad "S26" smd rect
			(at 6.919976 -1.949958 90)
			(size 0.508 2.0066)
			(layers "F.Cu" "F.Mask" "F.Paste")
			(net "PE_RX3_DR5_P")
		)
		(pad "S27" smd rect
			(at 7.720076 -1.949958 90)
			(size 0.508 2.0066)
			(layers "F.Cu" "F.Mask" "F.Paste")
			(net "PE_RX3_DR5_N")
		)
		(pad "S28" smd rect
			(at 8.519922 -1.949958 90)
			(size 0.508 2.0066)
			(layers "F.Cu" "F.Mask" "F.Paste")
			(net "GND")
		)
		(zone
			(layers "F.Cu" "B.Cu" "In1.Cu" "In2.Cu" "In3.Cu" "In4.Cu" "In5.Cu" "In6.Cu")
			(hatch none 0.5)
			(connect_pads
				(clearance 0)
			)
			(min_thickness 0.25)
			(keepout
				(tracks not_allowed)
				(vias allowed)
				(pads allowed)
				(copperpour not_allowed)
				(footprints allowed)
			)
			(placement
				(enabled no)
				(sheetname "")
			)
			(fill
				(thermal_gap 0.5)
				(thermal_bridge_width 0.5)
				(island_removal_mode 0)
			)
			(polygon
				(pts
					(arc
						(start 42.381932 -498.670072)
						(mid 39.918132 -498.670072)
						(end 42.381932 -498.670072)
					)
				)
			)
		)
		(zone
			(layers "F.Cu" "B.Cu" "In1.Cu" "In2.Cu" "In3.Cu" "In4.Cu" "In5.Cu" "In6.Cu")
			(hatch none 0.5)
			(connect_pads
				(clearance 0)
			)
			(min_thickness 0.25)
			(keepout
				(tracks not_allowed)
				(vias allowed)
				(pads allowed)
				(copperpour not_allowed)
				(footprints allowed)
			)
			(placement
				(enabled no)
				(sheetname "")
			)
			(fill
				(thermal_gap 0.5)
				(thermal_bridge_width 0.5)
				(island_removal_mode 0)
			)
			(polygon
				(pts
					(arc
						(start 42.381932 -460.670148)
						(mid 39.918132 -460.670148)
						(end 42.381932 -460.670148)
					)
				)
			)
		)
	)
	(footprint ""
		(layer "F.Cu")
		(at 91.313 -423.164)
		(property "Reference" "R9070"
			(at 0 0 0)
			(layer "F.SilkS")
			(hide yes)
			(effects
				(font
					(size 1.27 1.27)
				)
			)
		)
		(property "Value" "27R2F-GP"
			(at 0.064008 -3.993896 0)
			(unlocked yes)
			(layer "F.Fab")
			(hide yes)
			(effects
				(font
					(size 1.016 1.016)
					(thickness 0.1524)
				)
			)
		)
		(property "Device Type" "R402H16"
			(at 0.064008 -5.517896 0)
			(unlocked yes)
			(layer "F.Fab")
			(hide yes)
			(effects
				(font
					(size 1.016 1.016)
					(thickness 0.1524)
				)
			)
		)
		(duplicate_pad_numbers_are_jumpers no)
		(fp_line
			(start -0.508 -0.9398)
			(end -0.508 0.9398)
			(stroke
				(width 0.1524)
				(type default)
			)
			(layer "F.SilkS")
		)
		(fp_line
			(start 0.508 -0.9398)
			(end -0.508 -0.9398)
			(stroke
				(width 0.1524)
				(type default)
			)
			(layer "F.SilkS")
		)
		(fp_rect
			(start -0.508 0.9398)
			(end 0.508 -0.9398)
			(stroke
				(width 0)
				(type default)
			)
			(fill no)
			(layer "F.CrtYd")
		)
		(fp_rect
			(start -0.508 0.9398)
			(end 0.508 -0.9398)
			(stroke
				(width 0)
				(type default)
			)
			(fill no)
			(layer "F.Fab")
		)
		(pad "1" smd custom
			(at 0 -0.4445)
			(size 0.1397 0.1397)
			(layers "F.Cu" "F.Mask" "F.Paste")
			(net "PE_CLK_100M_DR10_1_R_N")
			(options
				(clearance outline)
				(anchor circle)
			)
			(primitives
				(gr_poly
					(pts
						(arc
							(start -0.1778 -0.2794)
							(mid -0.249642 -0.249642)
							(end -0.2794 -0.1778)
						)
						(arc
							(start -0.2794 0.1778)
							(mid -0.249642 0.249642)
							(end -0.1778 0.2794)
						)
						(arc
							(start 0.1778 0.2794)
							(mid 0.249642 0.249642)
							(end 0.2794 0.1778)
						)
						(arc
							(start 0.2794 -0.1778)
							(mid 0.249642 -0.249642)
							(end 0.1778 -0.2794)
						)
					)
					(width 0)
					(fill yes)
				)
			)
		)
		(pad "2" smd custom
			(at 0 0.4445)
			(size 0.1397 0.1397)
			(layers "F.Cu" "F.Mask" "F.Paste")
			(net "PE_CLK100M_DR10_1_N")
			(options
				(clearance outline)
				(anchor circle)
			)
			(primitives
				(gr_poly
					(pts
						(arc
							(start -0.1778 -0.2794)
							(mid -0.249642 -0.249642)
							(end -0.2794 -0.1778)
						)
						(arc
							(start -0.2794 0.1778)
							(mid -0.249642 0.249642)
							(end -0.1778 0.2794)
						)
						(arc
							(start 0.1778 0.2794)
							(mid 0.249642 0.249642)
							(end 0.2794 0.1778)
						)
						(arc
							(start 0.2794 -0.1778)
							(mid 0.249642 -0.249642)
							(end 0.1778 -0.2794)
						)
					)
					(width 0)
					(fill yes)
				)
			)
		)
	)
	(footprint ""
		(layer "F.Cu")
		(at 16.55953 -257.158744 90)
		(property "Reference" "R9952"
			(at 0 0 90)
			(layer "F.SilkS")
			(hide yes)
			(effects
				(font
					(size 1.27 1.27)
				)
			)
		)
		(property "Value" "4K7R2J-2-GP"
			(at 0.064008 -3.993896 90)
			(unlocked yes)
			(layer "F.Fab")
			(hide yes)
			(effects
				(font
					(size 1.016 1.016)
					(thickness 0.1524)
				)
			)
		)
		(property "Device Type" "R402H16"
			(at 0.064008 -5.517896 90)
			(unlocked yes)
			(layer "F.Fab")
			(hide yes)
			(effects
				(font
					(size 1.016 1.016)
					(thickness 0.1524)
				)
			)
		)
		(duplicate_pad_numbers_are_jumpers no)
		(fp_line
			(start 0.508 -0.9398)
			(end -0.508 -0.9398)
			(stroke
				(width 0.1524)
				(type default)
			)
			(layer "F.SilkS")
		)
		(fp_line
			(start -0.508 -0.9398)
			(end -0.508 0.9398)
			(stroke
				(width 0.1524)
				(type default)
			)
			(layer "F.SilkS")
		)
		(fp_rect
			(start -0.508 0.9398)
			(end 0.508 -0.9398)
			(stroke
				(width 0)
				(type default)
			)
			(fill no)
			(layer "F.CrtYd")
		)
		(fp_rect
			(start -0.508 0.9398)
			(end 0.508 -0.9398)
			(stroke
				(width 0)
				(type default)
			)
			(fill no)
			(layer "F.Fab")
		)
		(pad "1" smd custom
			(at 0 -0.4445 90)
			(size 0.1397 0.1397)
			(layers "F.Cu" "F.Mask" "F.Paste")
			(net "P3V3")
			(options
				(clearance outline)
				(anchor circle)
			)
			(primitives
				(gr_poly
					(pts
						(arc
							(start -0.1778 -0.2794)
							(mid -0.249642 -0.249642)
							(end -0.2794 -0.1778)
						)
						(arc
							(start -0.2794 0.1778)
							(mid -0.249642 0.249642)
							(end -0.1778 0.2794)
						)
						(arc
							(start 0.1778 0.2794)
							(mid 0.249642 0.249642)
							(end 0.2794 0.1778)
						)
						(arc
							(start 0.2794 -0.1778)
							(mid 0.249642 -0.249642)
							(end 0.1778 -0.2794)
						)
					)
					(width 0)
					(fill yes)
				)
			)
		)
		(pad "2" smd custom
			(at 0 0.4445 90)
			(size 0.1397 0.1397)
			(layers "F.Cu" "F.Mask" "F.Paste")
			(net "SSD_ACT_DR12_MOS_N")
			(options
				(clearance outline)
				(anchor circle)
			)
			(primitives
				(gr_poly
					(pts
						(arc
							(start -0.1778 -0.2794)
							(mid -0.249642 -0.249642)
							(end -0.2794 -0.1778)
						)
						(arc
							(start -0.2794 0.1778)
							(mid -0.249642 0.249642)
							(end -0.1778 0.2794)
						)
						(arc
							(start 0.1778 0.2794)
							(mid 0.249642 0.249642)
							(end 0.2794 0.1778)
						)
						(arc
							(start 0.2794 -0.1778)
							(mid 0.249642 -0.249642)
							(end 0.1778 -0.2794)
						)
					)
					(width 0)
					(fill yes)
				)
			)
		)
	)
	(footprint ""
		(layer "F.Cu")
		(at 82.931 -307.34 90)
		(property "Reference" "SR949"
			(at 0 0 90)
			(layer "F.SilkS")
			(hide yes)
			(effects
				(font
					(size 1.27 1.27)
				)
			)
		)
		(property "Value" "4K7R2F-GP"
			(at 0.064008 -3.993896 90)
			(unlocked yes)
			(layer "F.Fab")
			(hide yes)
			(effects
				(font
					(size 1.016 1.016)
					(thickness 0.1524)
				)
			)
		)
		(property "Device Type" "R402H16"
			(at 0.064008 -5.517896 90)
			(unlocked yes)
			(layer "F.Fab")
			(hide yes)
			(effects
				(font
					(size 1.016 1.016)
					(thickness 0.1524)
				)
			)
		)
		(duplicate_pad_numbers_are_jumpers no)
		(fp_line
			(start 0.508 -0.9398)
			(end -0.508 -0.9398)
			(stroke
				(width 0.1524)
				(type default)
			)
			(layer "F.SilkS")
		)
		(fp_line
			(start -0.508 -0.9398)
			(end -0.508 0.9398)
			(stroke
				(width 0.1524)
				(type default)
			)
			(layer "F.SilkS")
		)
		(fp_rect
			(start -0.508 0.9398)
			(end 0.508 -0.9398)
			(stroke
				(width 0)
				(type default)
			)
			(fill no)
			(layer "F.CrtYd")
		)
		(fp_rect
			(start -0.508 0.9398)
			(end 0.508 -0.9398)
			(stroke
				(width 0)
				(type default)
			)
			(fill no)
			(layer "F.Fab")
		)
		(pad "1" smd custom
			(at 0 -0.4445 90)
			(size 0.1397 0.1397)
			(layers "F.Cu" "F.Mask" "F.Paste")
			(net "VDD_DIFF_2")
			(options
				(clearance outline)
				(anchor circle)
			)
			(primitives
				(gr_poly
					(pts
						(arc
							(start -0.1778 -0.2794)
							(mid -0.249642 -0.249642)
							(end -0.2794 -0.1778)
						)
						(arc
							(start -0.2794 0.1778)
							(mid -0.249642 0.249642)
							(end -0.1778 0.2794)
						)
						(arc
							(start 0.1778 0.2794)
							(mid 0.249642 0.249642)
							(end 0.2794 0.1778)
						)
						(arc
							(start 0.2794 -0.1778)
							(mid 0.249642 -0.249642)
							(end 0.1778 -0.2794)
						)
					)
					(width 0)
					(fill yes)
				)
			)
		)
		(pad "2" smd custom
			(at 0 0.4445 90)
			(size 0.1397 0.1397)
			(layers "F.Cu" "F.Mask" "F.Paste")
			(net "P3V3_PG")
			(options
				(clearance outline)
				(anchor circle)
			)
			(primitives
				(gr_poly
					(pts
						(arc
							(start -0.1778 -0.2794)
							(mid -0.249642 -0.249642)
							(end -0.2794 -0.1778)
						)
						(arc
							(start -0.2794 0.1778)
							(mid -0.249642 0.249642)
							(end -0.1778 0.2794)
						)
						(arc
							(start 0.1778 0.2794)
							(mid 0.249642 0.249642)
							(end 0.2794 0.1778)
						)
						(arc
							(start 0.2794 -0.1778)
							(mid 0.249642 -0.249642)
							(end 0.1778 -0.2794)
						)
					)
					(width 0)
					(fill yes)
				)
			)
		)
	)
	(footprint ""
		(layer "F.Cu")
		(at 52.324 -141.986 90)
		(property "Reference" "Q68"
			(at 0 0 90)
			(layer "F.SilkS")
			(hide yes)
			(effects
				(font
					(size 1.27 1.27)
				)
			)
		)
		(property "Value" "2N7002A-7-GP"
			(at 0.127 -8.9662 90)
			(unlocked yes)
			(layer "F.Fab")
			(hide yes)
			(effects
				(font
					(size 1.016 1.016)
					(thickness 0.1524)
				)
			)
		)
		(property "Device Type" "SOT23DGS2D4H48"
			(at 0.127 -10.4902 90)
			(unlocked yes)
			(layer "F.Fab")
			(hide yes)
			(effects
				(font
					(size 1.016 1.016)
					(thickness 0.1524)
				)
			)
		)
		(duplicate_pad_numbers_are_jumpers no)
		(fp_line
			(start 1.651 -1.778)
			(end -1.651 -1.778)
			(stroke
				(width 0.1524)
				(type default)
			)
			(layer "F.SilkS")
		)
		(fp_line
			(start -1.651 -1.778)
			(end -1.651 1.778)
			(stroke
				(width 0.1524)
				(type default)
			)
			(layer "F.SilkS")
		)
		(fp_line
			(start 1.651 1.778)
			(end 1.651 -1.778)
			(stroke
				(width 0.1524)
				(type default)
			)
			(layer "F.SilkS")
		)
		(fp_line
			(start -1.651 1.778)
			(end 1.651 1.778)
			(stroke
				(width 0.1524)
				(type default)
			)
			(layer "F.SilkS")
		)
		(fp_poly
			(pts
				(xy -1.778 1.8796) (xy -1.778 -1.8796) (xy 1.778 -1.8796) (xy 1.778 1.8796)
			)
			(stroke
				(width 0)
				(type default)
			)
			(fill no)
			(layer "F.CrtYd")
		)
		(fp_poly
			(pts
				(xy -1.778 1.8796) (xy -1.778 -1.8796) (xy 1.778 -1.8796) (xy 1.778 1.8796)
			)
			(stroke
				(width 0)
				(type default)
			)
			(fill no)
			(layer "F.Fab")
		)
		(pad "D" smd custom
			(at 0 -0.9525 90)
			(size 0.1905 0.1905)
			(layers "F.Cu" "F.Mask" "F.Paste")
			(net "SSD_ACT_DR8_MOS_N")
			(options
				(clearance outline)
				(anchor circle)
			)
			(primitives
				(gr_poly
					(pts
						(arc
							(start -0.1778 0.5715)
							(mid -0.321484 0.511984)
							(end -0.381 0.3683)
						)
						(arc
							(start -0.381 -0.3683)
							(mid -0.321484 -0.511984)
							(end -0.1778 -0.5715)
						)
						(arc
							(start 0.1778 -0.5715)
							(mid 0.321484 -0.511984)
							(end 0.381 -0.3683)
						)
						(arc
							(start 0.381 0.3683)
							(mid 0.321484 0.511984)
							(end 0.1778 0.5715)
						)
					)
					(width 0)
					(fill yes)
				)
			)
		)
		(pad "G" smd custom
			(at -0.98425 0.9525 90)
			(size 0.1905 0.1905)
			(layers "F.Cu" "F.Mask" "F.Paste")
			(net "ATTN_LED_DR8_AND_R")
			(options
				(clearance outline)
				(anchor circle)
			)
			(primitives
				(gr_poly
					(pts
						(arc
							(start -0.1778 0.5715)
							(mid -0.321484 0.511984)
							(end -0.381 0.3683)
						)
						(arc
							(start -0.381 -0.3683)
							(mid -0.321484 -0.511984)
							(end -0.1778 -0.5715)
						)
						(arc
							(start 0.1778 -0.5715)
							(mid 0.321484 -0.511984)
							(end 0.381 -0.3683)
						)
						(arc
							(start 0.381 0.3683)
							(mid 0.321484 0.511984)
							(end 0.1778 0.5715)
						)
					)
					(width 0)
					(fill yes)
				)
			)
		)
		(pad "S" smd custom
			(at 0.98425 0.9525 90)
			(size 0.1905 0.1905)
			(layers "F.Cu" "F.Mask" "F.Paste")
			(net "SSD_ACT_DR8_R")
			(options
				(clearance outline)
				(anchor circle)
			)
			(primitives
				(gr_poly
					(pts
						(arc
							(start -0.1778 0.5715)
							(mid -0.321484 0.511984)
							(end -0.381 0.3683)
						)
						(arc
							(start -0.381 -0.3683)
							(mid -0.321484 -0.511984)
							(end -0.1778 -0.5715)
						)
						(arc
							(start 0.1778 -0.5715)
							(mid 0.321484 -0.511984)
							(end 0.381 -0.3683)
						)
						(arc
							(start 0.381 0.3683)
							(mid 0.321484 0.511984)
							(end 0.1778 0.5715)
						)
					)
					(width 0)
					(fill yes)
				)
			)
		)
	)
	(footprint ""
		(layer "F.Cu")
		(at 19.115024 -402.68525 180)
		(property "Reference" "R9819"
			(at 0 0 180)
			(layer "F.SilkS")
			(hide yes)
			(effects
				(font
					(size 1.27 1.27)
				)
			)
		)
		(property "Value" "1KR2J-1-GP"
			(at 0.064008 -3.993896 180)
			(unlocked yes)
			(layer "F.Fab")
			(hide yes)
			(effects
				(font
					(size 1.016 1.016)
					(thickness 0.1524)
				)
			)
		)
		(property "Device Type" "R402H16"
			(at 0.064008 -5.517896 180)
			(unlocked yes)
			(layer "F.Fab")
			(hide yes)
			(effects
				(font
					(size 1.016 1.016)
					(thickness 0.1524)
				)
			)
		)
		(duplicate_pad_numbers_are_jumpers no)
		(fp_line
			(start 0.508 -0.9398)
			(end -0.508 -0.9398)
			(stroke
				(width 0.1524)
				(type default)
			)
			(layer "F.SilkS")
		)
		(fp_line
			(start -0.508 -0.9398)
			(end -0.508 0.9398)
			(stroke
				(width 0.1524)
				(type default)
			)
			(layer "F.SilkS")
		)
		(fp_rect
			(start -0.508 0.9398)
			(end 0.508 -0.9398)
			(stroke
				(width 0)
				(type default)
			)
			(fill no)
			(layer "F.CrtYd")
		)
		(fp_rect
			(start -0.508 0.9398)
			(end 0.508 -0.9398)
			(stroke
				(width 0)
				(type default)
			)
			(fill no)
			(layer "F.Fab")
		)
		(pad "1" smd custom
			(at 0 -0.4445 180)
			(size 0.1397 0.1397)
			(layers "F.Cu" "F.Mask" "F.Paste")
			(net "SSD6_PWREN")
			(options
				(clearance outline)
				(anchor circle)
			)
			(primitives
				(gr_poly
					(pts
						(arc
							(start -0.1778 -0.2794)
							(mid -0.249642 -0.249642)
							(end -0.2794 -0.1778)
						)
						(arc
							(start -0.2794 0.1778)
							(mid -0.249642 0.249642)
							(end -0.1778 0.2794)
						)
						(arc
							(start 0.1778 0.2794)
							(mid 0.249642 0.249642)
							(end 0.2794 0.1778)
						)
						(arc
							(start 0.2794 -0.1778)
							(mid 0.249642 -0.249642)
							(end 0.1778 -0.2794)
						)
					)
					(width 0)
					(fill yes)
				)
			)
		)
		(pad "2" smd custom
			(at 0 0.4445 180)
			(size 0.1397 0.1397)
			(layers "F.Cu" "F.Mask" "F.Paste")
			(net "SSD6_PWREN_R")
			(options
				(clearance outline)
				(anchor circle)
			)
			(primitives
				(gr_poly
					(pts
						(arc
							(start -0.1778 -0.2794)
							(mid -0.249642 -0.249642)
							(end -0.2794 -0.1778)
						)
						(arc
							(start -0.2794 0.1778)
							(mid -0.249642 0.249642)
							(end -0.1778 0.2794)
						)
						(arc
							(start 0.1778 0.2794)
							(mid 0.249642 0.249642)
							(end 0.2794 0.1778)
						)
						(arc
							(start 0.2794 -0.1778)
							(mid 0.249642 -0.249642)
							(end 0.1778 -0.2794)
						)
					)
					(width 0)
					(fill yes)
				)
			)
		)
	)
	(footprint ""
		(layer "F.Cu")
		(at 25.2984 -105.791)
		(property "Reference" "PC1210"
			(at 0 0 0)
			(layer "F.SilkS")
			(hide yes)
			(effects
				(font
					(size 1.27 1.27)
				)
			)
		)
		(property "Value" "SC22U25V6KX-GP-U"
			(at -2.860802 -5.279644 0)
			(unlocked yes)
			(layer "F.Fab")
			(hide yes)
			(effects
				(font
					(size 1.016 1.016)
					(thickness 0.1524)
				)
			)
		)
		(property "Device Type" "C1206-TO0D3H75"
			(at -2.860802 -6.803644 0)
			(unlocked yes)
			(layer "F.Fab")
			(hide yes)
			(effects
				(font
					(size 1.016 1.016)
					(thickness 0.1524)
				)
			)
		)
		(duplicate_pad_numbers_are_jumpers no)
		(fp_line
			(start -1.3081 -2.3749)
			(end 1.3081 -2.3749)
			(stroke
				(width 0.1524)
				(type default)
			)
			(layer "F.SilkS")
		)
		(fp_line
			(start -1.3081 2.3749)
			(end -1.3081 -2.3749)
			(stroke
				(width 0.1524)
				(type default)
			)
			(layer "F.SilkS")
		)
		(fp_line
			(start 1.3081 -2.3749)
			(end 1.3081 2.3749)
			(stroke
				(width 0.1524)
				(type default)
			)
			(layer "F.SilkS")
		)
		(fp_line
			(start 1.3081 2.3749)
			(end -1.3081 2.3749)
			(stroke
				(width 0.1524)
				(type default)
			)
			(layer "F.SilkS")
		)
		(fp_rect
			(start -0.8001 1.6002)
			(end 0.8001 -1.6002)
			(stroke
				(width 0)
				(type default)
			)
			(fill no)
			(layer "F.CrtYd")
		)
		(fp_poly
			(pts
				(xy -1.5621 2.4511) (xy -1.5621 1.6002) (xy 0.8001 1.6002) (xy 0.8001 -1.6002) (xy -0.8001 -1.6002)
				(xy -0.8001 1.5875) (xy -1.5621 1.5875) (xy -1.5621 -2.4511) (xy 1.5621 -2.4511) (xy 1.5621 2.4511)
			)
			(stroke
				(width 0)
				(type default)
			)
			(fill no)
			(layer "F.CrtYd")
		)
		(fp_rect
			(start -1.5621 2.4511)
			(end 1.5621 -2.4511)
			(stroke
				(width 0)
				(type default)
			)
			(fill no)
			(layer "F.Fab")
		)
		(pad "1" smd rect
			(at 0 -1.392936)
			(size 2.1082 1.4478)
			(layers "F.Cu" "F.Mask" "F.Paste")
			(net "P12V_SSD13")
		)
		(pad "2" smd rect
			(at 0 1.392936)
			(size 2.1082 1.4478)
			(layers "F.Cu" "F.Mask" "F.Paste")
			(net "GND")
		)
	)
	(footprint ""
		(layer "F.Cu")
		(at 40.259 -204.724)
		(property "Reference" "R9859"
			(at 0 0 0)
			(layer "F.SilkS")
			(hide yes)
			(effects
				(font
					(size 1.27 1.27)
				)
			)
		)
		(property "Value" "1KR2J-1-GP"
			(at 0.064008 -3.993896 0)
			(unlocked yes)
			(layer "F.Fab")
			(hide yes)
			(effects
				(font
					(size 1.016 1.016)
					(thickness 0.1524)
				)
			)
		)
		(property "Device Type" "R402H16"
			(at 0.064008 -5.517896 0)
			(unlocked yes)
			(layer "F.Fab")
			(hide yes)
			(effects
				(font
					(size 1.016 1.016)
					(thickness 0.1524)
				)
			)
		)
		(duplicate_pad_numbers_are_jumpers no)
		(fp_line
			(start -0.508 -0.9398)
			(end -0.508 0.9398)
			(stroke
				(width 0.1524)
				(type default)
			)
			(layer "F.SilkS")
		)
		(fp_line
			(start 0.508 -0.9398)
			(end -0.508 -0.9398)
			(stroke
				(width 0.1524)
				(type default)
			)
			(layer "F.SilkS")
		)
		(fp_rect
			(start -0.508 0.9398)
			(end 0.508 -0.9398)
			(stroke
				(width 0)
				(type default)
			)
			(fill no)
			(layer "F.CrtYd")
		)
		(fp_rect
			(start -0.508 0.9398)
			(end 0.508 -0.9398)
			(stroke
				(width 0)
				(type default)
			)
			(fill no)
			(layer "F.Fab")
		)
		(pad "1" smd custom
			(at 0 -0.4445)
			(size 0.1397 0.1397)
			(layers "F.Cu" "F.Mask" "F.Paste")
			(net "SSD12_PWREN")
			(options
				(clearance outline)
				(anchor circle)
			)
			(primitives
				(gr_poly
					(pts
						(arc
							(start -0.1778 -0.2794)
							(mid -0.249642 -0.249642)
							(end -0.2794 -0.1778)
						)
						(arc
							(start -0.2794 0.1778)
							(mid -0.249642 0.249642)
							(end -0.1778 0.2794)
						)
						(arc
							(start 0.1778 0.2794)
							(mid 0.249642 0.249642)
							(end 0.2794 0.1778)
						)
						(arc
							(start 0.2794 -0.1778)
							(mid 0.249642 -0.249642)
							(end 0.1778 -0.2794)
						)
					)
					(width 0)
					(fill yes)
				)
			)
		)
		(pad "2" smd custom
			(at 0 0.4445)
			(size 0.1397 0.1397)
			(layers "F.Cu" "F.Mask" "F.Paste")
			(net "SSD12_PWREN_R")
			(options
				(clearance outline)
				(anchor circle)
			)
			(primitives
				(gr_poly
					(pts
						(arc
							(start -0.1778 -0.2794)
							(mid -0.249642 -0.249642)
							(end -0.2794 -0.1778)
						)
						(arc
							(start -0.2794 0.1778)
							(mid -0.249642 0.249642)
							(end -0.1778 0.2794)
						)
						(arc
							(start 0.1778 0.2794)
							(mid 0.249642 0.249642)
							(end 0.2794 0.1778)
						)
						(arc
							(start 0.2794 -0.1778)
							(mid 0.249642 -0.249642)
							(end 0.1778 -0.2794)
						)
					)
					(width 0)
					(fill yes)
				)
			)
		)
	)
	(footprint ""
		(layer "F.Cu")
		(at 108.966 -436.88)
		(property "Reference" "R119"
			(at 0 0 0)
			(layer "F.SilkS")
			(hide yes)
			(effects
				(font
					(size 1.27 1.27)
				)
			)
		)
		(property "Value" "4K7R2J-2-GP"
			(at 0.064008 -3.993896 0)
			(unlocked yes)
			(layer "F.Fab")
			(hide yes)
			(effects
				(font
					(size 1.016 1.016)
					(thickness 0.1524)
				)
			)
		)
		(property "Device Type" "R402H16"
			(at 0.064008 -5.517896 0)
			(unlocked yes)
			(layer "F.Fab")
			(hide yes)
			(effects
				(font
					(size 1.016 1.016)
					(thickness 0.1524)
				)
			)
		)
		(duplicate_pad_numbers_are_jumpers no)
		(fp_line
			(start -0.508 -0.9398)
			(end -0.508 0.9398)
			(stroke
				(width 0.1524)
				(type default)
			)
			(layer "F.SilkS")
		)
		(fp_line
			(start 0.508 -0.9398)
			(end -0.508 -0.9398)
			(stroke
				(width 0.1524)
				(type default)
			)
			(layer "F.SilkS")
		)
		(fp_rect
			(start -0.508 0.9398)
			(end 0.508 -0.9398)
			(stroke
				(width 0)
				(type default)
			)
			(fill no)
			(layer "F.CrtYd")
		)
		(fp_rect
			(start -0.508 0.9398)
			(end 0.508 -0.9398)
			(stroke
				(width 0)
				(type default)
			)
			(fill no)
			(layer "F.Fab")
		)
		(pad "1" smd custom
			(at 0 -0.4445)
			(size 0.1397 0.1397)
			(layers "F.Cu" "F.Mask" "F.Paste")
			(net "P3V3")
			(options
				(clearance outline)
				(anchor circle)
			)
			(primitives
				(gr_poly
					(pts
						(arc
							(start -0.1778 -0.2794)
							(mid -0.249642 -0.249642)
							(end -0.2794 -0.1778)
						)
						(arc
							(start -0.2794 0.1778)
							(mid -0.249642 0.249642)
							(end -0.1778 0.2794)
						)
						(arc
							(start 0.1778 0.2794)
							(mid 0.249642 0.249642)
							(end 0.2794 0.1778)
						)
						(arc
							(start 0.2794 -0.1778)
							(mid 0.249642 -0.249642)
							(end 0.1778 -0.2794)
						)
					)
					(width 0)
					(fill yes)
				)
			)
		)
		(pad "2" smd custom
			(at 0 0.4445)
			(size 0.1397 0.1397)
			(layers "F.Cu" "F.Mask" "F.Paste")
			(net "SSD0_CLK0_OE_N")
			(options
				(clearance outline)
				(anchor circle)
			)
			(primitives
				(gr_poly
					(pts
						(arc
							(start -0.1778 -0.2794)
							(mid -0.249642 -0.249642)
							(end -0.2794 -0.1778)
						)
						(arc
							(start -0.2794 0.1778)
							(mid -0.249642 0.249642)
							(end -0.1778 0.2794)
						)
						(arc
							(start 0.1778 0.2794)
							(mid 0.249642 0.249642)
							(end 0.2794 0.1778)
						)
						(arc
							(start 0.2794 -0.1778)
							(mid 0.249642 -0.249642)
							(end 0.1778 -0.2794)
						)
					)
					(width 0)
					(fill yes)
				)
			)
		)
	)
	(footprint ""
		(layer "F.Cu")
		(at 87.757 -222.885 -90)
		(property "Reference" "C9372"
			(at 0 0 270)
			(layer "F.SilkS")
			(hide yes)
			(effects
				(font
					(size 1.27 1.27)
				)
			)
		)
		(property "Value" "SC1KP50V2KX-1GP"
			(at 1.1811 -2.7051 270)
			(unlocked yes)
			(layer "F.Fab")
			(hide yes)
			(effects
				(font
					(size 1.016 1.016)
					(thickness 0.1524)
				)
			)
		)
		(property "Device Type" "C402H22"
			(at 1.1811 -4.2291 270)
			(unlocked yes)
			(layer "F.Fab")
			(hide yes)
			(effects
				(font
					(size 1.016 1.016)
					(thickness 0.1524)
				)
			)
		)
		(duplicate_pad_numbers_are_jumpers no)
		(fp_rect
			(start -0.4318 0.9525)
			(end 0.4318 -0.9525)
			(stroke
				(width 0)
				(type default)
			)
			(fill no)
			(layer "F.CrtYd")
		)
		(fp_rect
			(start -0.4318 0.9525)
			(end 0.4318 -0.9525)
			(stroke
				(width 0)
				(type default)
			)
			(fill no)
			(layer "F.Fab")
		)
		(pad "1" smd custom
			(at 0 -0.4445 270)
			(size 0.1524 0.1524)
			(layers "F.Cu" "F.Mask" "F.Paste")
			(net "SSD12_CLK0_OE_R_N")
			(options
				(clearance outline)
				(anchor circle)
			)
			(primitives
				(gr_poly
					(pts
						(arc
							(start 0.3048 -0.2032)
							(mid 0.275042 -0.275042)
							(end 0.2032 -0.3048)
						)
						(arc
							(start -0.2032 -0.3048)
							(mid -0.275042 -0.275042)
							(end -0.3048 -0.2032)
						)
						(arc
							(start -0.3048 0.2032)
							(mid -0.275042 0.275042)
							(end -0.2032 0.3048)
						)
						(arc
							(start 0.2032 0.3048)
							(mid 0.275042 0.275042)
							(end 0.3048 0.2032)
						)
					)
					(width 0)
					(fill yes)
				)
			)
		)
		(pad "2" smd custom
			(at 0 0.4445 270)
			(size 0.1524 0.1524)
			(layers "F.Cu" "F.Mask" "F.Paste")
			(net "GND")
			(options
				(clearance outline)
				(anchor circle)
			)
			(primitives
				(gr_poly
					(pts
						(arc
							(start 0.3048 -0.2032)
							(mid 0.275042 -0.275042)
							(end 0.2032 -0.3048)
						)
						(arc
							(start -0.2032 -0.3048)
							(mid -0.275042 -0.275042)
							(end -0.3048 -0.2032)
						)
						(arc
							(start -0.3048 0.2032)
							(mid -0.275042 0.275042)
							(end -0.2032 0.3048)
						)
						(arc
							(start 0.2032 0.3048)
							(mid 0.275042 0.275042)
							(end 0.3048 0.2032)
						)
					)
					(width 0)
					(fill yes)
				)
			)
		)
	)
	(footprint ""
		(layer "F.Cu")
		(at 96.52 -313.817 180)
		(property "Reference" "R9097"
			(at 0 0 180)
			(layer "F.SilkS")
			(hide yes)
			(effects
				(font
					(size 1.27 1.27)
				)
			)
		)
		(property "Value" "27R2F-GP"
			(at 0.064008 -3.993896 180)
			(unlocked yes)
			(layer "F.Fab")
			(hide yes)
			(effects
				(font
					(size 1.016 1.016)
					(thickness 0.1524)
				)
			)
		)
		(property "Device Type" "R402H16"
			(at 0.064008 -5.517896 180)
			(unlocked yes)
			(layer "F.Fab")
			(hide yes)
			(effects
				(font
					(size 1.016 1.016)
					(thickness 0.1524)
				)
			)
		)
		(duplicate_pad_numbers_are_jumpers no)
		(fp_line
			(start 0.508 -0.9398)
			(end -0.508 -0.9398)
			(stroke
				(width 0.1524)
				(type default)
			)
			(layer "F.SilkS")
		)
		(fp_line
			(start -0.508 -0.9398)
			(end -0.508 0.9398)
			(stroke
				(width 0.1524)
				(type default)
			)
			(layer "F.SilkS")
		)
		(fp_rect
			(start -0.508 0.9398)
			(end 0.508 -0.9398)
			(stroke
				(width 0)
				(type default)
			)
			(fill no)
			(layer "F.CrtYd")
		)
		(fp_rect
			(start -0.508 0.9398)
			(end 0.508 -0.9398)
			(stroke
				(width 0)
				(type default)
			)
			(fill no)
			(layer "F.Fab")
		)
		(pad "1" smd custom
			(at 0 -0.4445 180)
			(size 0.1397 0.1397)
			(layers "F.Cu" "F.Mask" "F.Paste")
			(net "PE_CLK_100M_DR6_1_R_P")
			(options
				(clearance outline)
				(anchor circle)
			)
			(primitives
				(gr_poly
					(pts
						(arc
							(start -0.1778 -0.2794)
							(mid -0.249642 -0.249642)
							(end -0.2794 -0.1778)
						)
						(arc
							(start -0.2794 0.1778)
							(mid -0.249642 0.249642)
							(end -0.1778 0.2794)
						)
						(arc
							(start 0.1778 0.2794)
							(mid 0.249642 0.249642)
							(end 0.2794 0.1778)
						)
						(arc
							(start 0.2794 -0.1778)
							(mid 0.249642 -0.249642)
							(end 0.1778 -0.2794)
						)
					)
					(width 0)
					(fill yes)
				)
			)
		)
		(pad "2" smd custom
			(at 0 0.4445 180)
			(size 0.1397 0.1397)
			(layers "F.Cu" "F.Mask" "F.Paste")
			(net "PE_CLK100M_DR6_1_P")
			(options
				(clearance outline)
				(anchor circle)
			)
			(primitives
				(gr_poly
					(pts
						(arc
							(start -0.1778 -0.2794)
							(mid -0.249642 -0.249642)
							(end -0.2794 -0.1778)
						)
						(arc
							(start -0.2794 0.1778)
							(mid -0.249642 0.249642)
							(end -0.1778 0.2794)
						)
						(arc
							(start 0.1778 0.2794)
							(mid 0.249642 0.249642)
							(end 0.2794 0.1778)
						)
						(arc
							(start 0.2794 -0.1778)
							(mid 0.249642 -0.249642)
							(end 0.1778 -0.2794)
						)
					)
					(width 0)
					(fill yes)
				)
			)
		)
	)
	(footprint ""
		(layer "F.Cu")
		(at 99.06 -290.195 -90)
		(property "Reference" "R9488"
			(at 0 0 270)
			(layer "F.SilkS")
			(hide yes)
			(effects
				(font
					(size 1.27 1.27)
				)
			)
		)
		(property "Value" "4K7R2J-2-GP"
			(at 0.064008 -3.993896 270)
			(unlocked yes)
			(layer "F.Fab")
			(hide yes)
			(effects
				(font
					(size 1.016 1.016)
					(thickness 0.1524)
				)
			)
		)
		(property "Device Type" "R402H16"
			(at 0.064008 -5.517896 270)
			(unlocked yes)
			(layer "F.Fab")
			(hide yes)
			(effects
				(font
					(size 1.016 1.016)
					(thickness 0.1524)
				)
			)
		)
		(duplicate_pad_numbers_are_jumpers no)
		(fp_line
			(start -0.508 -0.9398)
			(end -0.508 0.9398)
			(stroke
				(width 0.1524)
				(type default)
			)
			(layer "F.SilkS")
		)
		(fp_line
			(start 0.508 -0.9398)
			(end -0.508 -0.9398)
			(stroke
				(width 0.1524)
				(type default)
			)
			(layer "F.SilkS")
		)
		(fp_rect
			(start -0.508 0.9398)
			(end 0.508 -0.9398)
			(stroke
				(width 0)
				(type default)
			)
			(fill no)
			(layer "F.CrtYd")
		)
		(fp_rect
			(start -0.508 0.9398)
			(end 0.508 -0.9398)
			(stroke
				(width 0)
				(type default)
			)
			(fill no)
			(layer "F.Fab")
		)
		(pad "1" smd custom
			(at 0 -0.4445 270)
			(size 0.1397 0.1397)
			(layers "F.Cu" "F.Mask" "F.Paste")
			(net "P3V3")
			(options
				(clearance outline)
				(anchor circle)
			)
			(primitives
				(gr_poly
					(pts
						(arc
							(start -0.1778 -0.2794)
							(mid -0.249642 -0.249642)
							(end -0.2794 -0.1778)
						)
						(arc
							(start -0.2794 0.1778)
							(mid -0.249642 0.249642)
							(end -0.1778 0.2794)
						)
						(arc
							(start 0.1778 0.2794)
							(mid 0.249642 0.249642)
							(end 0.2794 0.1778)
						)
						(arc
							(start 0.2794 -0.1778)
							(mid 0.249642 -0.249642)
							(end 0.1778 -0.2794)
						)
					)
					(width 0)
					(fill yes)
				)
			)
		)
		(pad "2" smd custom
			(at 0 0.4445 270)
			(size 0.1397 0.1397)
			(layers "F.Cu" "F.Mask" "F.Paste")
			(net "SSD2_CLK0_OE_N")
			(options
				(clearance outline)
				(anchor circle)
			)
			(primitives
				(gr_poly
					(pts
						(arc
							(start -0.1778 -0.2794)
							(mid -0.249642 -0.249642)
							(end -0.2794 -0.1778)
						)
						(arc
							(start -0.2794 0.1778)
							(mid -0.249642 0.249642)
							(end -0.1778 0.2794)
						)
						(arc
							(start 0.1778 0.2794)
							(mid 0.249642 0.249642)
							(end 0.2794 0.1778)
						)
						(arc
							(start 0.2794 -0.1778)
							(mid 0.249642 -0.249642)
							(end 0.1778 -0.2794)
						)
					)
					(width 0)
					(fill yes)
				)
			)
		)
	)
	(footprint ""
		(layer "F.Cu")
		(at 78.5622 -100.2792 180)
		(property "Reference" "R9972"
			(at 0 0 180)
			(layer "F.SilkS")
			(hide yes)
			(effects
				(font
					(size 1.27 1.27)
				)
			)
		)
		(property "Value" "470R2F-GP"
			(at 0.064008 -3.993896 180)
			(unlocked yes)
			(layer "F.Fab")
			(hide yes)
			(effects
				(font
					(size 1.016 1.016)
					(thickness 0.1524)
				)
			)
		)
		(property "Device Type" "R402H16"
			(at 0.064008 -5.517896 180)
			(unlocked yes)
			(layer "F.Fab")
			(hide yes)
			(effects
				(font
					(size 1.016 1.016)
					(thickness 0.1524)
				)
			)
		)
		(duplicate_pad_numbers_are_jumpers no)
		(fp_line
			(start 0.508 -0.9398)
			(end -0.508 -0.9398)
			(stroke
				(width 0.1524)
				(type default)
			)
			(layer "F.SilkS")
		)
		(fp_line
			(start -0.508 -0.9398)
			(end -0.508 0.9398)
			(stroke
				(width 0.1524)
				(type default)
			)
			(layer "F.SilkS")
		)
		(fp_rect
			(start -0.508 0.9398)
			(end 0.508 -0.9398)
			(stroke
				(width 0)
				(type default)
			)
			(fill no)
			(layer "F.CrtYd")
		)
		(fp_rect
			(start -0.508 0.9398)
			(end 0.508 -0.9398)
			(stroke
				(width 0)
				(type default)
			)
			(fill no)
			(layer "F.Fab")
		)
		(pad "1" smd custom
			(at 0 -0.4445 180)
			(size 0.1397 0.1397)
			(layers "F.Cu" "F.Mask" "F.Paste")
			(net "VDD_DIFF_4")
			(options
				(clearance outline)
				(anchor circle)
			)
			(primitives
				(gr_poly
					(pts
						(arc
							(start -0.1778 -0.2794)
							(mid -0.249642 -0.249642)
							(end -0.2794 -0.1778)
						)
						(arc
							(start -0.2794 0.1778)
							(mid -0.249642 0.249642)
							(end -0.1778 0.2794)
						)
						(arc
							(start 0.1778 0.2794)
							(mid 0.249642 0.249642)
							(end 0.2794 0.1778)
						)
						(arc
							(start 0.2794 -0.1778)
							(mid 0.249642 -0.249642)
							(end 0.1778 -0.2794)
						)
					)
					(width 0)
					(fill yes)
				)
			)
		)
		(pad "2" smd custom
			(at 0 0.4445 180)
			(size 0.1397 0.1397)
			(layers "F.Cu" "F.Mask" "F.Paste")
			(net "PE_100M_CLK1_N")
			(options
				(clearance outline)
				(anchor circle)
			)
			(primitives
				(gr_poly
					(pts
						(arc
							(start -0.1778 -0.2794)
							(mid -0.249642 -0.249642)
							(end -0.2794 -0.1778)
						)
						(arc
							(start -0.2794 0.1778)
							(mid -0.249642 0.249642)
							(end -0.1778 0.2794)
						)
						(arc
							(start 0.1778 0.2794)
							(mid 0.249642 0.249642)
							(end 0.2794 0.1778)
						)
						(arc
							(start 0.2794 -0.1778)
							(mid 0.249642 -0.249642)
							(end 0.1778 -0.2794)
						)
					)
					(width 0)
					(fill yes)
				)
			)
		)
	)
	(footprint ""
		(layer "F.Cu")
		(at 18.23974 -466.66658 -90)
		(property "Reference" "R9947"
			(at 0 0 270)
			(layer "F.SilkS")
			(hide yes)
			(effects
				(font
					(size 1.27 1.27)
				)
			)
		)
		(property "Value" "4K7R2J-2-GP"
			(at 0.064008 -3.993896 270)
			(unlocked yes)
			(layer "F.Fab")
			(hide yes)
			(effects
				(font
					(size 1.016 1.016)
					(thickness 0.1524)
				)
			)
		)
		(property "Device Type" "R402H16"
			(at 0.064008 -5.517896 270)
			(unlocked yes)
			(layer "F.Fab")
			(hide yes)
			(effects
				(font
					(size 1.016 1.016)
					(thickness 0.1524)
				)
			)
		)
		(duplicate_pad_numbers_are_jumpers no)
		(fp_line
			(start -0.508 -0.9398)
			(end -0.508 0.9398)
			(stroke
				(width 0.1524)
				(type default)
			)
			(layer "F.SilkS")
		)
		(fp_line
			(start 0.508 -0.9398)
			(end -0.508 -0.9398)
			(stroke
				(width 0.1524)
				(type default)
			)
			(layer "F.SilkS")
		)
		(fp_rect
			(start -0.508 0.9398)
			(end 0.508 -0.9398)
			(stroke
				(width 0)
				(type default)
			)
			(fill no)
			(layer "F.CrtYd")
		)
		(fp_rect
			(start -0.508 0.9398)
			(end 0.508 -0.9398)
			(stroke
				(width 0)
				(type default)
			)
			(fill no)
			(layer "F.Fab")
		)
		(pad "1" smd custom
			(at 0 -0.4445 270)
			(size 0.1397 0.1397)
			(layers "F.Cu" "F.Mask" "F.Paste")
			(net "P3V3")
			(options
				(clearance outline)
				(anchor circle)
			)
			(primitives
				(gr_poly
					(pts
						(arc
							(start -0.1778 -0.2794)
							(mid -0.249642 -0.249642)
							(end -0.2794 -0.1778)
						)
						(arc
							(start -0.2794 0.1778)
							(mid -0.249642 0.249642)
							(end -0.1778 0.2794)
						)
						(arc
							(start 0.1778 0.2794)
							(mid 0.249642 0.249642)
							(end 0.2794 0.1778)
						)
						(arc
							(start 0.2794 -0.1778)
							(mid 0.249642 -0.249642)
							(end 0.1778 -0.2794)
						)
					)
					(width 0)
					(fill yes)
				)
			)
		)
		(pad "2" smd custom
			(at 0 0.4445 270)
			(size 0.1397 0.1397)
			(layers "F.Cu" "F.Mask" "F.Paste")
			(net "ATTN_LED_DR10_MOS_N")
			(options
				(clearance outline)
				(anchor circle)
			)
			(primitives
				(gr_poly
					(pts
						(arc
							(start -0.1778 -0.2794)
							(mid -0.249642 -0.249642)
							(end -0.2794 -0.1778)
						)
						(arc
							(start -0.2794 0.1778)
							(mid -0.249642 0.249642)
							(end -0.1778 0.2794)
						)
						(arc
							(start 0.1778 0.2794)
							(mid 0.249642 0.249642)
							(end 0.2794 0.1778)
						)
						(arc
							(start 0.2794 -0.1778)
							(mid 0.249642 -0.249642)
							(end 0.1778 -0.2794)
						)
					)
					(width 0)
					(fill yes)
				)
			)
		)
	)
	(footprint ""
		(layer "F.Cu")
		(at 231.267 -439.293)
		(property "Reference" "R9756"
			(at 0 0 0)
			(layer "F.SilkS")
			(hide yes)
			(effects
				(font
					(size 1.27 1.27)
				)
			)
		)
		(property "Value" "4K7R2F-GP"
			(at 0.064008 -3.993896 0)
			(unlocked yes)
			(layer "F.Fab")
			(hide yes)
			(effects
				(font
					(size 1.016 1.016)
					(thickness 0.1524)
				)
			)
		)
		(property "Device Type" "R402H16"
			(at 0.064008 -5.517896 0)
			(unlocked yes)
			(layer "F.Fab")
			(hide yes)
			(effects
				(font
					(size 1.016 1.016)
					(thickness 0.1524)
				)
			)
		)
		(duplicate_pad_numbers_are_jumpers no)
		(fp_line
			(start -0.508 -0.9398)
			(end -0.508 0.9398)
			(stroke
				(width 0.1524)
				(type default)
			)
			(layer "F.SilkS")
		)
		(fp_line
			(start 0.508 -0.9398)
			(end -0.508 -0.9398)
			(stroke
				(width 0.1524)
				(type default)
			)
			(layer "F.SilkS")
		)
		(fp_rect
			(start -0.508 0.9398)
			(end 0.508 -0.9398)
			(stroke
				(width 0)
				(type default)
			)
			(fill no)
			(layer "F.CrtYd")
		)
		(fp_rect
			(start -0.508 0.9398)
			(end 0.508 -0.9398)
			(stroke
				(width 0)
				(type default)
			)
			(fill no)
			(layer "F.Fab")
		)
		(pad "1" smd custom
			(at 0 -0.4445)
			(size 0.1397 0.1397)
			(layers "F.Cu" "F.Mask" "F.Paste")
			(net "P3V3")
			(options
				(clearance outline)
				(anchor circle)
			)
			(primitives
				(gr_poly
					(pts
						(arc
							(start -0.1778 -0.2794)
							(mid -0.249642 -0.249642)
							(end -0.2794 -0.1778)
						)
						(arc
							(start -0.2794 0.1778)
							(mid -0.249642 0.249642)
							(end -0.1778 0.2794)
						)
						(arc
							(start 0.1778 0.2794)
							(mid 0.249642 0.249642)
							(end 0.2794 0.1778)
						)
						(arc
							(start 0.2794 -0.1778)
							(mid 0.249642 -0.249642)
							(end 0.1778 -0.2794)
						)
					)
					(width 0)
					(fill yes)
				)
			)
		)
		(pad "2" smd custom
			(at 0 0.4445)
			(size 0.1397 0.1397)
			(layers "F.Cu" "F.Mask" "F.Paste")
			(net "TPS53312_P3V3_PG")
			(options
				(clearance outline)
				(anchor circle)
			)
			(primitives
				(gr_poly
					(pts
						(arc
							(start -0.1778 -0.2794)
							(mid -0.249642 -0.249642)
							(end -0.2794 -0.1778)
						)
						(arc
							(start -0.2794 0.1778)
							(mid -0.249642 0.249642)
							(end -0.1778 0.2794)
						)
						(arc
							(start 0.1778 0.2794)
							(mid 0.249642 0.249642)
							(end 0.2794 0.1778)
						)
						(arc
							(start 0.2794 -0.1778)
							(mid 0.249642 -0.249642)
							(end 0.1778 -0.2794)
						)
					)
					(width 0)
					(fill yes)
				)
			)
		)
	)
	(footprint ""
		(layer "F.Cu")
		(at 87.757 -225.806 90)
		(property "Reference" "R9517"
			(at 0 0 90)
			(layer "F.SilkS")
			(hide yes)
			(effects
				(font
					(size 1.27 1.27)
				)
			)
		)
		(property "Value" "4K7R2J-2-GP"
			(at 0.064008 -3.993896 90)
			(unlocked yes)
			(layer "F.Fab")
			(hide yes)
			(effects
				(font
					(size 1.016 1.016)
					(thickness 0.1524)
				)
			)
		)
		(property "Device Type" "R402H16"
			(at 0.064008 -5.517896 90)
			(unlocked yes)
			(layer "F.Fab")
			(hide yes)
			(effects
				(font
					(size 1.016 1.016)
					(thickness 0.1524)
				)
			)
		)
		(duplicate_pad_numbers_are_jumpers no)
		(fp_line
			(start 0.508 -0.9398)
			(end -0.508 -0.9398)
			(stroke
				(width 0.1524)
				(type default)
			)
			(layer "F.SilkS")
		)
		(fp_line
			(start -0.508 -0.9398)
			(end -0.508 0.9398)
			(stroke
				(width 0.1524)
				(type default)
			)
			(layer "F.SilkS")
		)
		(fp_rect
			(start -0.508 0.9398)
			(end 0.508 -0.9398)
			(stroke
				(width 0)
				(type default)
			)
			(fill no)
			(layer "F.CrtYd")
		)
		(fp_rect
			(start -0.508 0.9398)
			(end 0.508 -0.9398)
			(stroke
				(width 0)
				(type default)
			)
			(fill no)
			(layer "F.Fab")
		)
		(pad "1" smd custom
			(at 0 -0.4445 90)
			(size 0.1397 0.1397)
			(layers "F.Cu" "F.Mask" "F.Paste")
			(net "P3V3")
			(options
				(clearance outline)
				(anchor circle)
			)
			(primitives
				(gr_poly
					(pts
						(arc
							(start -0.1778 -0.2794)
							(mid -0.249642 -0.249642)
							(end -0.2794 -0.1778)
						)
						(arc
							(start -0.2794 0.1778)
							(mid -0.249642 0.249642)
							(end -0.1778 0.2794)
						)
						(arc
							(start 0.1778 0.2794)
							(mid 0.249642 0.249642)
							(end 0.2794 0.1778)
						)
						(arc
							(start 0.2794 -0.1778)
							(mid 0.249642 -0.249642)
							(end 0.1778 -0.2794)
						)
					)
					(width 0)
					(fill yes)
				)
			)
		)
		(pad "2" smd custom
			(at 0 0.4445 90)
			(size 0.1397 0.1397)
			(layers "F.Cu" "F.Mask" "F.Paste")
			(net "SSD12_CLK0_OE_N")
			(options
				(clearance outline)
				(anchor circle)
			)
			(primitives
				(gr_poly
					(pts
						(arc
							(start -0.1778 -0.2794)
							(mid -0.249642 -0.249642)
							(end -0.2794 -0.1778)
						)
						(arc
							(start -0.2794 0.1778)
							(mid -0.249642 0.249642)
							(end -0.1778 0.2794)
						)
						(arc
							(start 0.1778 0.2794)
							(mid 0.249642 0.249642)
							(end 0.2794 0.1778)
						)
						(arc
							(start 0.2794 -0.1778)
							(mid 0.249642 -0.249642)
							(end 0.1778 -0.2794)
						)
					)
					(width 0)
					(fill yes)
				)
			)
		)
	)
	(footprint ""
		(layer "F.Cu")
		(at 97.409 -198.755 90)
		(property "Reference" "C9366"
			(at 0 0 90)
			(layer "F.SilkS")
			(hide yes)
			(effects
				(font
					(size 1.27 1.27)
				)
			)
		)
		(property "Value" "SC1KP50V2KX-1GP"
			(at 1.1811 -2.7051 90)
			(unlocked yes)
			(layer "F.Fab")
			(hide yes)
			(effects
				(font
					(size 1.016 1.016)
					(thickness 0.1524)
				)
			)
		)
		(property "Device Type" "C402H22"
			(at 1.1811 -4.2291 90)
			(unlocked yes)
			(layer "F.Fab")
			(hide yes)
			(effects
				(font
					(size 1.016 1.016)
					(thickness 0.1524)
				)
			)
		)
		(duplicate_pad_numbers_are_jumpers no)
		(fp_rect
			(start -0.4318 0.9525)
			(end 0.4318 -0.9525)
			(stroke
				(width 0)
				(type default)
			)
			(fill no)
			(layer "F.CrtYd")
		)
		(fp_rect
			(start -0.4318 0.9525)
			(end 0.4318 -0.9525)
			(stroke
				(width 0)
				(type default)
			)
			(fill no)
			(layer "F.Fab")
		)
		(pad "1" smd custom
			(at 0 -0.4445 90)
			(size 0.1524 0.1524)
			(layers "F.Cu" "F.Mask" "F.Paste")
			(net "SSD4_CLK0_OE_R_N")
			(options
				(clearance outline)
				(anchor circle)
			)
			(primitives
				(gr_poly
					(pts
						(arc
							(start 0.3048 -0.2032)
							(mid 0.275042 -0.275042)
							(end 0.2032 -0.3048)
						)
						(arc
							(start -0.2032 -0.3048)
							(mid -0.275042 -0.275042)
							(end -0.3048 -0.2032)
						)
						(arc
							(start -0.3048 0.2032)
							(mid -0.275042 0.275042)
							(end -0.2032 0.3048)
						)
						(arc
							(start 0.2032 0.3048)
							(mid 0.275042 0.275042)
							(end 0.3048 0.2032)
						)
					)
					(width 0)
					(fill yes)
				)
			)
		)
		(pad "2" smd custom
			(at 0 0.4445 90)
			(size 0.1524 0.1524)
			(layers "F.Cu" "F.Mask" "F.Paste")
			(net "GND")
			(options
				(clearance outline)
				(anchor circle)
			)
			(primitives
				(gr_poly
					(pts
						(arc
							(start 0.3048 -0.2032)
							(mid 0.275042 -0.275042)
							(end 0.2032 -0.3048)
						)
						(arc
							(start -0.2032 -0.3048)
							(mid -0.275042 -0.275042)
							(end -0.3048 -0.2032)
						)
						(arc
							(start -0.3048 0.2032)
							(mid -0.275042 0.275042)
							(end -0.2032 0.3048)
						)
						(arc
							(start 0.2032 0.3048)
							(mid 0.275042 0.275042)
							(end 0.3048 0.2032)
						)
					)
					(width 0)
					(fill yes)
				)
			)
		)
	)
	(footprint ""
		(layer "F.Cu")
		(at 21.231606 -162.109658 180)
		(property "Reference" "R9925"
			(at 0 0 180)
			(layer "F.SilkS")
			(hide yes)
			(effects
				(font
					(size 1.27 1.27)
				)
			)
		)
		(property "Value" "47KR2J-2-GP"
			(at 0.064008 -3.993896 180)
			(unlocked yes)
			(layer "F.Fab")
			(hide yes)
			(effects
				(font
					(size 1.016 1.016)
					(thickness 0.1524)
				)
			)
		)
		(property "Device Type" "R402H16"
			(at 0.064008 -5.517896 180)
			(unlocked yes)
			(layer "F.Fab")
			(hide yes)
			(effects
				(font
					(size 1.016 1.016)
					(thickness 0.1524)
				)
			)
		)
		(duplicate_pad_numbers_are_jumpers no)
		(fp_line
			(start 0.508 -0.9398)
			(end -0.508 -0.9398)
			(stroke
				(width 0.1524)
				(type default)
			)
			(layer "F.SilkS")
		)
		(fp_line
			(start -0.508 -0.9398)
			(end -0.508 0.9398)
			(stroke
				(width 0.1524)
				(type default)
			)
			(layer "F.SilkS")
		)
		(fp_rect
			(start -0.508 0.9398)
			(end 0.508 -0.9398)
			(stroke
				(width 0)
				(type default)
			)
			(fill no)
			(layer "F.CrtYd")
		)
		(fp_rect
			(start -0.508 0.9398)
			(end 0.508 -0.9398)
			(stroke
				(width 0)
				(type default)
			)
			(fill no)
			(layer "F.Fab")
		)
		(pad "1" smd custom
			(at 0 -0.4445 180)
			(size 0.1397 0.1397)
			(layers "F.Cu" "F.Mask" "F.Paste")
			(net "P3V3")
			(options
				(clearance outline)
				(anchor circle)
			)
			(primitives
				(gr_poly
					(pts
						(arc
							(start -0.1778 -0.2794)
							(mid -0.249642 -0.249642)
							(end -0.2794 -0.1778)
						)
						(arc
							(start -0.2794 0.1778)
							(mid -0.249642 0.249642)
							(end -0.1778 0.2794)
						)
						(arc
							(start 0.1778 0.2794)
							(mid 0.249642 0.249642)
							(end 0.2794 0.1778)
						)
						(arc
							(start 0.2794 -0.1778)
							(mid 0.249642 -0.249642)
							(end 0.1778 -0.2794)
						)
					)
					(width 0)
					(fill yes)
				)
			)
		)
		(pad "2" smd custom
			(at 0 0.4445 180)
			(size 0.1397 0.1397)
			(layers "F.Cu" "F.Mask" "F.Paste")
			(net "ATTN_LED_DR13_N")
			(options
				(clearance outline)
				(anchor circle)
			)
			(primitives
				(gr_poly
					(pts
						(arc
							(start -0.1778 -0.2794)
							(mid -0.249642 -0.249642)
							(end -0.2794 -0.1778)
						)
						(arc
							(start -0.2794 0.1778)
							(mid -0.249642 0.249642)
							(end -0.1778 0.2794)
						)
						(arc
							(start 0.1778 0.2794)
							(mid 0.249642 0.249642)
							(end 0.2794 0.1778)
						)
						(arc
							(start 0.2794 -0.1778)
							(mid 0.249642 -0.249642)
							(end 0.1778 -0.2794)
						)
					)
					(width 0)
					(fill yes)
				)
			)
		)
	)
	(footprint ""
		(layer "F.Cu")
		(at 24.003 -52.197 -90)
		(property "Reference" "R9457"
			(at 0 0 270)
			(layer "F.SilkS")
			(hide yes)
			(effects
				(font
					(size 1.27 1.27)
				)
			)
		)
		(property "Value" "100R2J-2-GP"
			(at 0.064008 -3.993896 270)
			(unlocked yes)
			(layer "F.Fab")
			(hide yes)
			(effects
				(font
					(size 1.016 1.016)
					(thickness 0.1524)
				)
			)
		)
		(property "Device Type" "R402H14"
			(at 0.064008 -5.517896 270)
			(unlocked yes)
			(layer "F.Fab")
			(hide yes)
			(effects
				(font
					(size 1.016 1.016)
					(thickness 0.1524)
				)
			)
		)
		(duplicate_pad_numbers_are_jumpers no)
		(fp_line
			(start -0.508 -0.9398)
			(end -0.508 0.9398)
			(stroke
				(width 0.1524)
				(type default)
			)
			(layer "F.SilkS")
		)
		(fp_line
			(start 0.508 -0.9398)
			(end -0.508 -0.9398)
			(stroke
				(width 0.1524)
				(type default)
			)
			(layer "F.SilkS")
		)
		(fp_rect
			(start -0.508 0.9398)
			(end 0.508 -0.9398)
			(stroke
				(width 0)
				(type default)
			)
			(fill no)
			(layer "F.CrtYd")
		)
		(fp_rect
			(start -0.508 0.9398)
			(end 0.508 -0.9398)
			(stroke
				(width 0)
				(type default)
			)
			(fill no)
			(layer "F.Fab")
		)
		(pad "1" smd custom
			(at 0 -0.4445 270)
			(size 0.1397 0.1397)
			(layers "F.Cu" "F.Mask" "F.Paste")
			(net "P3V3")
			(options
				(clearance outline)
				(anchor circle)
			)
			(primitives
				(gr_poly
					(pts
						(arc
							(start -0.1778 -0.2794)
							(mid -0.249642 -0.249642)
							(end -0.2794 -0.1778)
						)
						(arc
							(start -0.2794 0.1778)
							(mid -0.249642 0.249642)
							(end -0.1778 0.2794)
						)
						(arc
							(start 0.1778 0.2794)
							(mid 0.249642 0.249642)
							(end 0.2794 0.1778)
						)
						(arc
							(start 0.2794 -0.1778)
							(mid 0.249642 -0.249642)
							(end 0.1778 -0.2794)
						)
					)
					(width 0)
					(fill yes)
				)
			)
		)
		(pad "2" smd custom
			(at 0 0.4445 270)
			(size 0.1397 0.1397)
			(layers "F.Cu" "F.Mask" "F.Paste")
			(net "DRV_ACT_14")
			(options
				(clearance outline)
				(anchor circle)
			)
			(primitives
				(gr_poly
					(pts
						(arc
							(start -0.1778 -0.2794)
							(mid -0.249642 -0.249642)
							(end -0.2794 -0.1778)
						)
						(arc
							(start -0.2794 0.1778)
							(mid -0.249642 0.249642)
							(end -0.1778 0.2794)
						)
						(arc
							(start 0.1778 0.2794)
							(mid 0.249642 0.249642)
							(end 0.2794 0.1778)
						)
						(arc
							(start 0.2794 -0.1778)
							(mid 0.249642 -0.249642)
							(end 0.1778 -0.2794)
						)
					)
					(width 0)
					(fill yes)
				)
			)
		)
	)
	(footprint ""
		(layer "F.Cu")
		(at 83.185 -151.638 90)
		(property "Reference" "SR1047"
			(at 0 0 90)
			(layer "F.SilkS")
			(hide yes)
			(effects
				(font
					(size 1.27 1.27)
				)
			)
		)
		(property "Value" "4K7R2F-GP"
			(at 0.064008 -3.993896 90)
			(unlocked yes)
			(layer "F.Fab")
			(hide yes)
			(effects
				(font
					(size 1.016 1.016)
					(thickness 0.1524)
				)
			)
		)
		(property "Device Type" "R402H16"
			(at 0.064008 -5.517896 90)
			(unlocked yes)
			(layer "F.Fab")
			(hide yes)
			(effects
				(font
					(size 1.016 1.016)
					(thickness 0.1524)
				)
			)
		)
		(duplicate_pad_numbers_are_jumpers no)
		(fp_line
			(start 0.508 -0.9398)
			(end -0.508 -0.9398)
			(stroke
				(width 0.1524)
				(type default)
			)
			(layer "F.SilkS")
		)
		(fp_line
			(start -0.508 -0.9398)
			(end -0.508 0.9398)
			(stroke
				(width 0.1524)
				(type default)
			)
			(layer "F.SilkS")
		)
		(fp_rect
			(start -0.508 0.9398)
			(end 0.508 -0.9398)
			(stroke
				(width 0)
				(type default)
			)
			(fill no)
			(layer "F.CrtYd")
		)
		(fp_rect
			(start -0.508 0.9398)
			(end 0.508 -0.9398)
			(stroke
				(width 0)
				(type default)
			)
			(fill no)
			(layer "F.Fab")
		)
		(pad "1" smd custom
			(at 0 -0.4445 90)
			(size 0.1397 0.1397)
			(layers "F.Cu" "F.Mask" "F.Paste")
			(net "I2C_SW_EU16_ADDRESS_A1")
			(options
				(clearance outline)
				(anchor circle)
			)
			(primitives
				(gr_poly
					(pts
						(arc
							(start -0.1778 -0.2794)
							(mid -0.249642 -0.249642)
							(end -0.2794 -0.1778)
						)
						(arc
							(start -0.2794 0.1778)
							(mid -0.249642 0.249642)
							(end -0.1778 0.2794)
						)
						(arc
							(start 0.1778 0.2794)
							(mid 0.249642 0.249642)
							(end 0.2794 0.1778)
						)
						(arc
							(start 0.2794 -0.1778)
							(mid 0.249642 -0.249642)
							(end 0.1778 -0.2794)
						)
					)
					(width 0)
					(fill yes)
				)
			)
		)
		(pad "2" smd custom
			(at 0 0.4445 90)
			(size 0.1397 0.1397)
			(layers "F.Cu" "F.Mask" "F.Paste")
			(net "GND")
			(options
				(clearance outline)
				(anchor circle)
			)
			(primitives
				(gr_poly
					(pts
						(arc
							(start -0.1778 -0.2794)
							(mid -0.249642 -0.249642)
							(end -0.2794 -0.1778)
						)
						(arc
							(start -0.2794 0.1778)
							(mid -0.249642 0.249642)
							(end -0.1778 0.2794)
						)
						(arc
							(start 0.1778 0.2794)
							(mid 0.249642 0.249642)
							(end 0.2794 0.1778)
						)
						(arc
							(start 0.2794 -0.1778)
							(mid 0.249642 -0.249642)
							(end 0.1778 -0.2794)
						)
					)
					(width 0)
					(fill yes)
				)
			)
		)
	)
	(footprint ""
		(layer "F.Cu")
		(at 24.13 -393.827 180)
		(property "Reference" "R572"
			(at 0 0 180)
			(layer "F.SilkS")
			(hide yes)
			(effects
				(font
					(size 1.27 1.27)
				)
			)
		)
		(property "Value" "300KR2F-GP"
			(at 0.064008 -3.993896 180)
			(unlocked yes)
			(layer "F.Fab")
			(hide yes)
			(effects
				(font
					(size 1.016 1.016)
					(thickness 0.1524)
				)
			)
		)
		(property "Device Type" "R402H16"
			(at 0.064008 -5.517896 180)
			(unlocked yes)
			(layer "F.Fab")
			(hide yes)
			(effects
				(font
					(size 1.016 1.016)
					(thickness 0.1524)
				)
			)
		)
		(duplicate_pad_numbers_are_jumpers no)
		(fp_line
			(start 0.508 -0.9398)
			(end -0.508 -0.9398)
			(stroke
				(width 0.1524)
				(type default)
			)
			(layer "F.SilkS")
		)
		(fp_line
			(start -0.508 -0.9398)
			(end -0.508 0.9398)
			(stroke
				(width 0.1524)
				(type default)
			)
			(layer "F.SilkS")
		)
		(fp_rect
			(start -0.508 0.9398)
			(end 0.508 -0.9398)
			(stroke
				(width 0)
				(type default)
			)
			(fill no)
			(layer "F.CrtYd")
		)
		(fp_rect
			(start -0.508 0.9398)
			(end 0.508 -0.9398)
			(stroke
				(width 0)
				(type default)
			)
			(fill no)
			(layer "F.Fab")
		)
		(pad "1" smd custom
			(at 0 -0.4445 180)
			(size 0.1397 0.1397)
			(layers "F.Cu" "F.Mask" "F.Paste")
			(net "SW_SSD6_N")
			(options
				(clearance outline)
				(anchor circle)
			)
			(primitives
				(gr_poly
					(pts
						(arc
							(start -0.1778 -0.2794)
							(mid -0.249642 -0.249642)
							(end -0.2794 -0.1778)
						)
						(arc
							(start -0.2794 0.1778)
							(mid -0.249642 0.249642)
							(end -0.1778 0.2794)
						)
						(arc
							(start 0.1778 0.2794)
							(mid 0.249642 0.249642)
							(end 0.2794 0.1778)
						)
						(arc
							(start 0.2794 -0.1778)
							(mid 0.249642 -0.249642)
							(end 0.1778 -0.2794)
						)
					)
					(width 0)
					(fill yes)
				)
			)
		)
		(pad "2" smd custom
			(at 0 0.4445 180)
			(size 0.1397 0.1397)
			(layers "F.Cu" "F.Mask" "F.Paste")
			(net "P12V")
			(options
				(clearance outline)
				(anchor circle)
			)
			(primitives
				(gr_poly
					(pts
						(arc
							(start -0.1778 -0.2794)
							(mid -0.249642 -0.249642)
							(end -0.2794 -0.1778)
						)
						(arc
							(start -0.2794 0.1778)
							(mid -0.249642 0.249642)
							(end -0.1778 0.2794)
						)
						(arc
							(start 0.1778 0.2794)
							(mid 0.249642 0.249642)
							(end 0.2794 0.1778)
						)
						(arc
							(start 0.2794 -0.1778)
							(mid 0.249642 -0.249642)
							(end 0.1778 -0.2794)
						)
					)
					(width 0)
					(fill yes)
				)
			)
		)
	)
	(footprint ""
		(layer "F.Cu")
		(at 26.416 -197.9676 -90)
		(property "Reference" "Q66"
			(at 0 0 270)
			(layer "F.SilkS")
			(hide yes)
			(effects
				(font
					(size 1.27 1.27)
				)
			)
		)
		(property "Value" "2N7002A-7-GP"
			(at 0.127 -8.9662 270)
			(unlocked yes)
			(layer "F.Fab")
			(hide yes)
			(effects
				(font
					(size 1.016 1.016)
					(thickness 0.1524)
				)
			)
		)
		(property "Device Type" "SOT23DGS2D4H48"
			(at 0.127 -10.4902 270)
			(unlocked yes)
			(layer "F.Fab")
			(hide yes)
			(effects
				(font
					(size 1.016 1.016)
					(thickness 0.1524)
				)
			)
		)
		(duplicate_pad_numbers_are_jumpers no)
		(fp_line
			(start -1.651 1.778)
			(end 1.651 1.778)
			(stroke
				(width 0.1524)
				(type default)
			)
			(layer "F.SilkS")
		)
		(fp_line
			(start 1.651 1.778)
			(end 1.651 -1.778)
			(stroke
				(width 0.1524)
				(type default)
			)
			(layer "F.SilkS")
		)
		(fp_line
			(start -1.651 -1.778)
			(end -1.651 1.778)
			(stroke
				(width 0.1524)
				(type default)
			)
			(layer "F.SilkS")
		)
		(fp_line
			(start 1.651 -1.778)
			(end -1.651 -1.778)
			(stroke
				(width 0.1524)
				(type default)
			)
			(layer "F.SilkS")
		)
		(fp_poly
			(pts
				(xy -1.778 1.8796) (xy -1.778 -1.8796) (xy 1.778 -1.8796) (xy 1.778 1.8796)
			)
			(stroke
				(width 0)
				(type default)
			)
			(fill no)
			(layer "F.CrtYd")
		)
		(fp_poly
			(pts
				(xy -1.778 1.8796) (xy -1.778 -1.8796) (xy 1.778 -1.8796) (xy 1.778 1.8796)
			)
			(stroke
				(width 0)
				(type default)
			)
			(fill no)
			(layer "F.Fab")
		)
		(pad "D" smd custom
			(at 0 -0.9525 270)
			(size 0.1905 0.1905)
			(layers "F.Cu" "F.Mask" "F.Paste")
			(net "P12V_MOST8_GATE")
			(options
				(clearance outline)
				(anchor circle)
			)
			(primitives
				(gr_poly
					(pts
						(arc
							(start -0.1778 0.5715)
							(mid -0.321484 0.511984)
							(end -0.381 0.3683)
						)
						(arc
							(start -0.381 -0.3683)
							(mid -0.321484 -0.511984)
							(end -0.1778 -0.5715)
						)
						(arc
							(start 0.1778 -0.5715)
							(mid 0.321484 -0.511984)
							(end 0.381 -0.3683)
						)
						(arc
							(start 0.381 0.3683)
							(mid 0.321484 0.511984)
							(end 0.1778 0.5715)
						)
					)
					(width 0)
					(fill yes)
				)
			)
		)
		(pad "G" smd custom
			(at -0.98425 0.9525 270)
			(size 0.1905 0.1905)
			(layers "F.Cu" "F.Mask" "F.Paste")
			(net "SSD8_PWREN_R")
			(options
				(clearance outline)
				(anchor circle)
			)
			(primitives
				(gr_poly
					(pts
						(arc
							(start -0.1778 0.5715)
							(mid -0.321484 0.511984)
							(end -0.381 0.3683)
						)
						(arc
							(start -0.381 -0.3683)
							(mid -0.321484 -0.511984)
							(end -0.1778 -0.5715)
						)
						(arc
							(start 0.1778 -0.5715)
							(mid 0.321484 -0.511984)
							(end 0.381 -0.3683)
						)
						(arc
							(start 0.381 0.3683)
							(mid 0.321484 0.511984)
							(end 0.1778 0.5715)
						)
					)
					(width 0)
					(fill yes)
				)
			)
		)
		(pad "S" smd custom
			(at 0.98425 0.9525 270)
			(size 0.1905 0.1905)
			(layers "F.Cu" "F.Mask" "F.Paste")
			(net "GND")
			(options
				(clearance outline)
				(anchor circle)
			)
			(primitives
				(gr_poly
					(pts
						(arc
							(start -0.1778 0.5715)
							(mid -0.321484 0.511984)
							(end -0.381 0.3683)
						)
						(arc
							(start -0.381 -0.3683)
							(mid -0.321484 -0.511984)
							(end -0.1778 -0.5715)
						)
						(arc
							(start 0.1778 -0.5715)
							(mid 0.321484 -0.511984)
							(end 0.381 -0.3683)
						)
						(arc
							(start 0.381 0.3683)
							(mid 0.321484 0.511984)
							(end 0.1778 0.5715)
						)
					)
					(width 0)
					(fill yes)
				)
			)
		)
	)
	(footprint ""
		(layer "F.Cu")
		(at 32.131 -81.534 -90)
		(property "Reference" "R405"
			(at 0 0 270)
			(layer "F.SilkS")
			(hide yes)
			(effects
				(font
					(size 1.27 1.27)
				)
			)
		)
		(property "Value" "0R2J-2-GP"
			(at 0.064008 -3.993896 270)
			(unlocked yes)
			(layer "F.Fab")
			(hide yes)
			(effects
				(font
					(size 1.016 1.016)
					(thickness 0.1524)
				)
			)
		)
		(property "Device Type" "R402H16"
			(at 0.064008 -5.517896 270)
			(unlocked yes)
			(layer "F.Fab")
			(hide yes)
			(effects
				(font
					(size 1.016 1.016)
					(thickness 0.1524)
				)
			)
		)
		(duplicate_pad_numbers_are_jumpers no)
		(fp_line
			(start -0.508 -0.9398)
			(end -0.508 0.9398)
			(stroke
				(width 0.1524)
				(type default)
			)
			(layer "F.SilkS")
		)
		(fp_line
			(start 0.508 -0.9398)
			(end -0.508 -0.9398)
			(stroke
				(width 0.1524)
				(type default)
			)
			(layer "F.SilkS")
		)
		(fp_rect
			(start -0.508 0.9398)
			(end 0.508 -0.9398)
			(stroke
				(width 0)
				(type default)
			)
			(fill no)
			(layer "F.CrtYd")
		)
		(fp_rect
			(start -0.508 0.9398)
			(end 0.508 -0.9398)
			(stroke
				(width 0)
				(type default)
			)
			(fill no)
			(layer "F.Fab")
		)
		(pad "1" smd custom
			(at 0 -0.4445 270)
			(size 0.1397 0.1397)
			(layers "F.Cu" "F.Mask" "F.Paste")
			(net "SCL_DR9_R")
			(options
				(clearance outline)
				(anchor circle)
			)
			(primitives
				(gr_poly
					(pts
						(arc
							(start -0.1778 -0.2794)
							(mid -0.249642 -0.249642)
							(end -0.2794 -0.1778)
						)
						(arc
							(start -0.2794 0.1778)
							(mid -0.249642 0.249642)
							(end -0.1778 0.2794)
						)
						(arc
							(start 0.1778 0.2794)
							(mid 0.249642 0.249642)
							(end 0.2794 0.1778)
						)
						(arc
							(start 0.2794 -0.1778)
							(mid 0.249642 -0.249642)
							(end 0.1778 -0.2794)
						)
					)
					(width 0)
					(fill yes)
				)
			)
		)
		(pad "2" smd custom
			(at 0 0.4445 270)
			(size 0.1397 0.1397)
			(layers "F.Cu" "F.Mask" "F.Paste")
			(net "SCL_DR9")
			(options
				(clearance outline)
				(anchor circle)
			)
			(primitives
				(gr_poly
					(pts
						(arc
							(start -0.1778 -0.2794)
							(mid -0.249642 -0.249642)
							(end -0.2794 -0.1778)
						)
						(arc
							(start -0.2794 0.1778)
							(mid -0.249642 0.249642)
							(end -0.1778 0.2794)
						)
						(arc
							(start 0.1778 0.2794)
							(mid 0.249642 0.249642)
							(end 0.2794 0.1778)
						)
						(arc
							(start 0.2794 -0.1778)
							(mid 0.249642 -0.249642)
							(end 0.1778 -0.2794)
						)
					)
					(width 0)
					(fill yes)
				)
			)
		)
	)
	(footprint ""
		(layer "F.Cu")
		(at 217.043 -184.531 -90)
		(property "Reference" "R393"
			(at 0 0 270)
			(layer "F.SilkS")
			(hide yes)
			(effects
				(font
					(size 1.27 1.27)
				)
			)
		)
		(property "Value" "0R2J-2-GP"
			(at 0.064008 -3.993896 270)
			(unlocked yes)
			(layer "F.Fab")
			(hide yes)
			(effects
				(font
					(size 1.016 1.016)
					(thickness 0.1524)
				)
			)
		)
		(property "Device Type" "R402H16"
			(at 0.064008 -5.517896 270)
			(unlocked yes)
			(layer "F.Fab")
			(hide yes)
			(effects
				(font
					(size 1.016 1.016)
					(thickness 0.1524)
				)
			)
		)
		(duplicate_pad_numbers_are_jumpers no)
		(fp_line
			(start -0.508 -0.9398)
			(end -0.508 0.9398)
			(stroke
				(width 0.1524)
				(type default)
			)
			(layer "F.SilkS")
		)
		(fp_line
			(start 0.508 -0.9398)
			(end -0.508 -0.9398)
			(stroke
				(width 0.1524)
				(type default)
			)
			(layer "F.SilkS")
		)
		(fp_rect
			(start -0.508 0.9398)
			(end 0.508 -0.9398)
			(stroke
				(width 0)
				(type default)
			)
			(fill no)
			(layer "F.CrtYd")
		)
		(fp_rect
			(start -0.508 0.9398)
			(end 0.508 -0.9398)
			(stroke
				(width 0)
				(type default)
			)
			(fill no)
			(layer "F.Fab")
		)
		(pad "1" smd custom
			(at 0 -0.4445 270)
			(size 0.1397 0.1397)
			(layers "F.Cu" "F.Mask" "F.Paste")
			(net "SCL_DR3_R")
			(options
				(clearance outline)
				(anchor circle)
			)
			(primitives
				(gr_poly
					(pts
						(arc
							(start -0.1778 -0.2794)
							(mid -0.249642 -0.249642)
							(end -0.2794 -0.1778)
						)
						(arc
							(start -0.2794 0.1778)
							(mid -0.249642 0.249642)
							(end -0.1778 0.2794)
						)
						(arc
							(start 0.1778 0.2794)
							(mid 0.249642 0.249642)
							(end 0.2794 0.1778)
						)
						(arc
							(start 0.2794 -0.1778)
							(mid 0.249642 -0.249642)
							(end 0.1778 -0.2794)
						)
					)
					(width 0)
					(fill yes)
				)
			)
		)
		(pad "2" smd custom
			(at 0 0.4445 270)
			(size 0.1397 0.1397)
			(layers "F.Cu" "F.Mask" "F.Paste")
			(net "SCL_DR3")
			(options
				(clearance outline)
				(anchor circle)
			)
			(primitives
				(gr_poly
					(pts
						(arc
							(start -0.1778 -0.2794)
							(mid -0.249642 -0.249642)
							(end -0.2794 -0.1778)
						)
						(arc
							(start -0.2794 0.1778)
							(mid -0.249642 0.249642)
							(end -0.1778 0.2794)
						)
						(arc
							(start 0.1778 0.2794)
							(mid 0.249642 0.249642)
							(end 0.2794 0.1778)
						)
						(arc
							(start 0.2794 -0.1778)
							(mid 0.249642 -0.249642)
							(end 0.1778 -0.2794)
						)
					)
					(width 0)
					(fill yes)
				)
			)
		)
	)
	(footprint ""
		(layer "F.Cu")
		(at 29.7688 -191.897 -90)
		(property "Reference" "U17"
			(at 0 0 270)
			(layer "F.SilkS")
			(hide yes)
			(effects
				(font
					(size 1.27 1.27)
				)
			)
		)
		(property "Value" "P2003EVG-GP"
			(at 0 -11.1252 270)
			(unlocked yes)
			(layer "F.Fab")
			(hide yes)
			(effects
				(font
					(size 1.016 1.016)
					(thickness 0.1524)
				)
			)
		)
		(property "Device Type" "SOIC8H79"
			(at 0 -12.6492 270)
			(unlocked yes)
			(layer "F.Fab")
			(hide yes)
			(effects
				(font
					(size 1.016 1.016)
					(thickness 0.1524)
				)
			)
		)
		(duplicate_pad_numbers_are_jumpers no)
		(fp_line
			(start -2.6162 3.429)
			(end -2.6162 1.4732)
			(stroke
				(width 0.4064)
				(type default)
			)
			(layer "F.SilkS")
		)
		(fp_line
			(start -2.7432 1.4224)
			(end 2.1336 1.4224)
			(stroke
				(width 0.1524)
				(type default)
			)
			(layer "F.SilkS")
		)
		(fp_line
			(start 2.1336 1.4224)
			(end 2.1336 -1.4224)
			(stroke
				(width 0.1524)
				(type default)
			)
			(layer "F.SilkS")
		)
		(fp_line
			(start -2.2352 0)
			(end -2.7432 0.508)
			(stroke
				(width 0.1524)
				(type default)
			)
			(layer "F.SilkS")
		)
		(fp_line
			(start -2.7432 -0.508)
			(end -2.2352 0)
			(stroke
				(width 0.1524)
				(type default)
			)
			(layer "F.SilkS")
		)
		(fp_line
			(start -2.7432 -1.4224)
			(end -2.7432 1.4224)
			(stroke
				(width 0.1524)
				(type default)
			)
			(layer "F.SilkS")
		)
		(fp_line
			(start 2.1336 -1.4224)
			(end -2.7432 -1.4224)
			(stroke
				(width 0.1524)
				(type default)
			)
			(layer "F.SilkS")
		)
		(fp_poly
			(pts
				(xy 2.2098 -1.4224) (xy 2.2098 1.4224) (xy -2.2225 1.4224) (xy -2.2225 -1.4224)
			)
			(stroke
				(width 0)
				(type default)
			)
			(fill yes)
			(layer "F.SilkS")
		)
		(fp_rect
			(start -2.4511 2.9972)
			(end 2.4511 -2.9972)
			(stroke
				(width 0)
				(type default)
			)
			(fill no)
			(layer "F.CrtYd")
		)
		(fp_poly
			(pts
				(xy -2.8194 3.6322) (xy -2.8194 -3.6322) (xy 2.8194 -3.6322) (xy 2.8194 -2.2987) (xy 2.4511 -2.2987)
				(xy 2.4511 -2.9972) (xy -2.4511 -2.9972) (xy -2.4511 2.9972) (xy 2.4511 2.9972) (xy 2.4511 -2.286)
				(xy 2.8194 -2.286) (xy 2.8194 3.6322)
			)
			(stroke
				(width 0)
				(type default)
			)
			(fill no)
			(layer "F.CrtYd")
		)
		(fp_rect
			(start -2.8194 3.6322)
			(end 2.8194 -3.6322)
			(stroke
				(width 0)
				(type default)
			)
			(fill no)
			(layer "F.Fab")
		)
		(pad "1" smd rect
			(at -1.905 2.54 270)
			(size 0.635 1.651)
			(layers "F.Cu" "F.Mask" "F.Paste")
			(net "P12V")
		)
		(pad "2" smd rect
			(at -0.635 2.54 270)
			(size 0.635 1.651)
			(layers "F.Cu" "F.Mask" "F.Paste")
			(net "P12V")
		)
		(pad "3" smd rect
			(at 0.635 2.54 270)
			(size 0.635 1.651)
			(layers "F.Cu" "F.Mask" "F.Paste")
			(net "P12V")
		)
		(pad "4" smd rect
			(at 1.905 2.54 270)
			(size 0.635 1.651)
			(layers "F.Cu" "F.Mask" "F.Paste")
			(net "SW_SSD8_N")
		)
		(pad "5" smd rect
			(at 1.905 -2.54 270)
			(size 0.635 1.651)
			(layers "F.Cu" "F.Mask" "F.Paste")
			(net "P12V_SSD8")
		)
		(pad "6" smd rect
			(at 0.635 -2.54 270)
			(size 0.635 1.651)
			(layers "F.Cu" "F.Mask" "F.Paste")
			(net "P12V_SSD8")
		)
		(pad "7" smd rect
			(at -0.635 -2.54 270)
			(size 0.635 1.651)
			(layers "F.Cu" "F.Mask" "F.Paste")
			(net "P12V_SSD8")
		)
		(pad "8" smd rect
			(at -1.905 -2.54 270)
			(size 0.635 1.651)
			(layers "F.Cu" "F.Mask" "F.Paste")
			(net "P12V_SSD8")
		)
	)
	(footprint ""
		(layer "F.Cu")
		(at 90.932 -19.304 90)
		(property "Reference" "TP150"
			(at 0 0 90)
			(layer "F.SilkS")
			(hide yes)
			(effects
				(font
					(size 1.27 1.27)
				)
			)
		)
		(property "Value" "TPAD32-GP"
			(at -0.0508 -1.6764 90)
			(unlocked yes)
			(layer "F.Fab")
			(hide yes)
			(effects
				(font
					(size 1.016 1.016)
					(thickness 0.1524)
				)
			)
		)
		(property "Device Type" "TPAD32"
			(at -0.0508 -3.2004 90)
			(unlocked yes)
			(layer "F.Fab")
			(hide yes)
			(effects
				(font
					(size 1.016 1.016)
					(thickness 0.1524)
				)
			)
		)
		(duplicate_pad_numbers_are_jumpers no)
		(fp_poly
			(pts
				(arc
					(start 0 0.4064)
					(mid 0 -0.4064)
					(end 0 0.4064)
				)
			)
			(stroke
				(width 0)
				(type default)
			)
			(fill no)
			(layer "F.CrtYd")
		)
		(fp_poly
			(pts
				(arc
					(start 0 0.7112)
					(mid 0 -0.7112)
					(end 0 0.7112)
				)
			)
			(stroke
				(width 0)
				(type default)
			)
			(fill no)
			(layer "F.Fab")
		)
		(pad "1" smd circle
			(at 0 0 90)
			(size 0.8128 0.8128)
			(layers "F.Cu" "F.Mask" "F.Paste")
			(net "VOL_SEN_ALERT")
		)
	)
	(footprint ""
		(layer "F.Cu")
		(at 15.204186 -52.494434)
		(property "Reference" "R9956"
			(at 0 0 0)
			(layer "F.SilkS")
			(hide yes)
			(effects
				(font
					(size 1.27 1.27)
				)
			)
		)
		(property "Value" "4K7R2J-2-GP"
			(at 0.064008 -3.993896 0)
			(unlocked yes)
			(layer "F.Fab")
			(hide yes)
			(effects
				(font
					(size 1.016 1.016)
					(thickness 0.1524)
				)
			)
		)
		(property "Device Type" "R402H16"
			(at 0.064008 -5.517896 0)
			(unlocked yes)
			(layer "F.Fab")
			(hide yes)
			(effects
				(font
					(size 1.016 1.016)
					(thickness 0.1524)
				)
			)
		)
		(duplicate_pad_numbers_are_jumpers no)
		(fp_line
			(start -0.508 -0.9398)
			(end -0.508 0.9398)
			(stroke
				(width 0.1524)
				(type default)
			)
			(layer "F.SilkS")
		)
		(fp_line
			(start 0.508 -0.9398)
			(end -0.508 -0.9398)
			(stroke
				(width 0.1524)
				(type default)
			)
			(layer "F.SilkS")
		)
		(fp_rect
			(start -0.508 0.9398)
			(end 0.508 -0.9398)
			(stroke
				(width 0)
				(type default)
			)
			(fill no)
			(layer "F.CrtYd")
		)
		(fp_rect
			(start -0.508 0.9398)
			(end 0.508 -0.9398)
			(stroke
				(width 0)
				(type default)
			)
			(fill no)
			(layer "F.Fab")
		)
		(pad "1" smd custom
			(at 0 -0.4445)
			(size 0.1397 0.1397)
			(layers "F.Cu" "F.Mask" "F.Paste")
			(net "P3V3")
			(options
				(clearance outline)
				(anchor circle)
			)
			(primitives
				(gr_poly
					(pts
						(arc
							(start -0.1778 -0.2794)
							(mid -0.249642 -0.249642)
							(end -0.2794 -0.1778)
						)
						(arc
							(start -0.2794 0.1778)
							(mid -0.249642 0.249642)
							(end -0.1778 0.2794)
						)
						(arc
							(start 0.1778 0.2794)
							(mid 0.249642 0.249642)
							(end 0.2794 0.1778)
						)
						(arc
							(start 0.2794 -0.1778)
							(mid 0.249642 -0.249642)
							(end 0.1778 -0.2794)
						)
					)
					(width 0)
					(fill yes)
				)
			)
		)
		(pad "2" smd custom
			(at 0 0.4445)
			(size 0.1397 0.1397)
			(layers "F.Cu" "F.Mask" "F.Paste")
			(net "SSD_ACT_DR14_MOS_N")
			(options
				(clearance outline)
				(anchor circle)
			)
			(primitives
				(gr_poly
					(pts
						(arc
							(start -0.1778 -0.2794)
							(mid -0.249642 -0.249642)
							(end -0.2794 -0.1778)
						)
						(arc
							(start -0.2794 0.1778)
							(mid -0.249642 0.249642)
							(end -0.1778 0.2794)
						)
						(arc
							(start 0.1778 0.2794)
							(mid 0.249642 0.249642)
							(end 0.2794 0.1778)
						)
						(arc
							(start 0.2794 -0.1778)
							(mid 0.249642 -0.249642)
							(end 0.1778 -0.2794)
						)
					)
					(width 0)
					(fill yes)
				)
			)
		)
	)
	(footprint ""
		(layer "F.Cu")
		(at 86.487 -440.436 180)
		(property "Reference" "R9064"
			(at 0 0 180)
			(layer "F.SilkS")
			(hide yes)
			(effects
				(font
					(size 1.27 1.27)
				)
			)
		)
		(property "Value" "27R2F-GP"
			(at 0.064008 -3.993896 180)
			(unlocked yes)
			(layer "F.Fab")
			(hide yes)
			(effects
				(font
					(size 1.016 1.016)
					(thickness 0.1524)
				)
			)
		)
		(property "Device Type" "R402H16"
			(at 0.064008 -5.517896 180)
			(unlocked yes)
			(layer "F.Fab")
			(hide yes)
			(effects
				(font
					(size 1.016 1.016)
					(thickness 0.1524)
				)
			)
		)
		(duplicate_pad_numbers_are_jumpers no)
		(fp_line
			(start 0.508 -0.9398)
			(end -0.508 -0.9398)
			(stroke
				(width 0.1524)
				(type default)
			)
			(layer "F.SilkS")
		)
		(fp_line
			(start -0.508 -0.9398)
			(end -0.508 0.9398)
			(stroke
				(width 0.1524)
				(type default)
			)
			(layer "F.SilkS")
		)
		(fp_rect
			(start -0.508 0.9398)
			(end 0.508 -0.9398)
			(stroke
				(width 0)
				(type default)
			)
			(fill no)
			(layer "F.CrtYd")
		)
		(fp_rect
			(start -0.508 0.9398)
			(end 0.508 -0.9398)
			(stroke
				(width 0)
				(type default)
			)
			(fill no)
			(layer "F.Fab")
		)
		(pad "1" smd custom
			(at 0 -0.4445 180)
			(size 0.1397 0.1397)
			(layers "F.Cu" "F.Mask" "F.Paste")
			(net "PE_CLK_100M_DR5_1_R_N")
			(options
				(clearance outline)
				(anchor circle)
			)
			(primitives
				(gr_poly
					(pts
						(arc
							(start -0.1778 -0.2794)
							(mid -0.249642 -0.249642)
							(end -0.2794 -0.1778)
						)
						(arc
							(start -0.2794 0.1778)
							(mid -0.249642 0.249642)
							(end -0.1778 0.2794)
						)
						(arc
							(start 0.1778 0.2794)
							(mid 0.249642 0.249642)
							(end 0.2794 0.1778)
						)
						(arc
							(start 0.2794 -0.1778)
							(mid 0.249642 -0.249642)
							(end 0.1778 -0.2794)
						)
					)
					(width 0)
					(fill yes)
				)
			)
		)
		(pad "2" smd custom
			(at 0 0.4445 180)
			(size 0.1397 0.1397)
			(layers "F.Cu" "F.Mask" "F.Paste")
			(net "PE_CLK100M_DR5_1_N")
			(options
				(clearance outline)
				(anchor circle)
			)
			(primitives
				(gr_poly
					(pts
						(arc
							(start -0.1778 -0.2794)
							(mid -0.249642 -0.249642)
							(end -0.2794 -0.1778)
						)
						(arc
							(start -0.2794 0.1778)
							(mid -0.249642 0.249642)
							(end -0.1778 0.2794)
						)
						(arc
							(start 0.1778 0.2794)
							(mid 0.249642 0.249642)
							(end 0.2794 0.1778)
						)
						(arc
							(start 0.2794 -0.1778)
							(mid 0.249642 -0.249642)
							(end 0.1778 -0.2794)
						)
					)
					(width 0)
					(fill yes)
				)
			)
		)
	)
	(footprint ""
		(layer "F.Cu")
		(at 214.757 -397.891 -90)
		(property "Reference" "U10"
			(at 0 0 270)
			(layer "F.SilkS")
			(hide yes)
			(effects
				(font
					(size 1.27 1.27)
				)
			)
		)
		(property "Value" "P2003EVG-GP"
			(at 0 -11.1252 270)
			(unlocked yes)
			(layer "F.Fab")
			(hide yes)
			(effects
				(font
					(size 1.016 1.016)
					(thickness 0.1524)
				)
			)
		)
		(property "Device Type" "SOIC8H79"
			(at 0 -12.6492 270)
			(unlocked yes)
			(layer "F.Fab")
			(hide yes)
			(effects
				(font
					(size 1.016 1.016)
					(thickness 0.1524)
				)
			)
		)
		(duplicate_pad_numbers_are_jumpers no)
		(fp_line
			(start -2.6162 3.429)
			(end -2.6162 1.4732)
			(stroke
				(width 0.4064)
				(type default)
			)
			(layer "F.SilkS")
		)
		(fp_line
			(start -2.7432 1.4224)
			(end 2.1336 1.4224)
			(stroke
				(width 0.1524)
				(type default)
			)
			(layer "F.SilkS")
		)
		(fp_line
			(start 2.1336 1.4224)
			(end 2.1336 -1.4224)
			(stroke
				(width 0.1524)
				(type default)
			)
			(layer "F.SilkS")
		)
		(fp_line
			(start -2.2352 0)
			(end -2.7432 0.508)
			(stroke
				(width 0.1524)
				(type default)
			)
			(layer "F.SilkS")
		)
		(fp_line
			(start -2.7432 -0.508)
			(end -2.2352 0)
			(stroke
				(width 0.1524)
				(type default)
			)
			(layer "F.SilkS")
		)
		(fp_line
			(start -2.7432 -1.4224)
			(end -2.7432 1.4224)
			(stroke
				(width 0.1524)
				(type default)
			)
			(layer "F.SilkS")
		)
		(fp_line
			(start 2.1336 -1.4224)
			(end -2.7432 -1.4224)
			(stroke
				(width 0.1524)
				(type default)
			)
			(layer "F.SilkS")
		)
		(fp_poly
			(pts
				(xy 2.2098 -1.4224) (xy 2.2098 1.4224) (xy -2.2225 1.4224) (xy -2.2225 -1.4224)
			)
			(stroke
				(width 0)
				(type default)
			)
			(fill yes)
			(layer "F.SilkS")
		)
		(fp_rect
			(start -2.4511 2.9972)
			(end 2.4511 -2.9972)
			(stroke
				(width 0)
				(type default)
			)
			(fill no)
			(layer "F.CrtYd")
		)
		(fp_poly
			(pts
				(xy -2.8194 3.6322) (xy -2.8194 -3.6322) (xy 2.8194 -3.6322) (xy 2.8194 -2.2987) (xy 2.4511 -2.2987)
				(xy 2.4511 -2.9972) (xy -2.4511 -2.9972) (xy -2.4511 2.9972) (xy 2.4511 2.9972) (xy 2.4511 -2.286)
				(xy 2.8194 -2.286) (xy 2.8194 3.6322)
			)
			(stroke
				(width 0)
				(type default)
			)
			(fill no)
			(layer "F.CrtYd")
		)
		(fp_rect
			(start -2.8194 3.6322)
			(end 2.8194 -3.6322)
			(stroke
				(width 0)
				(type default)
			)
			(fill no)
			(layer "F.Fab")
		)
		(pad "1" smd rect
			(at -1.905 2.54 270)
			(size 0.635 1.651)
			(layers "F.Cu" "F.Mask" "F.Paste")
			(net "P12V")
		)
		(pad "2" smd rect
			(at -0.635 2.54 270)
			(size 0.635 1.651)
			(layers "F.Cu" "F.Mask" "F.Paste")
			(net "P12V")
		)
		(pad "3" smd rect
			(at 0.635 2.54 270)
			(size 0.635 1.651)
			(layers "F.Cu" "F.Mask" "F.Paste")
			(net "P12V")
		)
		(pad "4" smd rect
			(at 1.905 2.54 270)
			(size 0.635 1.651)
			(layers "F.Cu" "F.Mask" "F.Paste")
			(net "SW_SSD1_N")
		)
		(pad "5" smd rect
			(at 1.905 -2.54 270)
			(size 0.635 1.651)
			(layers "F.Cu" "F.Mask" "F.Paste")
			(net "P12V_SSD1")
		)
		(pad "6" smd rect
			(at 0.635 -2.54 270)
			(size 0.635 1.651)
			(layers "F.Cu" "F.Mask" "F.Paste")
			(net "P12V_SSD1")
		)
		(pad "7" smd rect
			(at -0.635 -2.54 270)
			(size 0.635 1.651)
			(layers "F.Cu" "F.Mask" "F.Paste")
			(net "P12V_SSD1")
		)
		(pad "8" smd rect
			(at -1.905 -2.54 270)
			(size 0.635 1.651)
			(layers "F.Cu" "F.Mask" "F.Paste")
			(net "P12V_SSD1")
		)
	)
	(footprint ""
		(layer "F.Cu")
		(at 20.850098 -26.329894 -90)
		(property "Reference" "J14"
			(at 0 0 270)
			(layer "F.SilkS")
			(hide yes)
			(effects
				(font
					(size 1.27 1.27)
				)
			)
		)
		(property "Value" "PCISLT68-14-GP-U1"
			(at -22.225 12.7508 270)
			(unlocked yes)
			(layer "F.Fab")
			(hide yes)
			(effects
				(font
					(size 1.016 1.016)
					(thickness 0.1524)
				)
			)
		)
		(property "Device Type" "SD-78827-0001"
			(at -22.225 11.2268 270)
			(unlocked yes)
			(layer "F.Fab")
			(hide yes)
			(effects
				(font
					(size 1.016 1.016)
					(thickness 0.1524)
				)
			)
		)
		(duplicate_pad_numbers_are_jumpers no)
		(fp_line
			(start -20.4724 12.0142)
			(end -20.4724 4.6736)
			(stroke
				(width 0.1524)
				(type default)
			)
			(layer "F.SilkS")
		)
		(fp_line
			(start -17.8435 12.0142)
			(end -20.4724 12.0142)
			(stroke
				(width 0.1524)
				(type default)
			)
			(layer "F.SilkS")
		)
		(fp_line
			(start 17.8435 12.0142)
			(end 17.8435 10.3124)
			(stroke
				(width 0.1524)
				(type default)
			)
			(layer "F.SilkS")
		)
		(fp_line
			(start 20.4724 12.0142)
			(end 17.8435 12.0142)
			(stroke
				(width 0.1524)
				(type default)
			)
			(layer "F.SilkS")
		)
		(fp_line
			(start -17.8435 10.3124)
			(end -17.8435 12.0142)
			(stroke
				(width 0.1524)
				(type default)
			)
			(layer "F.SilkS")
		)
		(fp_line
			(start 17.8435 10.3124)
			(end -17.8435 10.3124)
			(stroke
				(width 0.1524)
				(type default)
			)
			(layer "F.SilkS")
		)
		(fp_line
			(start -23.749 4.6736)
			(end -23.749 0.0254)
			(stroke
				(width 0.1524)
				(type default)
			)
			(layer "F.SilkS")
		)
		(fp_line
			(start -20.4724 4.6736)
			(end -23.749 4.6736)
			(stroke
				(width 0.1524)
				(type default)
			)
			(layer "F.SilkS")
		)
		(fp_line
			(start 20.4724 4.6736)
			(end 20.4724 12.0142)
			(stroke
				(width 0.1524)
				(type default)
			)
			(layer "F.SilkS")
		)
		(fp_line
			(start 23.749 4.6736)
			(end 20.4724 4.6736)
			(stroke
				(width 0.1524)
				(type default)
			)
			(layer "F.SilkS")
		)
		(fp_line
			(start -23.117556 2.896108)
			(end -23.117556 1.803908)
			(stroke
				(width 0.3048)
				(type default)
			)
			(layer "F.SilkS")
		)
		(fp_line
			(start 20.882356 2.896108)
			(end 20.882356 1.803908)
			(stroke
				(width 0.3048)
				(type default)
			)
			(layer "F.SilkS")
		)
		(fp_line
			(start -20.882356 1.803908)
			(end -20.882356 2.896108)
			(stroke
				(width 0.3048)
				(type default)
			)
			(layer "F.SilkS")
		)
		(fp_line
			(start 23.117556 1.803908)
			(end 23.117556 2.896108)
			(stroke
				(width 0.3048)
				(type default)
			)
			(layer "F.SilkS")
		)
		(fp_line
			(start -23.749 0.0254)
			(end -20.4724 0.0254)
			(stroke
				(width 0.1524)
				(type default)
			)
			(layer "F.SilkS")
		)
		(fp_line
			(start -20.4724 0.0254)
			(end -20.4724 -3.4036)
			(stroke
				(width 0.1524)
				(type default)
			)
			(layer "F.SilkS")
		)
		(fp_line
			(start 20.4724 0.0254)
			(end 23.749 0.0254)
			(stroke
				(width 0.1524)
				(type default)
			)
			(layer "F.SilkS")
		)
		(fp_line
			(start 23.749 0.0254)
			(end 23.749 4.6736)
			(stroke
				(width 0.1524)
				(type default)
			)
			(layer "F.SilkS")
		)
		(fp_line
			(start -20.4724 -3.4036)
			(end 20.4724 -3.4036)
			(stroke
				(width 0.1524)
				(type default)
			)
			(layer "F.SilkS")
		)
		(fp_line
			(start 20.4724 -3.4036)
			(end 20.4724 0.0254)
			(stroke
				(width 0.1524)
				(type default)
			)
			(layer "F.SilkS")
		)
		(fp_arc
			(start -20.882356 2.896108)
			(mid -21.999956 4.013708)
			(end -23.117556 2.896108)
			(stroke
				(width 0.3048)
				(type default)
			)
			(layer "F.SilkS")
		)
		(fp_arc
			(start 23.117556 2.896108)
			(mid 21.999956 4.013708)
			(end 20.882356 2.896108)
			(stroke
				(width 0.3048)
				(type default)
			)
			(layer "F.SilkS")
		)
		(fp_arc
			(start -23.117556 1.803908)
			(mid -21.999956 0.686308)
			(end -20.882356 1.803908)
			(stroke
				(width 0.3048)
				(type default)
			)
			(layer "F.SilkS")
		)
		(fp_arc
			(start 20.882356 1.803908)
			(mid 21.999956 0.686308)
			(end 23.117556 1.803908)
			(stroke
				(width 0.3048)
				(type default)
			)
			(layer "F.SilkS")
		)
		(fp_poly
			(pts
				(xy -20.2184 11.7602) (xy -20.2184 4.4196) (xy -23.495 4.4196) (xy -23.495 0.2794) (xy -20.2184 0.2794)
				(xy -20.2184 -3.1496) (xy 20.2184 -3.1496) (xy 20.2184 0.2794) (xy 23.495 0.2794) (xy 23.495 4.4196)
				(xy 20.2184 4.4196) (xy 20.2184 11.7602) (xy 18.0975 11.7602) (xy 18.0975 10.0584) (xy -18.0975 10.0584)
				(xy -18.0975 11.7602)
			)
			(stroke
				(width 0)
				(type default)
			)
			(fill no)
			(layer "F.CrtYd")
		)
		(fp_poly
			(pts
				(xy -21.2471 16.256) (xy -21.2471 4.9276) (xy -24.003 4.9276) (xy -24.003 -0.2286) (xy -20.7264 -0.2286)
				(xy -20.7264 -3.6576) (xy 20.7264 -3.6576) (xy 20.7264 -0.2286) (xy 24.003 -0.2286) (xy 24.003 -0.00635)
				(xy 20.2184 -0.00635) (xy 20.2184 -3.1496) (xy -20.2184 -3.1496) (xy -20.2184 0.2794) (xy -23.495 0.2794)
				(xy -23.495 4.4196) (xy -20.2184 4.4196) (xy -20.2184 11.7602) (xy -18.0975 11.7602) (xy -18.0975 10.0584)
				(xy 18.0975 10.0584) (xy 18.0975 11.7602) (xy 20.2184 11.7602) (xy 20.2184 4.4196) (xy 23.495 4.4196)
				(xy 23.495 0.2794) (xy 20.2184 0.2794) (xy 20.2184 0.00635) (xy 24.003 0.00635) (xy 24.003 4.9276)
				(xy 21.2471 4.9276) (xy 21.2471 16.256)
			)
			(stroke
				(width 0)
				(type default)
			)
			(fill no)
			(layer "F.CrtYd")
		)
		(fp_poly
			(pts
				(xy -21.2471 16.256) (xy -21.2471 4.9276) (xy -24.003 4.9276) (xy -24.003 -0.2286) (xy -20.7264 -0.2286)
				(xy -20.7264 -3.6576) (xy 20.7264 -3.6576) (xy 20.7264 -0.2286) (xy 24.003 -0.2286) (xy 24.003 4.9276)
				(xy 21.2471 4.9276) (xy 21.2471 16.256)
			)
			(stroke
				(width 0)
				(type default)
			)
			(fill no)
			(layer "F.Fab")
		)
		(pad "" np_thru_hole circle
			(at -18.999962 0 270)
			(size 0.254 0.254)
			(drill 1.8542)
			(layers "*.Cu" "*.Mask")
			(clearance 1.1557)
			(thermal_gap 1.1557)
		)
		(pad "" np_thru_hole circle
			(at 18.999962 0 270)
			(size 0.254 0.254)
			(drill 1.8542)
			(layers "*.Cu" "*.Mask")
			(clearance 1.1557)
			(thermal_gap 1.1557)
		)
		(pad "E1" smd rect
			(at -7.079996 1.240028 270)
			(size 0.508 2.0066)
			(layers "F.Cu" "F.Mask" "F.Paste")
			(net "PE_CLK100M_DR14_2_P")
		)
		(pad "E2" smd rect
			(at -6.279896 1.240028 270)
			(size 0.508 2.0066)
			(layers "F.Cu" "F.Mask" "F.Paste")
			(net "PE_CLK100M_DR14_2_N")
		)
		(pad "E3" smd rect
			(at -5.48005 1.240028 270)
			(size 0.508 2.0066)
			(layers "F.Cu" "F.Mask" "F.Paste")
			(net "P3V3")
		)
		(pad "E4" smd rect
			(at -4.67995 1.240028 270)
			(size 0.508 2.0066)
			(layers "F.Cu" "F.Mask" "F.Paste")
			(net "SSD14_PERST_N")
		)
		(pad "E5" smd rect
			(at -3.880104 1.240028 270)
			(size 0.508 2.0066)
			(layers "F.Cu" "F.Mask" "F.Paste")
			(net "SSD14_PERST_N")
		)
		(pad "E6" smd rect
			(at -3.080004 1.240028 270)
			(size 0.508 2.0066)
			(layers "F.Cu" "F.Mask" "F.Paste")
			(net "Net_1215")
		)
		(pad "E7" smd rect
			(at -15.48003 -1.949958 270)
			(size 0.508 2.0066)
			(layers "F.Cu" "F.Mask" "F.Paste")
			(net "PE_CLK100M_DR14_1_P")
		)
		(pad "E8" smd rect
			(at -14.67993 -1.949958 270)
			(size 0.508 2.0066)
			(layers "F.Cu" "F.Mask" "F.Paste")
			(net "PE_CLK100M_DR14_1_N")
		)
		(pad "E9" smd rect
			(at -13.880084 -1.949958 270)
			(size 0.508 2.0066)
			(layers "F.Cu" "F.Mask" "F.Paste")
			(net "GND")
		)
		(pad "E10" smd rect
			(at -13.079984 -1.949958 270)
			(size 0.508 2.0066)
			(layers "F.Cu" "F.Mask" "F.Paste")
			(net "PE_TX1_DR14_N")
		)
		(pad "E11" smd rect
			(at -12.279884 -1.949958 270)
			(size 0.508 2.0066)
			(layers "F.Cu" "F.Mask" "F.Paste")
			(net "PE_TX1_DR14_P")
		)
		(pad "E12" smd rect
			(at -11.480038 -1.949958 270)
			(size 0.508 2.0066)
			(layers "F.Cu" "F.Mask" "F.Paste")
			(net "GND")
		)
		(pad "E13" smd rect
			(at -10.679938 -1.949958 270)
			(size 0.508 2.0066)
			(layers "F.Cu" "F.Mask" "F.Paste")
			(net "PE_RX1_DR14_N")
		)
		(pad "E14" smd rect
			(at -9.880092 -1.949958 270)
			(size 0.508 2.0066)
			(layers "F.Cu" "F.Mask" "F.Paste")
			(net "PE_RX1_DR14_P")
		)
		(pad "E15" smd rect
			(at -9.079992 -1.949958 270)
			(size 0.508 2.0066)
			(layers "F.Cu" "F.Mask" "F.Paste")
			(net "GND")
		)
		(pad "E16" smd rect
			(at -8.279892 -1.949958 270)
			(size 0.508 2.0066)
			(layers "F.Cu" "F.Mask" "F.Paste")
			(net "Net_1222")
		)
		(pad "E17" smd rect
			(at 9.320022 -1.949958 270)
			(size 0.508 2.0066)
			(layers "F.Cu" "F.Mask" "F.Paste")
			(net "PE_TX4_DR14_N")
		)
		(pad "E18" smd rect
			(at 10.120122 -1.949958 270)
			(size 0.508 2.0066)
			(layers "F.Cu" "F.Mask" "F.Paste")
			(net "PE_TX4_DR14_P")
		)
		(pad "E19" smd rect
			(at 10.919968 -1.949958 270)
			(size 0.508 2.0066)
			(layers "F.Cu" "F.Mask" "F.Paste")
			(net "GND")
		)
		(pad "E20" smd rect
			(at 11.720068 -1.949958 270)
			(size 0.508 2.0066)
			(layers "F.Cu" "F.Mask" "F.Paste")
			(net "PE_RX4_DR14_N")
		)
		(pad "E21" smd rect
			(at 12.519914 -1.949958 270)
			(size 0.508 2.0066)
			(layers "F.Cu" "F.Mask" "F.Paste")
			(net "PE_RX4_DR14_P")
		)
		(pad "E22" smd rect
			(at 13.320014 -1.949958 270)
			(size 0.508 2.0066)
			(layers "F.Cu" "F.Mask" "F.Paste")
			(net "GND")
		)
		(pad "E23" smd rect
			(at 14.120114 -1.949958 270)
			(size 0.508 2.0066)
			(layers "F.Cu" "F.Mask" "F.Paste")
			(net "SCL_DR14_R")
		)
		(pad "E24" smd rect
			(at 14.91996 -1.949958 270)
			(size 0.508 2.0066)
			(layers "F.Cu" "F.Mask" "F.Paste")
			(net "SDA_DR14_R")
		)
		(pad "E25" smd rect
			(at 15.72006 -1.949958 270)
			(size 0.508 2.0066)
			(layers "F.Cu" "F.Mask" "F.Paste")
			(net "DUALPORTEN#14")
		)
		(pad "P1" smd rect
			(at -1.905 0.824992 270)
			(size 0.6604 2.0574)
			(layers "F.Cu" "F.Mask" "F.Paste")
			(net "Net_1218")
		)
		(pad "P2" smd rect
			(at -0.635 0.824992 270)
			(size 0.6604 2.0574)
			(layers "F.Cu" "F.Mask" "F.Paste")
			(net "Net_1217")
		)
		(pad "P3" smd rect
			(at 0.635 0.824992 270)
			(size 0.6604 2.0574)
			(layers "F.Cu" "F.Mask" "F.Paste")
			(net "Net_1216")
		)
		(pad "P4" smd rect
			(at 1.905 0.824992 270)
			(size 0.6604 2.0574)
			(layers "F.Cu" "F.Mask" "F.Paste")
			(net "SSD14_CLK0_OE_N")
		)
		(pad "P5" smd rect
			(at 3.175 0.824992 270)
			(size 0.6604 2.0574)
			(layers "F.Cu" "F.Mask" "F.Paste")
			(net "GND")
		)
		(pad "P6" smd rect
			(at 4.445 0.824992 270)
			(size 0.6604 2.0574)
			(layers "F.Cu" "F.Mask" "F.Paste")
			(net "GND")
		)
		(pad "P7" smd rect
			(at 5.715 0.824992 270)
			(size 0.6604 2.0574)
			(layers "F.Cu" "F.Mask" "F.Paste")
			(net "Net_89")
		)
		(pad "P8" smd rect
			(at 6.985 0.824992 270)
			(size 0.6604 2.0574)
			(layers "F.Cu" "F.Mask" "F.Paste")
			(net "Net_61")
		)
		(pad "P9" smd rect
			(at 8.255 0.824992 270)
			(size 0.6604 2.0574)
			(layers "F.Cu" "F.Mask" "F.Paste")
			(net "Net_75")
		)
		(pad "P10" smd rect
			(at 9.525 0.824992 270)
			(size 0.6604 2.0574)
			(layers "F.Cu" "F.Mask" "F.Paste")
			(net "SSD_PRSNT_NET14")
		)
		(pad "P11" smd rect
			(at 10.795 0.824992 270)
			(size 0.6604 2.0574)
			(layers "F.Cu" "F.Mask" "F.Paste")
			(net "SSD_ACT_DR14")
		)
		(pad "P12" smd rect
			(at 12.065 0.824992 270)
			(size 0.6604 2.0574)
			(layers "F.Cu" "F.Mask" "F.Paste")
			(net "GND")
		)
		(pad "P13" smd rect
			(at 13.335 0.824992 270)
			(size 0.6604 2.0574)
			(layers "F.Cu" "F.Mask" "F.Paste")
			(net "12V_PRECH_SSD14")
		)
		(pad "P14" smd rect
			(at 14.605 0.824992 270)
			(size 0.6604 2.0574)
			(layers "F.Cu" "F.Mask" "F.Paste")
			(net "P12V_SSD14")
		)
		(pad "P15" smd rect
			(at 15.875 0.824992 270)
			(size 0.6604 2.0574)
			(layers "F.Cu" "F.Mask" "F.Paste")
			(net "P12V_SSD14")
		)
		(pad "PTH1" thru_hole oval
			(at -21.999956 2.350008 270)
			(size 1.524 2.6162)
			(drill oval 0.8128 1.905)
			(layers "*.Cu" "*.Mask")
			(remove_unused_layers no)
			(net "Net_1227")
			(clearance 0.1524)
			(thermal_gap 0.1524)
		)
		(pad "PTH2" thru_hole oval
			(at 21.999956 2.350008 270)
			(size 1.524 2.6162)
			(drill oval 0.8128 1.905)
			(layers "*.Cu" "*.Mask")
			(remove_unused_layers no)
			(net "Net_1211")
			(clearance 0.1524)
			(thermal_gap 0.1524)
		)
		(pad "S1" smd rect
			(at -15.875 0.824992 270)
			(size 0.6604 2.0574)
			(layers "F.Cu" "F.Mask" "F.Paste")
			(net "GND")
		)
		(pad "S2" smd rect
			(at -14.605 0.824992 270)
			(size 0.6604 2.0574)
			(layers "F.Cu" "F.Mask" "F.Paste")
			(net "Net_1226")
		)
		(pad "S3" smd rect
			(at -13.335 0.824992 270)
			(size 0.6604 2.0574)
			(layers "F.Cu" "F.Mask" "F.Paste")
			(net "Net_1225")
		)
		(pad "S4" smd rect
			(at -12.065 0.824992 270)
			(size 0.6604 2.0574)
			(layers "F.Cu" "F.Mask" "F.Paste")
			(net "GND")
		)
		(pad "S5" smd rect
			(at -10.795 0.824992 270)
			(size 0.6604 2.0574)
			(layers "F.Cu" "F.Mask" "F.Paste")
			(net "Net_1224")
		)
		(pad "S6" smd rect
			(at -9.525 0.824992 270)
			(size 0.6604 2.0574)
			(layers "F.Cu" "F.Mask" "F.Paste")
			(net "Net_1223")
		)
		(pad "S7" smd rect
			(at -8.255 0.824992 270)
			(size 0.6604 2.0574)
			(layers "F.Cu" "F.Mask" "F.Paste")
			(net "GND")
		)
		(pad "S8" smd rect
			(at -7.480046 -1.949958 270)
			(size 0.508 2.0066)
			(layers "F.Cu" "F.Mask" "F.Paste")
			(net "GND")
		)
		(pad "S9" smd rect
			(at -6.679946 -1.949958 270)
			(size 0.508 2.0066)
			(layers "F.Cu" "F.Mask" "F.Paste")
			(net "Net_1221")
		)
		(pad "S10" smd rect
			(at -5.8801 -1.949958 270)
			(size 0.508 2.0066)
			(layers "F.Cu" "F.Mask" "F.Paste")
			(net "Net_1220")
		)
		(pad "S11" smd rect
			(at -5.08 -1.949958 270)
			(size 0.508 2.0066)
			(layers "F.Cu" "F.Mask" "F.Paste")
			(net "GND")
		)
		(pad "S12" smd rect
			(at -4.2799 -1.949958 270)
			(size 0.508 2.0066)
			(layers "F.Cu" "F.Mask" "F.Paste")
			(net "Net_1219")
		)
		(pad "S13" smd rect
			(at -3.480054 -1.949958 270)
			(size 0.508 2.0066)
			(layers "F.Cu" "F.Mask" "F.Paste")
			(net "Net_1214")
		)
		(pad "S14" smd rect
			(at -2.679954 -1.949958 270)
			(size 0.508 2.0066)
			(layers "F.Cu" "F.Mask" "F.Paste")
			(net "GND")
		)
		(pad "S15" smd rect
			(at -1.880108 -1.949958 270)
			(size 0.508 2.0066)
			(layers "F.Cu" "F.Mask" "F.Paste")
			(net "Net_1213")
		)
		(pad "S16" smd rect
			(at -1.080008 -1.949958 270)
			(size 0.508 2.0066)
			(layers "F.Cu" "F.Mask" "F.Paste")
			(net "GND")
		)
		(pad "S17" smd rect
			(at -0.279908 -1.949958 270)
			(size 0.508 2.0066)
			(layers "F.Cu" "F.Mask" "F.Paste")
			(net "PE_TX2_DR14_N")
		)
		(pad "S18" smd rect
			(at 0.519938 -1.949958 270)
			(size 0.508 2.0066)
			(layers "F.Cu" "F.Mask" "F.Paste")
			(net "PE_TX2_DR14_P")
		)
		(pad "S19" smd rect
			(at 1.320038 -1.949958 270)
			(size 0.508 2.0066)
			(layers "F.Cu" "F.Mask" "F.Paste")
			(net "GND")
		)
		(pad "S20" smd rect
			(at 2.119884 -1.949958 270)
			(size 0.508 2.0066)
			(layers "F.Cu" "F.Mask" "F.Paste")
			(net "PE_RX2_DR14_N")
		)
		(pad "S21" smd rect
			(at 2.919984 -1.949958 270)
			(size 0.508 2.0066)
			(layers "F.Cu" "F.Mask" "F.Paste")
			(net "PE_RX2_DR14_P")
		)
		(pad "S22" smd rect
			(at 3.720084 -1.949958 270)
			(size 0.508 2.0066)
			(layers "F.Cu" "F.Mask" "F.Paste")
			(net "GND")
		)
		(pad "S23" smd rect
			(at 4.51993 -1.949958 270)
			(size 0.508 2.0066)
			(layers "F.Cu" "F.Mask" "F.Paste")
			(net "PE_TX3_DR14_N")
		)
		(pad "S24" smd rect
			(at 5.32003 -1.949958 270)
			(size 0.508 2.0066)
			(layers "F.Cu" "F.Mask" "F.Paste")
			(net "PE_TX3_DR14_P")
		)
		(pad "S25" smd rect
			(at 6.119876 -1.949958 270)
			(size 0.508 2.0066)
			(layers "F.Cu" "F.Mask" "F.Paste")
			(net "GND")
		)
		(pad "S26" smd rect
			(at 6.919976 -1.949958 270)
			(size 0.508 2.0066)
			(layers "F.Cu" "F.Mask" "F.Paste")
			(net "PE_RX3_DR14_N")
		)
		(pad "S27" smd rect
			(at 7.720076 -1.949958 270)
			(size 0.508 2.0066)
			(layers "F.Cu" "F.Mask" "F.Paste")
			(net "PE_RX3_DR14_P")
		)
		(pad "S28" smd rect
			(at 8.519922 -1.949958 270)
			(size 0.508 2.0066)
			(layers "F.Cu" "F.Mask" "F.Paste")
			(net "GND")
		)
		(zone
			(layers "F.Cu" "B.Cu" "In1.Cu" "In2.Cu" "In3.Cu" "In4.Cu" "In5.Cu" "In6.Cu")
			(hatch none 0.5)
			(connect_pads
				(clearance 0)
			)
			(min_thickness 0.25)
			(keepout
				(tracks not_allowed)
				(vias allowed)
				(pads allowed)
				(copperpour not_allowed)
				(footprints allowed)
			)
			(placement
				(enabled no)
				(sheetname "")
			)
			(fill
				(thermal_gap 0.5)
				(thermal_bridge_width 0.5)
				(island_removal_mode 0)
			)
			(polygon
				(pts
					(arc
						(start 22.081998 -45.329856)
						(mid 19.618198 -45.329856)
						(end 22.081998 -45.329856)
					)
				)
			)
		)
		(zone
			(layers "F.Cu" "B.Cu" "In1.Cu" "In2.Cu" "In3.Cu" "In4.Cu" "In5.Cu" "In6.Cu")
			(hatch none 0.5)
			(connect_pads
				(clearance 0)
			)
			(min_thickness 0.25)
			(keepout
				(tracks not_allowed)
				(vias allowed)
				(pads allowed)
				(copperpour not_allowed)
				(footprints allowed)
			)
			(placement
				(enabled no)
				(sheetname "")
			)
			(fill
				(thermal_gap 0.5)
				(thermal_bridge_width 0.5)
				(island_removal_mode 0)
			)
			(polygon
				(pts
					(arc
						(start 22.081998 -7.329932)
						(mid 19.618198 -7.329932)
						(end 22.081998 -7.329932)
					)
				)
			)
		)
	)
	(footprint ""
		(layer "F.Cu")
		(at 214.757 -294.894 -90)
		(property "Reference" "U11"
			(at 0 0 270)
			(layer "F.SilkS")
			(hide yes)
			(effects
				(font
					(size 1.27 1.27)
				)
			)
		)
		(property "Value" "P2003EVG-GP"
			(at 0 -11.1252 270)
			(unlocked yes)
			(layer "F.Fab")
			(hide yes)
			(effects
				(font
					(size 1.016 1.016)
					(thickness 0.1524)
				)
			)
		)
		(property "Device Type" "SOIC8H79"
			(at 0 -12.6492 270)
			(unlocked yes)
			(layer "F.Fab")
			(hide yes)
			(effects
				(font
					(size 1.016 1.016)
					(thickness 0.1524)
				)
			)
		)
		(duplicate_pad_numbers_are_jumpers no)
		(fp_line
			(start -2.6162 3.429)
			(end -2.6162 1.4732)
			(stroke
				(width 0.4064)
				(type default)
			)
			(layer "F.SilkS")
		)
		(fp_line
			(start -2.7432 1.4224)
			(end 2.1336 1.4224)
			(stroke
				(width 0.1524)
				(type default)
			)
			(layer "F.SilkS")
		)
		(fp_line
			(start 2.1336 1.4224)
			(end 2.1336 -1.4224)
			(stroke
				(width 0.1524)
				(type default)
			)
			(layer "F.SilkS")
		)
		(fp_line
			(start -2.2352 0)
			(end -2.7432 0.508)
			(stroke
				(width 0.1524)
				(type default)
			)
			(layer "F.SilkS")
		)
		(fp_line
			(start -2.7432 -0.508)
			(end -2.2352 0)
			(stroke
				(width 0.1524)
				(type default)
			)
			(layer "F.SilkS")
		)
		(fp_line
			(start -2.7432 -1.4224)
			(end -2.7432 1.4224)
			(stroke
				(width 0.1524)
				(type default)
			)
			(layer "F.SilkS")
		)
		(fp_line
			(start 2.1336 -1.4224)
			(end -2.7432 -1.4224)
			(stroke
				(width 0.1524)
				(type default)
			)
			(layer "F.SilkS")
		)
		(fp_poly
			(pts
				(xy 2.2098 -1.4224) (xy 2.2098 1.4224) (xy -2.2225 1.4224) (xy -2.2225 -1.4224)
			)
			(stroke
				(width 0)
				(type default)
			)
			(fill yes)
			(layer "F.SilkS")
		)
		(fp_rect
			(start -2.4511 2.9972)
			(end 2.4511 -2.9972)
			(stroke
				(width 0)
				(type default)
			)
			(fill no)
			(layer "F.CrtYd")
		)
		(fp_poly
			(pts
				(xy -2.8194 3.6322) (xy -2.8194 -3.6322) (xy 2.8194 -3.6322) (xy 2.8194 -2.2987) (xy 2.4511 -2.2987)
				(xy 2.4511 -2.9972) (xy -2.4511 -2.9972) (xy -2.4511 2.9972) (xy 2.4511 2.9972) (xy 2.4511 -2.286)
				(xy 2.8194 -2.286) (xy 2.8194 3.6322)
			)
			(stroke
				(width 0)
				(type default)
			)
			(fill no)
			(layer "F.CrtYd")
		)
		(fp_rect
			(start -2.8194 3.6322)
			(end 2.8194 -3.6322)
			(stroke
				(width 0)
				(type default)
			)
			(fill no)
			(layer "F.Fab")
		)
		(pad "1" smd rect
			(at -1.905 2.54 270)
			(size 0.635 1.651)
			(layers "F.Cu" "F.Mask" "F.Paste")
			(net "P12V")
		)
		(pad "2" smd rect
			(at -0.635 2.54 270)
			(size 0.635 1.651)
			(layers "F.Cu" "F.Mask" "F.Paste")
			(net "P12V")
		)
		(pad "3" smd rect
			(at 0.635 2.54 270)
			(size 0.635 1.651)
			(layers "F.Cu" "F.Mask" "F.Paste")
			(net "P12V")
		)
		(pad "4" smd rect
			(at 1.905 2.54 270)
			(size 0.635 1.651)
			(layers "F.Cu" "F.Mask" "F.Paste")
			(net "SW_SSD2_N")
		)
		(pad "5" smd rect
			(at 1.905 -2.54 270)
			(size 0.635 1.651)
			(layers "F.Cu" "F.Mask" "F.Paste")
			(net "P12V_SSD2")
		)
		(pad "6" smd rect
			(at 0.635 -2.54 270)
			(size 0.635 1.651)
			(layers "F.Cu" "F.Mask" "F.Paste")
			(net "P12V_SSD2")
		)
		(pad "7" smd rect
			(at -0.635 -2.54 270)
			(size 0.635 1.651)
			(layers "F.Cu" "F.Mask" "F.Paste")
			(net "P12V_SSD2")
		)
		(pad "8" smd rect
			(at -1.905 -2.54 270)
			(size 0.635 1.651)
			(layers "F.Cu" "F.Mask" "F.Paste")
			(net "P12V_SSD2")
		)
	)
	(footprint ""
		(layer "F.Cu")
		(at 78.105 -354.076 180)
		(property "Reference" "SR1154"
			(at 0 0 180)
			(layer "F.SilkS")
			(hide yes)
			(effects
				(font
					(size 1.27 1.27)
				)
			)
		)
		(property "Value" "4K7R2F-GP"
			(at 0.064008 -3.993896 180)
			(unlocked yes)
			(layer "F.Fab")
			(hide yes)
			(effects
				(font
					(size 1.016 1.016)
					(thickness 0.1524)
				)
			)
		)
		(property "Device Type" "R402H16"
			(at 0.064008 -5.517896 180)
			(unlocked yes)
			(layer "F.Fab")
			(hide yes)
			(effects
				(font
					(size 1.016 1.016)
					(thickness 0.1524)
				)
			)
		)
		(duplicate_pad_numbers_are_jumpers no)
		(fp_line
			(start 0.508 -0.9398)
			(end -0.508 -0.9398)
			(stroke
				(width 0.1524)
				(type default)
			)
			(layer "F.SilkS")
		)
		(fp_line
			(start -0.508 -0.9398)
			(end -0.508 0.9398)
			(stroke
				(width 0.1524)
				(type default)
			)
			(layer "F.SilkS")
		)
		(fp_rect
			(start -0.508 0.9398)
			(end 0.508 -0.9398)
			(stroke
				(width 0)
				(type default)
			)
			(fill no)
			(layer "F.CrtYd")
		)
		(fp_rect
			(start -0.508 0.9398)
			(end 0.508 -0.9398)
			(stroke
				(width 0)
				(type default)
			)
			(fill no)
			(layer "F.Fab")
		)
		(pad "1" smd custom
			(at 0 -0.4445 180)
			(size 0.1397 0.1397)
			(layers "F.Cu" "F.Mask" "F.Paste")
			(net "P3V3")
			(options
				(clearance outline)
				(anchor circle)
			)
			(primitives
				(gr_poly
					(pts
						(arc
							(start -0.1778 -0.2794)
							(mid -0.249642 -0.249642)
							(end -0.2794 -0.1778)
						)
						(arc
							(start -0.2794 0.1778)
							(mid -0.249642 0.249642)
							(end -0.1778 0.2794)
						)
						(arc
							(start 0.1778 0.2794)
							(mid 0.249642 0.249642)
							(end 0.2794 0.1778)
						)
						(arc
							(start 0.2794 -0.1778)
							(mid 0.249642 -0.249642)
							(end 0.1778 -0.2794)
						)
					)
					(width 0)
					(fill yes)
				)
			)
		)
		(pad "2" smd custom
			(at 0 0.4445 180)
			(size 0.1397 0.1397)
			(layers "F.Cu" "F.Mask" "F.Paste")
			(net "I2C_SW_EU17_ADDRESS_A0")
			(options
				(clearance outline)
				(anchor circle)
			)
			(primitives
				(gr_poly
					(pts
						(arc
							(start -0.1778 -0.2794)
							(mid -0.249642 -0.249642)
							(end -0.2794 -0.1778)
						)
						(arc
							(start -0.2794 0.1778)
							(mid -0.249642 0.249642)
							(end -0.1778 0.2794)
						)
						(arc
							(start 0.1778 0.2794)
							(mid 0.249642 0.249642)
							(end 0.2794 0.1778)
						)
						(arc
							(start 0.2794 -0.1778)
							(mid 0.249642 -0.249642)
							(end 0.1778 -0.2794)
						)
					)
					(width 0)
					(fill yes)
				)
			)
		)
	)
	(footprint ""
		(layer "F.Cu")
		(at 18.50009 -258.899914)
		(property "Reference" "LED12"
			(at 0 0 0)
			(layer "F.SilkS")
			(hide yes)
			(effects
				(font
					(size 1.27 1.27)
				)
			)
		)
		(property "Value" "LED-RB-4-GP"
			(at 5.88899 1.80848 0)
			(unlocked yes)
			(layer "F.Fab")
			(hide yes)
			(effects
				(font
					(size 1.016 1.016)
					(thickness 0.1524)
				)
			)
		)
		(property "Device Type" "LED1613-4PH20"
			(at 5.88899 0.28448 0)
			(unlocked yes)
			(layer "F.Fab")
			(hide yes)
			(effects
				(font
					(size 1.016 1.016)
					(thickness 0.1524)
				)
			)
		)
		(duplicate_pad_numbers_are_jumpers no)
		(fp_line
			(start -1.4478 -0.9652)
			(end 1.4478 -0.9652)
			(stroke
				(width 0.1524)
				(type default)
			)
			(layer "F.SilkS")
		)
		(fp_line
			(start -1.4478 0.9652)
			(end -1.4478 -0.9652)
			(stroke
				(width 0.1524)
				(type default)
			)
			(layer "F.SilkS")
		)
		(fp_line
			(start -1.4478 0.9652)
			(end -1.4478 -0.9652)
			(stroke
				(width 0.508)
				(type default)
			)
			(layer "F.SilkS")
		)
		(fp_line
			(start 1.4478 -0.9652)
			(end 1.4478 0.9652)
			(stroke
				(width 0.1524)
				(type default)
			)
			(layer "F.SilkS")
		)
		(fp_line
			(start 1.4478 0.9652)
			(end -1.4478 0.9652)
			(stroke
				(width 0.1524)
				(type default)
			)
			(layer "F.SilkS")
		)
		(fp_rect
			(start -0.8001 0.6477)
			(end 0.8001 -0.6477)
			(stroke
				(width 0)
				(type default)
			)
			(fill no)
			(layer "F.CrtYd")
		)
		(fp_poly
			(pts
				(xy -1.7018 1.2192) (xy -1.7018 -0.06223) (xy -0.8001 -0.06223) (xy -0.8001 0.6477) (xy 0.8001 0.6477)
				(xy 0.8001 -0.6477) (xy -0.8001 -0.6477) (xy -0.8001 -0.0635) (xy -1.7018 -0.0635) (xy -1.7018 -1.2192)
				(xy 1.7018 -1.2192) (xy 1.7018 1.2192)
			)
			(stroke
				(width 0)
				(type default)
			)
			(fill no)
			(layer "F.CrtYd")
		)
		(fp_rect
			(start -1.7018 1.2192)
			(end 1.7018 -1.2192)
			(stroke
				(width 0)
				(type default)
			)
			(fill no)
			(layer "F.Fab")
		)
		(pad "1" smd rect
			(at -0.73025 0.4064)
			(size 0.9144 0.6096)
			(layers "F.Cu" "F.Mask" "F.Paste")
			(net "SSD_ACT_DR12_MOS_N")
		)
		(pad "2" smd rect
			(at -0.73025 -0.4064)
			(size 0.9144 0.6096)
			(layers "F.Cu" "F.Mask" "F.Paste")
			(net "ATTN_LED_DR12_MOS_N")
		)
		(pad "3" smd rect
			(at 0.73025 -0.4064)
			(size 0.9144 0.6096)
			(layers "F.Cu" "F.Mask" "F.Paste")
			(net "DRV_ATTN_12")
		)
		(pad "4" smd rect
			(at 0.73025 0.4064)
			(size 0.9144 0.6096)
			(layers "F.Cu" "F.Mask" "F.Paste")
			(net "DRV_ACT_12")
		)
	)
	(footprint ""
		(layer "F.Cu")
		(at 102.616 -434.34 90)
		(property "Reference" "R9058"
			(at 0 0 90)
			(layer "F.SilkS")
			(hide yes)
			(effects
				(font
					(size 1.27 1.27)
				)
			)
		)
		(property "Value" "27R2F-GP"
			(at 0.064008 -3.993896 90)
			(unlocked yes)
			(layer "F.Fab")
			(hide yes)
			(effects
				(font
					(size 1.016 1.016)
					(thickness 0.1524)
				)
			)
		)
		(property "Device Type" "R402H16"
			(at 0.064008 -5.517896 90)
			(unlocked yes)
			(layer "F.Fab")
			(hide yes)
			(effects
				(font
					(size 1.016 1.016)
					(thickness 0.1524)
				)
			)
		)
		(duplicate_pad_numbers_are_jumpers no)
		(fp_line
			(start 0.508 -0.9398)
			(end -0.508 -0.9398)
			(stroke
				(width 0.1524)
				(type default)
			)
			(layer "F.SilkS")
		)
		(fp_line
			(start -0.508 -0.9398)
			(end -0.508 0.9398)
			(stroke
				(width 0.1524)
				(type default)
			)
			(layer "F.SilkS")
		)
		(fp_rect
			(start -0.508 0.9398)
			(end 0.508 -0.9398)
			(stroke
				(width 0)
				(type default)
			)
			(fill no)
			(layer "F.CrtYd")
		)
		(fp_rect
			(start -0.508 0.9398)
			(end 0.508 -0.9398)
			(stroke
				(width 0)
				(type default)
			)
			(fill no)
			(layer "F.Fab")
		)
		(pad "1" smd custom
			(at 0 -0.4445 90)
			(size 0.1397 0.1397)
			(layers "F.Cu" "F.Mask" "F.Paste")
			(net "PE_CLK_100M_DR0_2_R_N")
			(options
				(clearance outline)
				(anchor circle)
			)
			(primitives
				(gr_poly
					(pts
						(arc
							(start -0.1778 -0.2794)
							(mid -0.249642 -0.249642)
							(end -0.2794 -0.1778)
						)
						(arc
							(start -0.2794 0.1778)
							(mid -0.249642 0.249642)
							(end -0.1778 0.2794)
						)
						(arc
							(start 0.1778 0.2794)
							(mid 0.249642 0.249642)
							(end 0.2794 0.1778)
						)
						(arc
							(start 0.2794 -0.1778)
							(mid 0.249642 -0.249642)
							(end 0.1778 -0.2794)
						)
					)
					(width 0)
					(fill yes)
				)
			)
		)
		(pad "2" smd custom
			(at 0 0.4445 90)
			(size 0.1397 0.1397)
			(layers "F.Cu" "F.Mask" "F.Paste")
			(net "PE_CLK100M_DR0_2_N")
			(options
				(clearance outline)
				(anchor circle)
			)
			(primitives
				(gr_poly
					(pts
						(arc
							(start -0.1778 -0.2794)
							(mid -0.249642 -0.249642)
							(end -0.2794 -0.1778)
						)
						(arc
							(start -0.2794 0.1778)
							(mid -0.249642 0.249642)
							(end -0.1778 0.2794)
						)
						(arc
							(start 0.1778 0.2794)
							(mid 0.249642 0.249642)
							(end 0.2794 0.1778)
						)
						(arc
							(start 0.2794 -0.1778)
							(mid 0.249642 -0.249642)
							(end 0.1778 -0.2794)
						)
					)
					(width 0)
					(fill yes)
				)
			)
		)
	)
	(footprint ""
		(layer "F.Cu")
		(at 49.276 -40.132 -90)
		(property "Reference" "R9901"
			(at 0 0 270)
			(layer "F.SilkS")
			(hide yes)
			(effects
				(font
					(size 1.27 1.27)
				)
			)
		)
		(property "Value" "1K82R2F-1-GP"
			(at 0.064008 -3.993896 270)
			(unlocked yes)
			(layer "F.Fab")
			(hide yes)
			(effects
				(font
					(size 1.016 1.016)
					(thickness 0.1524)
				)
			)
		)
		(property "Device Type" "R402H16"
			(at 0.064008 -5.517896 270)
			(unlocked yes)
			(layer "F.Fab")
			(hide yes)
			(effects
				(font
					(size 1.016 1.016)
					(thickness 0.1524)
				)
			)
		)
		(duplicate_pad_numbers_are_jumpers no)
		(fp_line
			(start -0.508 -0.9398)
			(end -0.508 0.9398)
			(stroke
				(width 0.1524)
				(type default)
			)
			(layer "F.SilkS")
		)
		(fp_line
			(start 0.508 -0.9398)
			(end -0.508 -0.9398)
			(stroke
				(width 0.1524)
				(type default)
			)
			(layer "F.SilkS")
		)
		(fp_rect
			(start -0.508 0.9398)
			(end 0.508 -0.9398)
			(stroke
				(width 0)
				(type default)
			)
			(fill no)
			(layer "F.CrtYd")
		)
		(fp_rect
			(start -0.508 0.9398)
			(end 0.508 -0.9398)
			(stroke
				(width 0)
				(type default)
			)
			(fill no)
			(layer "F.Fab")
		)
		(pad "1" smd custom
			(at 0 -0.4445 270)
			(size 0.1397 0.1397)
			(layers "F.Cu" "F.Mask" "F.Paste")
			(net "P12V")
			(options
				(clearance outline)
				(anchor circle)
			)
			(primitives
				(gr_poly
					(pts
						(arc
							(start -0.1778 -0.2794)
							(mid -0.249642 -0.249642)
							(end -0.2794 -0.1778)
						)
						(arc
							(start -0.2794 0.1778)
							(mid -0.249642 0.249642)
							(end -0.1778 0.2794)
						)
						(arc
							(start 0.1778 0.2794)
							(mid 0.249642 0.249642)
							(end 0.2794 0.1778)
						)
						(arc
							(start 0.2794 -0.1778)
							(mid 0.249642 -0.249642)
							(end 0.1778 -0.2794)
						)
					)
					(width 0)
					(fill yes)
				)
			)
		)
		(pad "2" smd custom
			(at 0 0.4445 270)
			(size 0.1397 0.1397)
			(layers "F.Cu" "F.Mask" "F.Paste")
			(net "DRV_ACT_9")
			(options
				(clearance outline)
				(anchor circle)
			)
			(primitives
				(gr_poly
					(pts
						(arc
							(start -0.1778 -0.2794)
							(mid -0.249642 -0.249642)
							(end -0.2794 -0.1778)
						)
						(arc
							(start -0.2794 0.1778)
							(mid -0.249642 0.249642)
							(end -0.1778 0.2794)
						)
						(arc
							(start 0.1778 0.2794)
							(mid 0.249642 0.249642)
							(end 0.2794 0.1778)
						)
						(arc
							(start 0.2794 -0.1778)
							(mid 0.249642 -0.249642)
							(end 0.1778 -0.2794)
						)
					)
					(width 0)
					(fill yes)
				)
			)
		)
	)
	(footprint ""
		(layer "F.Cu")
		(at 209.296 -293.116 180)
		(property "Reference" "R568"
			(at 0 0 180)
			(layer "F.SilkS")
			(hide yes)
			(effects
				(font
					(size 1.27 1.27)
				)
			)
		)
		(property "Value" "300KR2F-GP"
			(at 0.064008 -3.993896 180)
			(unlocked yes)
			(layer "F.Fab")
			(hide yes)
			(effects
				(font
					(size 1.016 1.016)
					(thickness 0.1524)
				)
			)
		)
		(property "Device Type" "R402H16"
			(at 0.064008 -5.517896 180)
			(unlocked yes)
			(layer "F.Fab")
			(hide yes)
			(effects
				(font
					(size 1.016 1.016)
					(thickness 0.1524)
				)
			)
		)
		(duplicate_pad_numbers_are_jumpers no)
		(fp_line
			(start 0.508 -0.9398)
			(end -0.508 -0.9398)
			(stroke
				(width 0.1524)
				(type default)
			)
			(layer "F.SilkS")
		)
		(fp_line
			(start -0.508 -0.9398)
			(end -0.508 0.9398)
			(stroke
				(width 0.1524)
				(type default)
			)
			(layer "F.SilkS")
		)
		(fp_rect
			(start -0.508 0.9398)
			(end 0.508 -0.9398)
			(stroke
				(width 0)
				(type default)
			)
			(fill no)
			(layer "F.CrtYd")
		)
		(fp_rect
			(start -0.508 0.9398)
			(end 0.508 -0.9398)
			(stroke
				(width 0)
				(type default)
			)
			(fill no)
			(layer "F.Fab")
		)
		(pad "1" smd custom
			(at 0 -0.4445 180)
			(size 0.1397 0.1397)
			(layers "F.Cu" "F.Mask" "F.Paste")
			(net "SW_SSD2_N")
			(options
				(clearance outline)
				(anchor circle)
			)
			(primitives
				(gr_poly
					(pts
						(arc
							(start -0.1778 -0.2794)
							(mid -0.249642 -0.249642)
							(end -0.2794 -0.1778)
						)
						(arc
							(start -0.2794 0.1778)
							(mid -0.249642 0.249642)
							(end -0.1778 0.2794)
						)
						(arc
							(start 0.1778 0.2794)
							(mid 0.249642 0.249642)
							(end 0.2794 0.1778)
						)
						(arc
							(start 0.2794 -0.1778)
							(mid 0.249642 -0.249642)
							(end 0.1778 -0.2794)
						)
					)
					(width 0)
					(fill yes)
				)
			)
		)
		(pad "2" smd custom
			(at 0 0.4445 180)
			(size 0.1397 0.1397)
			(layers "F.Cu" "F.Mask" "F.Paste")
			(net "P12V")
			(options
				(clearance outline)
				(anchor circle)
			)
			(primitives
				(gr_poly
					(pts
						(arc
							(start -0.1778 -0.2794)
							(mid -0.249642 -0.249642)
							(end -0.2794 -0.1778)
						)
						(arc
							(start -0.2794 0.1778)
							(mid -0.249642 0.249642)
							(end -0.1778 0.2794)
						)
						(arc
							(start 0.1778 0.2794)
							(mid 0.249642 0.249642)
							(end 0.2794 0.1778)
						)
						(arc
							(start 0.2794 -0.1778)
							(mid 0.249642 -0.249642)
							(end 0.1778 -0.2794)
						)
					)
					(width 0)
					(fill yes)
				)
			)
		)
	)
	(footprint ""
		(layer "F.Cu")
		(at 99.06 -204.851 90)
		(property "Reference" "C8863"
			(at 0 0 90)
			(layer "F.SilkS")
			(hide yes)
			(effects
				(font
					(size 1.27 1.27)
				)
			)
		)
		(property "Value" "SCD1U16V2KX-3GP"
			(at 1.1811 -2.7051 90)
			(unlocked yes)
			(layer "F.Fab")
			(hide yes)
			(effects
				(font
					(size 1.016 1.016)
					(thickness 0.1524)
				)
			)
		)
		(property "Device Type" "C402H22"
			(at 1.1811 -4.2291 90)
			(unlocked yes)
			(layer "F.Fab")
			(hide yes)
			(effects
				(font
					(size 1.016 1.016)
					(thickness 0.1524)
				)
			)
		)
		(duplicate_pad_numbers_are_jumpers no)
		(fp_rect
			(start -0.4318 0.9525)
			(end 0.4318 -0.9525)
			(stroke
				(width 0)
				(type default)
			)
			(fill no)
			(layer "F.CrtYd")
		)
		(fp_rect
			(start -0.4318 0.9525)
			(end 0.4318 -0.9525)
			(stroke
				(width 0)
				(type default)
			)
			(fill no)
			(layer "F.Fab")
		)
		(pad "1" smd custom
			(at 0 -0.4445 90)
			(size 0.1524 0.1524)
			(layers "F.Cu" "F.Mask" "F.Paste")
			(net "VDD_IO_3")
			(options
				(clearance outline)
				(anchor circle)
			)
			(primitives
				(gr_poly
					(pts
						(arc
							(start 0.3048 -0.2032)
							(mid 0.275042 -0.275042)
							(end 0.2032 -0.3048)
						)
						(arc
							(start -0.2032 -0.3048)
							(mid -0.275042 -0.275042)
							(end -0.3048 -0.2032)
						)
						(arc
							(start -0.3048 0.2032)
							(mid -0.275042 0.275042)
							(end -0.2032 0.3048)
						)
						(arc
							(start 0.2032 0.3048)
							(mid 0.275042 0.275042)
							(end 0.3048 0.2032)
						)
					)
					(width 0)
					(fill yes)
				)
			)
		)
		(pad "2" smd custom
			(at 0 0.4445 90)
			(size 0.1524 0.1524)
			(layers "F.Cu" "F.Mask" "F.Paste")
			(net "GND")
			(options
				(clearance outline)
				(anchor circle)
			)
			(primitives
				(gr_poly
					(pts
						(arc
							(start 0.3048 -0.2032)
							(mid 0.275042 -0.275042)
							(end 0.2032 -0.3048)
						)
						(arc
							(start -0.2032 -0.3048)
							(mid -0.275042 -0.275042)
							(end -0.3048 -0.2032)
						)
						(arc
							(start -0.3048 0.2032)
							(mid -0.275042 0.275042)
							(end -0.2032 0.3048)
						)
						(arc
							(start 0.2032 0.3048)
							(mid 0.275042 0.275042)
							(end 0.3048 0.2032)
						)
					)
					(width 0)
					(fill yes)
				)
			)
		)
	)
	(footprint ""
		(layer "F.Cu")
		(at 96.52 -219.456 180)
		(property "Reference" "R9094"
			(at 0 0 180)
			(layer "F.SilkS")
			(hide yes)
			(effects
				(font
					(size 1.27 1.27)
				)
			)
		)
		(property "Value" "27R2F-GP"
			(at 0.064008 -3.993896 180)
			(unlocked yes)
			(layer "F.Fab")
			(hide yes)
			(effects
				(font
					(size 1.016 1.016)
					(thickness 0.1524)
				)
			)
		)
		(property "Device Type" "R402H16"
			(at 0.064008 -5.517896 180)
			(unlocked yes)
			(layer "F.Fab")
			(hide yes)
			(effects
				(font
					(size 1.016 1.016)
					(thickness 0.1524)
				)
			)
		)
		(duplicate_pad_numbers_are_jumpers no)
		(fp_line
			(start 0.508 -0.9398)
			(end -0.508 -0.9398)
			(stroke
				(width 0.1524)
				(type default)
			)
			(layer "F.SilkS")
		)
		(fp_line
			(start -0.508 -0.9398)
			(end -0.508 0.9398)
			(stroke
				(width 0.1524)
				(type default)
			)
			(layer "F.SilkS")
		)
		(fp_rect
			(start -0.508 0.9398)
			(end 0.508 -0.9398)
			(stroke
				(width 0)
				(type default)
			)
			(fill no)
			(layer "F.CrtYd")
		)
		(fp_rect
			(start -0.508 0.9398)
			(end 0.508 -0.9398)
			(stroke
				(width 0)
				(type default)
			)
			(fill no)
			(layer "F.Fab")
		)
		(pad "1" smd custom
			(at 0 -0.4445 180)
			(size 0.1397 0.1397)
			(layers "F.Cu" "F.Mask" "F.Paste")
			(net "PE_CLK_100M_DR7_1_R_P")
			(options
				(clearance outline)
				(anchor circle)
			)
			(primitives
				(gr_poly
					(pts
						(arc
							(start -0.1778 -0.2794)
							(mid -0.249642 -0.249642)
							(end -0.2794 -0.1778)
						)
						(arc
							(start -0.2794 0.1778)
							(mid -0.249642 0.249642)
							(end -0.1778 0.2794)
						)
						(arc
							(start 0.1778 0.2794)
							(mid 0.249642 0.249642)
							(end 0.2794 0.1778)
						)
						(arc
							(start 0.2794 -0.1778)
							(mid 0.249642 -0.249642)
							(end 0.1778 -0.2794)
						)
					)
					(width 0)
					(fill yes)
				)
			)
		)
		(pad "2" smd custom
			(at 0 0.4445 180)
			(size 0.1397 0.1397)
			(layers "F.Cu" "F.Mask" "F.Paste")
			(net "PE_CLK100M_DR7_1_P")
			(options
				(clearance outline)
				(anchor circle)
			)
			(primitives
				(gr_poly
					(pts
						(arc
							(start -0.1778 -0.2794)
							(mid -0.249642 -0.249642)
							(end -0.2794 -0.1778)
						)
						(arc
							(start -0.2794 0.1778)
							(mid -0.249642 0.249642)
							(end -0.1778 0.2794)
						)
						(arc
							(start 0.1778 0.2794)
							(mid 0.249642 0.249642)
							(end 0.2794 0.1778)
						)
						(arc
							(start 0.2794 -0.1778)
							(mid 0.249642 -0.249642)
							(end 0.1778 -0.2794)
						)
					)
					(width 0)
					(fill yes)
				)
			)
		)
	)
	(footprint ""
		(layer "F.Cu")
		(at 242.062 -423.799 90)
		(property "Reference" "PR9060"
			(at 0 0 90)
			(layer "F.SilkS")
			(hide yes)
			(effects
				(font
					(size 1.27 1.27)
				)
			)
		)
		(property "Value" "0R2J-2-GP"
			(at 0.064008 -3.993896 90)
			(unlocked yes)
			(layer "F.Fab")
			(hide yes)
			(effects
				(font
					(size 1.016 1.016)
					(thickness 0.1524)
				)
			)
		)
		(property "Device Type" "R402H16"
			(at 0.064008 -5.517896 90)
			(unlocked yes)
			(layer "F.Fab")
			(hide yes)
			(effects
				(font
					(size 1.016 1.016)
					(thickness 0.1524)
				)
			)
		)
		(duplicate_pad_numbers_are_jumpers no)
		(fp_line
			(start 0.508 -0.9398)
			(end -0.508 -0.9398)
			(stroke
				(width 0.1524)
				(type default)
			)
			(layer "F.SilkS")
		)
		(fp_line
			(start -0.508 -0.9398)
			(end -0.508 0.9398)
			(stroke
				(width 0.1524)
				(type default)
			)
			(layer "F.SilkS")
		)
		(fp_rect
			(start -0.508 0.9398)
			(end 0.508 -0.9398)
			(stroke
				(width 0)
				(type default)
			)
			(fill no)
			(layer "F.CrtYd")
		)
		(fp_rect
			(start -0.508 0.9398)
			(end 0.508 -0.9398)
			(stroke
				(width 0)
				(type default)
			)
			(fill no)
			(layer "F.Fab")
		)
		(pad "1" smd custom
			(at 0 -0.4445 90)
			(size 0.1397 0.1397)
			(layers "F.Cu" "F.Mask" "F.Paste")
			(net "SAS_I2C_C_BUF_SCL_R")
			(options
				(clearance outline)
				(anchor circle)
			)
			(primitives
				(gr_poly
					(pts
						(arc
							(start -0.1778 -0.2794)
							(mid -0.249642 -0.249642)
							(end -0.2794 -0.1778)
						)
						(arc
							(start -0.2794 0.1778)
							(mid -0.249642 0.249642)
							(end -0.1778 0.2794)
						)
						(arc
							(start 0.1778 0.2794)
							(mid 0.249642 0.249642)
							(end 0.2794 0.1778)
						)
						(arc
							(start 0.2794 -0.1778)
							(mid 0.249642 -0.249642)
							(end 0.1778 -0.2794)
						)
					)
					(width 0)
					(fill yes)
				)
			)
		)
		(pad "2" smd custom
			(at 0 0.4445 90)
			(size 0.1397 0.1397)
			(layers "F.Cu" "F.Mask" "F.Paste")
			(net "I2C_C_SCL")
			(options
				(clearance outline)
				(anchor circle)
			)
			(primitives
				(gr_poly
					(pts
						(arc
							(start -0.1778 -0.2794)
							(mid -0.249642 -0.249642)
							(end -0.2794 -0.1778)
						)
						(arc
							(start -0.2794 0.1778)
							(mid -0.249642 0.249642)
							(end -0.1778 0.2794)
						)
						(arc
							(start 0.1778 0.2794)
							(mid 0.249642 0.249642)
							(end 0.2794 0.1778)
						)
						(arc
							(start 0.2794 -0.1778)
							(mid 0.249642 -0.249642)
							(end 0.1778 -0.2794)
						)
					)
					(width 0)
					(fill yes)
				)
			)
		)
	)
	(footprint ""
		(layer "F.Cu")
		(at 87.503 -219.456 180)
		(property "Reference" "R9090"
			(at 0 0 180)
			(layer "F.SilkS")
			(hide yes)
			(effects
				(font
					(size 1.27 1.27)
				)
			)
		)
		(property "Value" "27R2F-GP"
			(at 0.064008 -3.993896 180)
			(unlocked yes)
			(layer "F.Fab")
			(hide yes)
			(effects
				(font
					(size 1.016 1.016)
					(thickness 0.1524)
				)
			)
		)
		(property "Device Type" "R402H16"
			(at 0.064008 -5.517896 180)
			(unlocked yes)
			(layer "F.Fab")
			(hide yes)
			(effects
				(font
					(size 1.016 1.016)
					(thickness 0.1524)
				)
			)
		)
		(duplicate_pad_numbers_are_jumpers no)
		(fp_line
			(start 0.508 -0.9398)
			(end -0.508 -0.9398)
			(stroke
				(width 0.1524)
				(type default)
			)
			(layer "F.SilkS")
		)
		(fp_line
			(start -0.508 -0.9398)
			(end -0.508 0.9398)
			(stroke
				(width 0.1524)
				(type default)
			)
			(layer "F.SilkS")
		)
		(fp_rect
			(start -0.508 0.9398)
			(end 0.508 -0.9398)
			(stroke
				(width 0)
				(type default)
			)
			(fill no)
			(layer "F.CrtYd")
		)
		(fp_rect
			(start -0.508 0.9398)
			(end 0.508 -0.9398)
			(stroke
				(width 0)
				(type default)
			)
			(fill no)
			(layer "F.Fab")
		)
		(pad "1" smd custom
			(at 0 -0.4445 180)
			(size 0.1397 0.1397)
			(layers "F.Cu" "F.Mask" "F.Paste")
			(net "PE_CLK_100M_DR12_1_R_P")
			(options
				(clearance outline)
				(anchor circle)
			)
			(primitives
				(gr_poly
					(pts
						(arc
							(start -0.1778 -0.2794)
							(mid -0.249642 -0.249642)
							(end -0.2794 -0.1778)
						)
						(arc
							(start -0.2794 0.1778)
							(mid -0.249642 0.249642)
							(end -0.1778 0.2794)
						)
						(arc
							(start 0.1778 0.2794)
							(mid 0.249642 0.249642)
							(end 0.2794 0.1778)
						)
						(arc
							(start 0.2794 -0.1778)
							(mid 0.249642 -0.249642)
							(end 0.1778 -0.2794)
						)
					)
					(width 0)
					(fill yes)
				)
			)
		)
		(pad "2" smd custom
			(at 0 0.4445 180)
			(size 0.1397 0.1397)
			(layers "F.Cu" "F.Mask" "F.Paste")
			(net "PE_CLK100M_DR12_1_P")
			(options
				(clearance outline)
				(anchor circle)
			)
			(primitives
				(gr_poly
					(pts
						(arc
							(start -0.1778 -0.2794)
							(mid -0.249642 -0.249642)
							(end -0.2794 -0.1778)
						)
						(arc
							(start -0.2794 0.1778)
							(mid -0.249642 0.249642)
							(end -0.1778 0.2794)
						)
						(arc
							(start 0.1778 0.2794)
							(mid 0.249642 0.249642)
							(end 0.2794 0.1778)
						)
						(arc
							(start 0.2794 -0.1778)
							(mid 0.249642 -0.249642)
							(end 0.1778 -0.2794)
						)
					)
					(width 0)
					(fill yes)
				)
			)
		)
	)
	(footprint ""
		(layer "F.Cu")
		(at 90.17 -115.062)
		(property "Reference" "R9614"
			(at 0 0 0)
			(layer "F.SilkS")
			(hide yes)
			(effects
				(font
					(size 1.27 1.27)
				)
			)
		)
		(property "Value" "10R2F-L-GP"
			(at 0.064008 -3.993896 0)
			(unlocked yes)
			(layer "F.Fab")
			(hide yes)
			(effects
				(font
					(size 1.016 1.016)
					(thickness 0.1524)
				)
			)
		)
		(property "Device Type" "R402H14"
			(at 0.064008 -5.517896 0)
			(unlocked yes)
			(layer "F.Fab")
			(hide yes)
			(effects
				(font
					(size 1.016 1.016)
					(thickness 0.1524)
				)
			)
		)
		(duplicate_pad_numbers_are_jumpers no)
		(fp_line
			(start -0.508 -0.9398)
			(end -0.508 0.9398)
			(stroke
				(width 0.1524)
				(type default)
			)
			(layer "F.SilkS")
		)
		(fp_line
			(start 0.508 -0.9398)
			(end -0.508 -0.9398)
			(stroke
				(width 0.1524)
				(type default)
			)
			(layer "F.SilkS")
		)
		(fp_rect
			(start -0.508 0.9398)
			(end 0.508 -0.9398)
			(stroke
				(width 0)
				(type default)
			)
			(fill no)
			(layer "F.CrtYd")
		)
		(fp_rect
			(start -0.508 0.9398)
			(end 0.508 -0.9398)
			(stroke
				(width 0)
				(type default)
			)
			(fill no)
			(layer "F.Fab")
		)
		(pad "1" smd custom
			(at 0 -0.4445)
			(size 0.1397 0.1397)
			(layers "F.Cu" "F.Mask" "F.Paste")
			(net "SSD_PRSNT_NET13")
			(options
				(clearance outline)
				(anchor circle)
			)
			(primitives
				(gr_poly
					(pts
						(arc
							(start -0.1778 -0.2794)
							(mid -0.249642 -0.249642)
							(end -0.2794 -0.1778)
						)
						(arc
							(start -0.2794 0.1778)
							(mid -0.249642 0.249642)
							(end -0.1778 0.2794)
						)
						(arc
							(start 0.1778 0.2794)
							(mid 0.249642 0.249642)
							(end 0.2794 0.1778)
						)
						(arc
							(start 0.2794 -0.1778)
							(mid 0.249642 -0.249642)
							(end 0.1778 -0.2794)
						)
					)
					(width 0)
					(fill yes)
				)
			)
		)
		(pad "2" smd custom
			(at 0 0.4445)
			(size 0.1397 0.1397)
			(layers "F.Cu" "F.Mask" "F.Paste")
			(net "SSD_PRSNT13")
			(options
				(clearance outline)
				(anchor circle)
			)
			(primitives
				(gr_poly
					(pts
						(arc
							(start -0.1778 -0.2794)
							(mid -0.249642 -0.249642)
							(end -0.2794 -0.1778)
						)
						(arc
							(start -0.2794 0.1778)
							(mid -0.249642 0.249642)
							(end -0.1778 0.2794)
						)
						(arc
							(start 0.1778 0.2794)
							(mid 0.249642 0.249642)
							(end 0.2794 0.1778)
						)
						(arc
							(start 0.2794 -0.1778)
							(mid 0.249642 -0.249642)
							(end 0.1778 -0.2794)
						)
					)
					(width 0)
					(fill yes)
				)
			)
		)
	)
	(footprint ""
		(layer "F.Cu")
		(at 39.2176 -418.8714 180)
		(property "Reference" "R561"
			(at 0 0 180)
			(layer "F.SilkS")
			(hide yes)
			(effects
				(font
					(size 1.27 1.27)
				)
			)
		)
		(property "Value" "200KR2F-L-GP"
			(at 0.064008 -3.993896 180)
			(unlocked yes)
			(layer "F.Fab")
			(hide yes)
			(effects
				(font
					(size 1.016 1.016)
					(thickness 0.1524)
				)
			)
		)
		(property "Device Type" "R402H16"
			(at 0.064008 -5.517896 180)
			(unlocked yes)
			(layer "F.Fab")
			(hide yes)
			(effects
				(font
					(size 1.016 1.016)
					(thickness 0.1524)
				)
			)
		)
		(duplicate_pad_numbers_are_jumpers no)
		(fp_line
			(start 0.508 -0.9398)
			(end -0.508 -0.9398)
			(stroke
				(width 0.1524)
				(type default)
			)
			(layer "F.SilkS")
		)
		(fp_line
			(start -0.508 -0.9398)
			(end -0.508 0.9398)
			(stroke
				(width 0.1524)
				(type default)
			)
			(layer "F.SilkS")
		)
		(fp_rect
			(start -0.508 0.9398)
			(end 0.508 -0.9398)
			(stroke
				(width 0)
				(type default)
			)
			(fill no)
			(layer "F.CrtYd")
		)
		(fp_rect
			(start -0.508 0.9398)
			(end 0.508 -0.9398)
			(stroke
				(width 0)
				(type default)
			)
			(fill no)
			(layer "F.Fab")
		)
		(pad "1" smd custom
			(at 0 -0.4445 180)
			(size 0.1397 0.1397)
			(layers "F.Cu" "F.Mask" "F.Paste")
			(net "SW_SSD10_R")
			(options
				(clearance outline)
				(anchor circle)
			)
			(primitives
				(gr_poly
					(pts
						(arc
							(start -0.1778 -0.2794)
							(mid -0.249642 -0.249642)
							(end -0.2794 -0.1778)
						)
						(arc
							(start -0.2794 0.1778)
							(mid -0.249642 0.249642)
							(end -0.1778 0.2794)
						)
						(arc
							(start 0.1778 0.2794)
							(mid 0.249642 0.249642)
							(end 0.2794 0.1778)
						)
						(arc
							(start 0.2794 -0.1778)
							(mid 0.249642 -0.249642)
							(end 0.1778 -0.2794)
						)
					)
					(width 0)
					(fill yes)
				)
			)
		)
		(pad "2" smd custom
			(at 0 0.4445 180)
			(size 0.1397 0.1397)
			(layers "F.Cu" "F.Mask" "F.Paste")
			(net "SW_SSD10_N")
			(options
				(clearance outline)
				(anchor circle)
			)
			(primitives
				(gr_poly
					(pts
						(arc
							(start -0.1778 -0.2794)
							(mid -0.249642 -0.249642)
							(end -0.2794 -0.1778)
						)
						(arc
							(start -0.2794 0.1778)
							(mid -0.249642 0.249642)
							(end -0.1778 0.2794)
						)
						(arc
							(start 0.1778 0.2794)
							(mid 0.249642 0.249642)
							(end 0.2794 0.1778)
						)
						(arc
							(start 0.2794 -0.1778)
							(mid 0.249642 -0.249642)
							(end 0.1778 -0.2794)
						)
					)
					(width 0)
					(fill yes)
				)
			)
		)
	)
	(footprint ""
		(layer "F.Cu")
		(at 70.231 -435.864 180)
		(property "Reference" "PR9057"
			(at 0 0 180)
			(layer "F.SilkS")
			(hide yes)
			(effects
				(font
					(size 1.27 1.27)
				)
			)
		)
		(property "Value" "0R2J-2-GP"
			(at 0.064008 -3.993896 180)
			(unlocked yes)
			(layer "F.Fab")
			(hide yes)
			(effects
				(font
					(size 1.016 1.016)
					(thickness 0.1524)
				)
			)
		)
		(property "Device Type" "R402H16"
			(at 0.064008 -5.517896 180)
			(unlocked yes)
			(layer "F.Fab")
			(hide yes)
			(effects
				(font
					(size 1.016 1.016)
					(thickness 0.1524)
				)
			)
		)
		(duplicate_pad_numbers_are_jumpers no)
		(fp_line
			(start 0.508 -0.9398)
			(end -0.508 -0.9398)
			(stroke
				(width 0.1524)
				(type default)
			)
			(layer "F.SilkS")
		)
		(fp_line
			(start -0.508 -0.9398)
			(end -0.508 0.9398)
			(stroke
				(width 0.1524)
				(type default)
			)
			(layer "F.SilkS")
		)
		(fp_rect
			(start -0.508 0.9398)
			(end 0.508 -0.9398)
			(stroke
				(width 0)
				(type default)
			)
			(fill no)
			(layer "F.CrtYd")
		)
		(fp_rect
			(start -0.508 0.9398)
			(end 0.508 -0.9398)
			(stroke
				(width 0)
				(type default)
			)
			(fill no)
			(layer "F.Fab")
		)
		(pad "1" smd custom
			(at 0 -0.4445 180)
			(size 0.1397 0.1397)
			(layers "F.Cu" "F.Mask" "F.Paste")
			(net "SAS_I2C_B_BUF_SCL_R")
			(options
				(clearance outline)
				(anchor circle)
			)
			(primitives
				(gr_poly
					(pts
						(arc
							(start -0.1778 -0.2794)
							(mid -0.249642 -0.249642)
							(end -0.2794 -0.1778)
						)
						(arc
							(start -0.2794 0.1778)
							(mid -0.249642 0.249642)
							(end -0.1778 0.2794)
						)
						(arc
							(start 0.1778 0.2794)
							(mid 0.249642 0.249642)
							(end 0.2794 0.1778)
						)
						(arc
							(start 0.2794 -0.1778)
							(mid 0.249642 -0.249642)
							(end 0.1778 -0.2794)
						)
					)
					(width 0)
					(fill yes)
				)
			)
		)
		(pad "2" smd custom
			(at 0 0.4445 180)
			(size 0.1397 0.1397)
			(layers "F.Cu" "F.Mask" "F.Paste")
			(net "I2C_B_SCL")
			(options
				(clearance outline)
				(anchor circle)
			)
			(primitives
				(gr_poly
					(pts
						(arc
							(start -0.1778 -0.2794)
							(mid -0.249642 -0.249642)
							(end -0.2794 -0.1778)
						)
						(arc
							(start -0.2794 0.1778)
							(mid -0.249642 0.249642)
							(end -0.1778 0.2794)
						)
						(arc
							(start 0.1778 0.2794)
							(mid 0.249642 0.249642)
							(end 0.2794 0.1778)
						)
						(arc
							(start 0.2794 -0.1778)
							(mid 0.249642 -0.249642)
							(end 0.1778 -0.2794)
						)
					)
					(width 0)
					(fill yes)
				)
			)
		)
	)
	(footprint ""
		(layer "F.Cu")
		(at 221.615 -62.992)
		(property "Reference" "PC1204"
			(at 0 0 0)
			(layer "F.SilkS")
			(hide yes)
			(effects
				(font
					(size 1.27 1.27)
				)
			)
		)
		(property "Value" "SCD1U25V3KX-GP"
			(at 0 -2.8194 0)
			(unlocked yes)
			(layer "F.Fab")
			(hide yes)
			(effects
				(font
					(size 1.016 1.016)
					(thickness 0.1524)
				)
			)
		)
		(property "Device Type" "C603H36"
			(at 0 -4.3434 0)
			(unlocked yes)
			(layer "F.Fab")
			(hide yes)
			(effects
				(font
					(size 1.016 1.016)
					(thickness 0.1524)
				)
			)
		)
		(duplicate_pad_numbers_are_jumpers no)
		(fp_line
			(start 0.508 0)
			(end -0.508 0)
			(stroke
				(width 0.2032)
				(type default)
			)
			(layer "F.SilkS")
		)
		(fp_rect
			(start -0.5842 1.3335)
			(end 0.5842 -1.3335)
			(stroke
				(width 0)
				(type default)
			)
			(fill no)
			(layer "F.CrtYd")
		)
		(fp_rect
			(start -0.5842 1.3335)
			(end 0.5842 -1.3335)
			(stroke
				(width 0)
				(type default)
			)
			(fill no)
			(layer "F.Fab")
		)
		(pad "1" smd custom
			(at 0 -0.762)
			(size 0.2159 0.2159)
			(layers "F.Cu" "F.Mask" "F.Paste")
			(net "P3V3")
			(options
				(clearance outline)
				(anchor circle)
			)
			(primitives
				(gr_poly
					(pts
						(arc
							(start -0.3302 -0.4318)
							(mid -0.402042 -0.402042)
							(end -0.4318 -0.3302)
						)
						(arc
							(start -0.4318 0.3302)
							(mid -0.402042 0.402042)
							(end -0.3302 0.4318)
						)
						(arc
							(start 0.3302 0.4318)
							(mid 0.402042 0.402042)
							(end 0.4318 0.3302)
						)
						(arc
							(start 0.4318 -0.3302)
							(mid 0.402042 -0.402042)
							(end 0.3302 -0.4318)
						)
					)
					(width 0)
					(fill yes)
				)
			)
		)
		(pad "2" smd custom
			(at 0 0.762)
			(size 0.2159 0.2159)
			(layers "F.Cu" "F.Mask" "F.Paste")
			(net "GND")
			(options
				(clearance outline)
				(anchor circle)
			)
			(primitives
				(gr_poly
					(pts
						(arc
							(start -0.3302 -0.4318)
							(mid -0.402042 -0.402042)
							(end -0.4318 -0.3302)
						)
						(arc
							(start -0.4318 0.3302)
							(mid -0.402042 0.402042)
							(end -0.3302 0.4318)
						)
						(arc
							(start 0.3302 0.4318)
							(mid 0.402042 0.402042)
							(end 0.4318 0.3302)
						)
						(arc
							(start 0.4318 -0.3302)
							(mid 0.402042 -0.402042)
							(end 0.3302 -0.4318)
						)
					)
					(width 0)
					(fill yes)
				)
			)
		)
	)
	(footprint ""
		(layer "F.Cu")
		(at 90.043 -86.614 -90)
		(property "Reference" "R9507"
			(at 0 0 270)
			(layer "F.SilkS")
			(hide yes)
			(effects
				(font
					(size 1.27 1.27)
				)
			)
		)
		(property "Value" "4K7R2J-2-GP"
			(at 0.064008 -3.993896 270)
			(unlocked yes)
			(layer "F.Fab")
			(hide yes)
			(effects
				(font
					(size 1.016 1.016)
					(thickness 0.1524)
				)
			)
		)
		(property "Device Type" "R402H16"
			(at 0.064008 -5.517896 270)
			(unlocked yes)
			(layer "F.Fab")
			(hide yes)
			(effects
				(font
					(size 1.016 1.016)
					(thickness 0.1524)
				)
			)
		)
		(duplicate_pad_numbers_are_jumpers no)
		(fp_line
			(start -0.508 -0.9398)
			(end -0.508 0.9398)
			(stroke
				(width 0.1524)
				(type default)
			)
			(layer "F.SilkS")
		)
		(fp_line
			(start 0.508 -0.9398)
			(end -0.508 -0.9398)
			(stroke
				(width 0.1524)
				(type default)
			)
			(layer "F.SilkS")
		)
		(fp_rect
			(start -0.508 0.9398)
			(end 0.508 -0.9398)
			(stroke
				(width 0)
				(type default)
			)
			(fill no)
			(layer "F.CrtYd")
		)
		(fp_rect
			(start -0.508 0.9398)
			(end 0.508 -0.9398)
			(stroke
				(width 0)
				(type default)
			)
			(fill no)
			(layer "F.Fab")
		)
		(pad "1" smd custom
			(at 0 -0.4445 270)
			(size 0.1397 0.1397)
			(layers "F.Cu" "F.Mask" "F.Paste")
			(net "P3V3")
			(options
				(clearance outline)
				(anchor circle)
			)
			(primitives
				(gr_poly
					(pts
						(arc
							(start -0.1778 -0.2794)
							(mid -0.249642 -0.249642)
							(end -0.2794 -0.1778)
						)
						(arc
							(start -0.2794 0.1778)
							(mid -0.249642 0.249642)
							(end -0.1778 0.2794)
						)
						(arc
							(start 0.1778 0.2794)
							(mid 0.249642 0.249642)
							(end 0.2794 0.1778)
						)
						(arc
							(start 0.2794 -0.1778)
							(mid 0.249642 -0.249642)
							(end 0.1778 -0.2794)
						)
					)
					(width 0)
					(fill yes)
				)
			)
		)
		(pad "2" smd custom
			(at 0 0.4445 270)
			(size 0.1397 0.1397)
			(layers "F.Cu" "F.Mask" "F.Paste")
			(net "SSD9_CLK0_OE_N")
			(options
				(clearance outline)
				(anchor circle)
			)
			(primitives
				(gr_poly
					(pts
						(arc
							(start -0.1778 -0.2794)
							(mid -0.249642 -0.249642)
							(end -0.2794 -0.1778)
						)
						(arc
							(start -0.2794 0.1778)
							(mid -0.249642 0.249642)
							(end -0.1778 0.2794)
						)
						(arc
							(start 0.1778 0.2794)
							(mid 0.249642 0.249642)
							(end 0.2794 0.1778)
						)
						(arc
							(start 0.2794 -0.1778)
							(mid 0.249642 -0.249642)
							(end 0.1778 -0.2794)
						)
					)
					(width 0)
					(fill yes)
				)
			)
		)
	)
	(footprint ""
		(layer "F.Cu")
		(at 102.235 -216.027 -90)
		(property "Reference" "R9584"
			(at 0 0 270)
			(layer "F.SilkS")
			(hide yes)
			(effects
				(font
					(size 1.27 1.27)
				)
			)
		)
		(property "Value" "0R5J-L1-GP"
			(at 0 -8.9535 270)
			(unlocked yes)
			(layer "F.Fab")
			(hide yes)
			(effects
				(font
					(size 1.27 1.016)
					(thickness 0.1524)
				)
			)
		)
		(property "Device Type" "R805H24"
			(at 0 -10.6299 270)
			(unlocked yes)
			(layer "F.Fab")
			(hide yes)
			(effects
				(font
					(size 1.27 1.016)
					(thickness 0.1524)
				)
			)
		)
		(duplicate_pad_numbers_are_jumpers no)
		(fp_line
			(start -0.889 1.7018)
			(end 0.889 1.7018)
			(stroke
				(width 0.1524)
				(type default)
			)
			(layer "F.SilkS")
		)
		(fp_line
			(start 0.889 1.7018)
			(end 0.889 -0.508)
			(stroke
				(width 0.1524)
				(type default)
			)
			(layer "F.SilkS")
		)
		(fp_line
			(start -0.889 0.0762)
			(end -0.889 1.7018)
			(stroke
				(width 0.1524)
				(type default)
			)
			(layer "F.SilkS")
		)
		(fp_line
			(start -0.889 -1.7018)
			(end -0.889 0.2794)
			(stroke
				(width 0.1524)
				(type default)
			)
			(layer "F.SilkS")
		)
		(fp_line
			(start 0.889 -1.7018)
			(end 0.889 -0.381)
			(stroke
				(width 0.1524)
				(type default)
			)
			(layer "F.SilkS")
		)
		(fp_line
			(start 0.889 -1.7018)
			(end -0.889 -1.7018)
			(stroke
				(width 0.1524)
				(type default)
			)
			(layer "F.SilkS")
		)
		(fp_poly
			(pts
				(xy 0.9652 -1.778) (xy 0.9652 1.778) (xy -0.9652 1.778) (xy -0.9652 -1.778)
			)
			(stroke
				(width 0)
				(type default)
			)
			(fill no)
			(layer "F.CrtYd")
		)
		(fp_rect
			(start -0.9652 1.778)
			(end 0.9652 -1.778)
			(stroke
				(width 0)
				(type default)
			)
			(fill no)
			(layer "F.Fab")
		)
		(pad "1" smd rect
			(at 0 -0.9652 270)
			(size 1.397 1.143)
			(layers "F.Cu" "F.Mask" "F.Paste")
			(net "P3V3")
		)
		(pad "2" smd rect
			(at 0 0.9652 270)
			(size 1.397 1.143)
			(layers "F.Cu" "F.Mask" "F.Paste")
			(net "VDD_IO_3")
		)
	)
	(footprint ""
		(layer "F.Cu")
		(at 92.837 -17.399 -90)
		(property "Reference" "R389"
			(at 0 0 270)
			(layer "F.SilkS")
			(hide yes)
			(effects
				(font
					(size 1.27 1.27)
				)
			)
		)
		(property "Value" "2KR2F-3-GP"
			(at 0.064008 -3.993896 270)
			(unlocked yes)
			(layer "F.Fab")
			(hide yes)
			(effects
				(font
					(size 1.016 1.016)
					(thickness 0.1524)
				)
			)
		)
		(property "Device Type" "R402H16"
			(at 0.064008 -5.517896 270)
			(unlocked yes)
			(layer "F.Fab")
			(hide yes)
			(effects
				(font
					(size 1.016 1.016)
					(thickness 0.1524)
				)
			)
		)
		(duplicate_pad_numbers_are_jumpers no)
		(fp_line
			(start -0.508 -0.9398)
			(end -0.508 0.9398)
			(stroke
				(width 0.1524)
				(type default)
			)
			(layer "F.SilkS")
		)
		(fp_line
			(start 0.508 -0.9398)
			(end -0.508 -0.9398)
			(stroke
				(width 0.1524)
				(type default)
			)
			(layer "F.SilkS")
		)
		(fp_rect
			(start -0.508 0.9398)
			(end 0.508 -0.9398)
			(stroke
				(width 0)
				(type default)
			)
			(fill no)
			(layer "F.CrtYd")
		)
		(fp_rect
			(start -0.508 0.9398)
			(end 0.508 -0.9398)
			(stroke
				(width 0)
				(type default)
			)
			(fill no)
			(layer "F.Fab")
		)
		(pad "1" smd custom
			(at 0 -0.4445 270)
			(size 0.1397 0.1397)
			(layers "F.Cu" "F.Mask" "F.Paste")
			(net "P12V_SENSE")
			(options
				(clearance outline)
				(anchor circle)
			)
			(primitives
				(gr_poly
					(pts
						(arc
							(start -0.1778 -0.2794)
							(mid -0.249642 -0.249642)
							(end -0.2794 -0.1778)
						)
						(arc
							(start -0.2794 0.1778)
							(mid -0.249642 0.249642)
							(end -0.1778 0.2794)
						)
						(arc
							(start 0.1778 0.2794)
							(mid 0.249642 0.249642)
							(end 0.2794 0.1778)
						)
						(arc
							(start 0.2794 -0.1778)
							(mid 0.249642 -0.249642)
							(end 0.1778 -0.2794)
						)
					)
					(width 0)
					(fill yes)
				)
			)
		)
		(pad "2" smd custom
			(at 0 0.4445 270)
			(size 0.1397 0.1397)
			(layers "F.Cu" "F.Mask" "F.Paste")
			(net "GND")
			(options
				(clearance outline)
				(anchor circle)
			)
			(primitives
				(gr_poly
					(pts
						(arc
							(start -0.1778 -0.2794)
							(mid -0.249642 -0.249642)
							(end -0.2794 -0.1778)
						)
						(arc
							(start -0.2794 0.1778)
							(mid -0.249642 0.249642)
							(end -0.1778 0.2794)
						)
						(arc
							(start 0.1778 0.2794)
							(mid 0.249642 0.249642)
							(end 0.2794 0.1778)
						)
						(arc
							(start 0.2794 -0.1778)
							(mid 0.249642 -0.249642)
							(end 0.1778 -0.2794)
						)
					)
					(width 0)
					(fill yes)
				)
			)
		)
	)
	(footprint ""
		(layer "F.Cu")
		(at 84.074 -146.9644 -90)
		(property "Reference" "R372"
			(at 0 0 270)
			(layer "F.SilkS")
			(hide yes)
			(effects
				(font
					(size 1.27 1.27)
				)
			)
		)
		(property "Value" "4K7R2J-2-GP"
			(at 0.064008 -3.993896 270)
			(unlocked yes)
			(layer "F.Fab")
			(hide yes)
			(effects
				(font
					(size 1.016 1.016)
					(thickness 0.1524)
				)
			)
		)
		(property "Device Type" "R402H16"
			(at 0.064008 -5.517896 270)
			(unlocked yes)
			(layer "F.Fab")
			(hide yes)
			(effects
				(font
					(size 1.016 1.016)
					(thickness 0.1524)
				)
			)
		)
		(duplicate_pad_numbers_are_jumpers no)
		(fp_line
			(start -0.508 -0.9398)
			(end -0.508 0.9398)
			(stroke
				(width 0.1524)
				(type default)
			)
			(layer "F.SilkS")
		)
		(fp_line
			(start 0.508 -0.9398)
			(end -0.508 -0.9398)
			(stroke
				(width 0.1524)
				(type default)
			)
			(layer "F.SilkS")
		)
		(fp_rect
			(start -0.508 0.9398)
			(end 0.508 -0.9398)
			(stroke
				(width 0)
				(type default)
			)
			(fill no)
			(layer "F.CrtYd")
		)
		(fp_rect
			(start -0.508 0.9398)
			(end 0.508 -0.9398)
			(stroke
				(width 0)
				(type default)
			)
			(fill no)
			(layer "F.Fab")
		)
		(pad "1" smd custom
			(at 0 -0.4445 270)
			(size 0.1397 0.1397)
			(layers "F.Cu" "F.Mask" "F.Paste")
			(net "P3V3")
			(options
				(clearance outline)
				(anchor circle)
			)
			(primitives
				(gr_poly
					(pts
						(arc
							(start -0.1778 -0.2794)
							(mid -0.249642 -0.249642)
							(end -0.2794 -0.1778)
						)
						(arc
							(start -0.2794 0.1778)
							(mid -0.249642 0.249642)
							(end -0.1778 0.2794)
						)
						(arc
							(start 0.1778 0.2794)
							(mid 0.249642 0.249642)
							(end 0.2794 0.1778)
						)
						(arc
							(start 0.2794 -0.1778)
							(mid 0.249642 -0.249642)
							(end 0.1778 -0.2794)
						)
					)
					(width 0)
					(fill yes)
				)
			)
		)
		(pad "2" smd custom
			(at 0 0.4445 270)
			(size 0.1397 0.1397)
			(layers "F.Cu" "F.Mask" "F.Paste")
			(net "BMC_I2C_SDA_BUF_8")
			(options
				(clearance outline)
				(anchor circle)
			)
			(primitives
				(gr_poly
					(pts
						(arc
							(start -0.1778 -0.2794)
							(mid -0.249642 -0.249642)
							(end -0.2794 -0.1778)
						)
						(arc
							(start -0.2794 0.1778)
							(mid -0.249642 0.249642)
							(end -0.1778 0.2794)
						)
						(arc
							(start 0.1778 0.2794)
							(mid 0.249642 0.249642)
							(end 0.2794 0.1778)
						)
						(arc
							(start 0.2794 -0.1778)
							(mid 0.249642 -0.249642)
							(end 0.1778 -0.2794)
						)
					)
					(width 0)
					(fill yes)
				)
			)
		)
	)
	(footprint ""
		(layer "F.Cu")
		(at 218.313 -432.054)
		(property "Reference" "PR9084"
			(at 0 0 0)
			(layer "F.SilkS")
			(hide yes)
			(effects
				(font
					(size 1.27 1.27)
				)
			)
		)
		(property "Value" "2KR2F-3-GP"
			(at 0.064008 -3.993896 0)
			(unlocked yes)
			(layer "F.Fab")
			(hide yes)
			(effects
				(font
					(size 1.016 1.016)
					(thickness 0.1524)
				)
			)
		)
		(property "Device Type" "R402H16"
			(at 0.064008 -5.517896 0)
			(unlocked yes)
			(layer "F.Fab")
			(hide yes)
			(effects
				(font
					(size 1.016 1.016)
					(thickness 0.1524)
				)
			)
		)
		(duplicate_pad_numbers_are_jumpers no)
		(fp_line
			(start -0.508 -0.9398)
			(end -0.508 0.9398)
			(stroke
				(width 0.1524)
				(type default)
			)
			(layer "F.SilkS")
		)
		(fp_line
			(start 0.508 -0.9398)
			(end -0.508 -0.9398)
			(stroke
				(width 0.1524)
				(type default)
			)
			(layer "F.SilkS")
		)
		(fp_rect
			(start -0.508 0.9398)
			(end 0.508 -0.9398)
			(stroke
				(width 0)
				(type default)
			)
			(fill no)
			(layer "F.CrtYd")
		)
		(fp_rect
			(start -0.508 0.9398)
			(end 0.508 -0.9398)
			(stroke
				(width 0)
				(type default)
			)
			(fill no)
			(layer "F.Fab")
		)
		(pad "1" smd custom
			(at 0 -0.4445)
			(size 0.1397 0.1397)
			(layers "F.Cu" "F.Mask" "F.Paste")
			(net "P3V3_SW")
			(options
				(clearance outline)
				(anchor circle)
			)
			(primitives
				(gr_poly
					(pts
						(arc
							(start -0.1778 -0.2794)
							(mid -0.249642 -0.249642)
							(end -0.2794 -0.1778)
						)
						(arc
							(start -0.2794 0.1778)
							(mid -0.249642 0.249642)
							(end -0.1778 0.2794)
						)
						(arc
							(start 0.1778 0.2794)
							(mid 0.249642 0.249642)
							(end 0.2794 0.1778)
						)
						(arc
							(start 0.2794 -0.1778)
							(mid 0.249642 -0.249642)
							(end 0.1778 -0.2794)
						)
					)
					(width 0)
					(fill yes)
				)
			)
		)
		(pad "2" smd custom
			(at 0 0.4445)
			(size 0.1397 0.1397)
			(layers "F.Cu" "F.Mask" "F.Paste")
			(net "P3V3_VFB_R")
			(options
				(clearance outline)
				(anchor circle)
			)
			(primitives
				(gr_poly
					(pts
						(arc
							(start -0.1778 -0.2794)
							(mid -0.249642 -0.249642)
							(end -0.2794 -0.1778)
						)
						(arc
							(start -0.2794 0.1778)
							(mid -0.249642 0.249642)
							(end -0.1778 0.2794)
						)
						(arc
							(start 0.1778 0.2794)
							(mid 0.249642 0.249642)
							(end 0.2794 0.1778)
						)
						(arc
							(start 0.2794 -0.1778)
							(mid 0.249642 -0.249642)
							(end 0.1778 -0.2794)
						)
					)
					(width 0)
					(fill yes)
				)
			)
		)
	)
	(footprint ""
		(layer "F.Cu")
		(at 102.616 -209.296 90)
		(property "Reference" "R9083"
			(at 0 0 90)
			(layer "F.SilkS")
			(hide yes)
			(effects
				(font
					(size 1.27 1.27)
				)
			)
		)
		(property "Value" "27R2F-GP"
			(at 0.064008 -3.993896 90)
			(unlocked yes)
			(layer "F.Fab")
			(hide yes)
			(effects
				(font
					(size 1.016 1.016)
					(thickness 0.1524)
				)
			)
		)
		(property "Device Type" "R402H16"
			(at 0.064008 -5.517896 90)
			(unlocked yes)
			(layer "F.Fab")
			(hide yes)
			(effects
				(font
					(size 1.016 1.016)
					(thickness 0.1524)
				)
			)
		)
		(duplicate_pad_numbers_are_jumpers no)
		(fp_line
			(start 0.508 -0.9398)
			(end -0.508 -0.9398)
			(stroke
				(width 0.1524)
				(type default)
			)
			(layer "F.SilkS")
		)
		(fp_line
			(start -0.508 -0.9398)
			(end -0.508 0.9398)
			(stroke
				(width 0.1524)
				(type default)
			)
			(layer "F.SilkS")
		)
		(fp_rect
			(start -0.508 0.9398)
			(end 0.508 -0.9398)
			(stroke
				(width 0)
				(type default)
			)
			(fill no)
			(layer "F.CrtYd")
		)
		(fp_rect
			(start -0.508 0.9398)
			(end 0.508 -0.9398)
			(stroke
				(width 0)
				(type default)
			)
			(fill no)
			(layer "F.Fab")
		)
		(pad "1" smd custom
			(at 0 -0.4445 90)
			(size 0.1397 0.1397)
			(layers "F.Cu" "F.Mask" "F.Paste")
			(net "PE_CLK_100M_DR3_1_R_N")
			(options
				(clearance outline)
				(anchor circle)
			)
			(primitives
				(gr_poly
					(pts
						(arc
							(start -0.1778 -0.2794)
							(mid -0.249642 -0.249642)
							(end -0.2794 -0.1778)
						)
						(arc
							(start -0.2794 0.1778)
							(mid -0.249642 0.249642)
							(end -0.1778 0.2794)
						)
						(arc
							(start 0.1778 0.2794)
							(mid 0.249642 0.249642)
							(end 0.2794 0.1778)
						)
						(arc
							(start 0.2794 -0.1778)
							(mid 0.249642 -0.249642)
							(end 0.1778 -0.2794)
						)
					)
					(width 0)
					(fill yes)
				)
			)
		)
		(pad "2" smd custom
			(at 0 0.4445 90)
			(size 0.1397 0.1397)
			(layers "F.Cu" "F.Mask" "F.Paste")
			(net "PE_CLK100M_DR3_1_N")
			(options
				(clearance outline)
				(anchor circle)
			)
			(primitives
				(gr_poly
					(pts
						(arc
							(start -0.1778 -0.2794)
							(mid -0.249642 -0.249642)
							(end -0.2794 -0.1778)
						)
						(arc
							(start -0.2794 0.1778)
							(mid -0.249642 0.249642)
							(end -0.1778 0.2794)
						)
						(arc
							(start 0.1778 0.2794)
							(mid 0.249642 0.249642)
							(end 0.2794 0.1778)
						)
						(arc
							(start 0.2794 -0.1778)
							(mid 0.249642 -0.249642)
							(end 0.1778 -0.2794)
						)
					)
					(width 0)
					(fill yes)
				)
			)
		)
	)
	(footprint ""
		(layer "F.Cu")
		(at 209.804 -88.646 -90)
		(property "Reference" "R142"
			(at 0 0 270)
			(layer "F.SilkS")
			(hide yes)
			(effects
				(font
					(size 1.27 1.27)
				)
			)
		)
		(property "Value" "4K7R2J-2-GP"
			(at 0.064008 -3.993896 270)
			(unlocked yes)
			(layer "F.Fab")
			(hide yes)
			(effects
				(font
					(size 1.016 1.016)
					(thickness 0.1524)
				)
			)
		)
		(property "Device Type" "R402H16"
			(at 0.064008 -5.517896 270)
			(unlocked yes)
			(layer "F.Fab")
			(hide yes)
			(effects
				(font
					(size 1.016 1.016)
					(thickness 0.1524)
				)
			)
		)
		(duplicate_pad_numbers_are_jumpers no)
		(fp_line
			(start -0.508 -0.9398)
			(end -0.508 0.9398)
			(stroke
				(width 0.1524)
				(type default)
			)
			(layer "F.SilkS")
		)
		(fp_line
			(start 0.508 -0.9398)
			(end -0.508 -0.9398)
			(stroke
				(width 0.1524)
				(type default)
			)
			(layer "F.SilkS")
		)
		(fp_rect
			(start -0.508 0.9398)
			(end 0.508 -0.9398)
			(stroke
				(width 0)
				(type default)
			)
			(fill no)
			(layer "F.CrtYd")
		)
		(fp_rect
			(start -0.508 0.9398)
			(end 0.508 -0.9398)
			(stroke
				(width 0)
				(type default)
			)
			(fill no)
			(layer "F.Fab")
		)
		(pad "1" smd custom
			(at 0 -0.4445 270)
			(size 0.1397 0.1397)
			(layers "F.Cu" "F.Mask" "F.Paste")
			(net "P12V")
			(options
				(clearance outline)
				(anchor circle)
			)
			(primitives
				(gr_poly
					(pts
						(arc
							(start -0.1778 -0.2794)
							(mid -0.249642 -0.249642)
							(end -0.2794 -0.1778)
						)
						(arc
							(start -0.2794 0.1778)
							(mid -0.249642 0.249642)
							(end -0.1778 0.2794)
						)
						(arc
							(start 0.1778 0.2794)
							(mid 0.249642 0.249642)
							(end 0.2794 0.1778)
						)
						(arc
							(start 0.2794 -0.1778)
							(mid 0.249642 -0.249642)
							(end 0.1778 -0.2794)
						)
					)
					(width 0)
					(fill yes)
				)
			)
		)
		(pad "2" smd custom
			(at 0 0.4445 270)
			(size 0.1397 0.1397)
			(layers "F.Cu" "F.Mask" "F.Paste")
			(net "SW_SSD4_R")
			(options
				(clearance outline)
				(anchor circle)
			)
			(primitives
				(gr_poly
					(pts
						(arc
							(start -0.1778 -0.2794)
							(mid -0.249642 -0.249642)
							(end -0.2794 -0.1778)
						)
						(arc
							(start -0.2794 0.1778)
							(mid -0.249642 0.249642)
							(end -0.1778 0.2794)
						)
						(arc
							(start 0.1778 0.2794)
							(mid 0.249642 0.249642)
							(end 0.2794 0.1778)
						)
						(arc
							(start 0.2794 -0.1778)
							(mid 0.249642 -0.249642)
							(end 0.1778 -0.2794)
						)
					)
					(width 0)
					(fill yes)
				)
			)
		)
	)
	(footprint ""
		(layer "F.Cu")
		(at 101.346 -213.487 -90)
		(property "Reference" "R9509"
			(at 0 0 270)
			(layer "F.SilkS")
			(hide yes)
			(effects
				(font
					(size 1.27 1.27)
				)
			)
		)
		(property "Value" "4K7R2F-GP"
			(at 0.064008 -3.993896 270)
			(unlocked yes)
			(layer "F.Fab")
			(hide yes)
			(effects
				(font
					(size 1.016 1.016)
					(thickness 0.1524)
				)
			)
		)
		(property "Device Type" "R402H16"
			(at 0.064008 -5.517896 270)
			(unlocked yes)
			(layer "F.Fab")
			(hide yes)
			(effects
				(font
					(size 1.016 1.016)
					(thickness 0.1524)
				)
			)
		)
		(duplicate_pad_numbers_are_jumpers no)
		(fp_line
			(start -0.508 -0.9398)
			(end -0.508 0.9398)
			(stroke
				(width 0.1524)
				(type default)
			)
			(layer "F.SilkS")
		)
		(fp_line
			(start 0.508 -0.9398)
			(end -0.508 -0.9398)
			(stroke
				(width 0.1524)
				(type default)
			)
			(layer "F.SilkS")
		)
		(fp_rect
			(start -0.508 0.9398)
			(end 0.508 -0.9398)
			(stroke
				(width 0)
				(type default)
			)
			(fill no)
			(layer "F.CrtYd")
		)
		(fp_rect
			(start -0.508 0.9398)
			(end 0.508 -0.9398)
			(stroke
				(width 0)
				(type default)
			)
			(fill no)
			(layer "F.Fab")
		)
		(pad "1" smd custom
			(at 0 -0.4445 270)
			(size 0.1397 0.1397)
			(layers "F.Cu" "F.Mask" "F.Paste")
			(net "P3V3")
			(options
				(clearance outline)
				(anchor circle)
			)
			(primitives
				(gr_poly
					(pts
						(arc
							(start -0.1778 -0.2794)
							(mid -0.249642 -0.249642)
							(end -0.2794 -0.1778)
						)
						(arc
							(start -0.2794 0.1778)
							(mid -0.249642 0.249642)
							(end -0.1778 0.2794)
						)
						(arc
							(start 0.1778 0.2794)
							(mid 0.249642 0.249642)
							(end 0.2794 0.1778)
						)
						(arc
							(start 0.2794 -0.1778)
							(mid 0.249642 -0.249642)
							(end 0.1778 -0.2794)
						)
					)
					(width 0)
					(fill yes)
				)
			)
		)
		(pad "2" smd custom
			(at 0 0.4445 270)
			(size 0.1397 0.1397)
			(layers "F.Cu" "F.Mask" "F.Paste")
			(net "CLK_BUFFER_EU3_VOE_N")
			(options
				(clearance outline)
				(anchor circle)
			)
			(primitives
				(gr_poly
					(pts
						(arc
							(start -0.1778 -0.2794)
							(mid -0.249642 -0.249642)
							(end -0.2794 -0.1778)
						)
						(arc
							(start -0.2794 0.1778)
							(mid -0.249642 0.249642)
							(end -0.1778 0.2794)
						)
						(arc
							(start 0.1778 0.2794)
							(mid 0.249642 0.249642)
							(end 0.2794 0.1778)
						)
						(arc
							(start 0.2794 -0.1778)
							(mid 0.249642 -0.249642)
							(end 0.1778 -0.2794)
						)
					)
					(width 0)
					(fill yes)
				)
			)
		)
	)
	(footprint ""
		(layer "F.Cu")
		(at 21.8694 -467.5124 90)
		(property "Reference" "R9848"
			(at 0 0 90)
			(layer "F.SilkS")
			(hide yes)
			(effects
				(font
					(size 1.27 1.27)
				)
			)
		)
		(property "Value" "0R2J-2-GP"
			(at 0.064008 -3.993896 90)
			(unlocked yes)
			(layer "F.Fab")
			(hide yes)
			(effects
				(font
					(size 1.016 1.016)
					(thickness 0.1524)
				)
			)
		)
		(property "Device Type" "R402H16"
			(at 0.064008 -5.517896 90)
			(unlocked yes)
			(layer "F.Fab")
			(hide yes)
			(effects
				(font
					(size 1.016 1.016)
					(thickness 0.1524)
				)
			)
		)
		(duplicate_pad_numbers_are_jumpers no)
		(fp_line
			(start 0.508 -0.9398)
			(end -0.508 -0.9398)
			(stroke
				(width 0.1524)
				(type default)
			)
			(layer "F.SilkS")
		)
		(fp_line
			(start -0.508 -0.9398)
			(end -0.508 0.9398)
			(stroke
				(width 0.1524)
				(type default)
			)
			(layer "F.SilkS")
		)
		(fp_rect
			(start -0.508 0.9398)
			(end 0.508 -0.9398)
			(stroke
				(width 0)
				(type default)
			)
			(fill no)
			(layer "F.CrtYd")
		)
		(fp_rect
			(start -0.508 0.9398)
			(end 0.508 -0.9398)
			(stroke
				(width 0)
				(type default)
			)
			(fill no)
			(layer "F.Fab")
		)
		(pad "1" smd custom
			(at 0 -0.4445 90)
			(size 0.1397 0.1397)
			(layers "F.Cu" "F.Mask" "F.Paste")
			(net "ATTN_LED_DR10_R")
			(options
				(clearance outline)
				(anchor circle)
			)
			(primitives
				(gr_poly
					(pts
						(arc
							(start -0.1778 -0.2794)
							(mid -0.249642 -0.249642)
							(end -0.2794 -0.1778)
						)
						(arc
							(start -0.2794 0.1778)
							(mid -0.249642 0.249642)
							(end -0.1778 0.2794)
						)
						(arc
							(start 0.1778 0.2794)
							(mid 0.249642 0.249642)
							(end 0.2794 0.1778)
						)
						(arc
							(start 0.2794 -0.1778)
							(mid 0.249642 -0.249642)
							(end 0.1778 -0.2794)
						)
					)
					(width 0)
					(fill yes)
				)
			)
		)
		(pad "2" smd custom
			(at 0 0.4445 90)
			(size 0.1397 0.1397)
			(layers "F.Cu" "F.Mask" "F.Paste")
			(net "ATTN_LED_DR10_N")
			(options
				(clearance outline)
				(anchor circle)
			)
			(primitives
				(gr_poly
					(pts
						(arc
							(start -0.1778 -0.2794)
							(mid -0.249642 -0.249642)
							(end -0.2794 -0.1778)
						)
						(arc
							(start -0.2794 0.1778)
							(mid -0.249642 0.249642)
							(end -0.1778 0.2794)
						)
						(arc
							(start 0.1778 0.2794)
							(mid 0.249642 0.249642)
							(end 0.2794 0.1778)
						)
						(arc
							(start 0.2794 -0.1778)
							(mid 0.249642 -0.249642)
							(end 0.1778 -0.2794)
						)
					)
					(width 0)
					(fill yes)
				)
			)
		)
	)
	(footprint ""
		(layer "F.Cu")
		(at 228.346 -93.6244)
		(property "Reference" "R9244"
			(at 0 0 0)
			(layer "F.SilkS")
			(hide yes)
			(effects
				(font
					(size 1.27 1.27)
				)
			)
		)
		(property "Value" "2R2010F-GP"
			(at 0.0762 -4.5466 0)
			(unlocked yes)
			(layer "F.Fab")
			(hide yes)
			(effects
				(font
					(size 1.016 1.016)
					(thickness 0.1524)
				)
			)
		)
		(property "Device Type" "R2010H26"
			(at 0.0762 -6.1468 0)
			(unlocked yes)
			(layer "F.Fab")
			(hide yes)
			(effects
				(font
					(size 1.016 1.016)
					(thickness 0.1524)
				)
			)
		)
		(duplicate_pad_numbers_are_jumpers no)
		(fp_line
			(start -3.302 -1.651)
			(end -3.302 1.651)
			(stroke
				(width 0.1524)
				(type default)
			)
			(layer "F.SilkS")
		)
		(fp_line
			(start -3.302 1.651)
			(end 3.302 1.651)
			(stroke
				(width 0.1524)
				(type default)
			)
			(layer "F.SilkS")
		)
		(fp_line
			(start 3.302 -1.651)
			(end -3.302 -1.651)
			(stroke
				(width 0.1524)
				(type default)
			)
			(layer "F.SilkS")
		)
		(fp_line
			(start 3.302 1.651)
			(end 3.302 -1.651)
			(stroke
				(width 0.1524)
				(type default)
			)
			(layer "F.SilkS")
		)
		(fp_rect
			(start -3.3782 1.7272)
			(end 3.3782 -1.7272)
			(stroke
				(width 0)
				(type default)
			)
			(fill no)
			(layer "F.CrtYd")
		)
		(fp_poly
			(pts
				(xy 3.3782 -1.7272) (xy -3.3782 -1.7272) (xy -3.3782 1.7272) (xy 3.3782 1.7272)
			)
			(stroke
				(width 0)
				(type default)
			)
			(fill no)
			(layer "F.Fab")
		)
		(pad "1" smd rect
			(at -2.3495 0)
			(size 1.143 2.794)
			(layers "F.Cu" "F.Mask" "F.Paste")
			(net "P12V_SSD4")
		)
		(pad "2" smd rect
			(at 2.3495 0)
			(size 1.143 2.794)
			(layers "F.Cu" "F.Mask" "F.Paste")
			(net "12V_PRECH_SSD4")
		)
	)
	(footprint ""
		(layer "F.Cu")
		(at 23.998174 -62.083442 -90)
		(property "Reference" "U211"
			(at 0 0 270)
			(layer "F.SilkS")
			(hide yes)
			(effects
				(font
					(size 1.27 1.27)
				)
			)
		)
		(property "Value" "SN74LVC1G08DCKR-GP"
			(at -2.3368 -8.6868 270)
			(unlocked yes)
			(layer "F.Fab")
			(hide yes)
			(effects
				(font
					(size 1.016 1.016)
					(thickness 0.1524)
				)
			)
		)
		(property "Device Type" "SC70-5H44"
			(at -2.3114 -10.414 270)
			(unlocked yes)
			(layer "F.Fab")
			(hide yes)
			(effects
				(font
					(size 1.016 1.016)
					(thickness 0.1524)
				)
			)
		)
		(duplicate_pad_numbers_are_jumpers no)
		(fp_line
			(start -1.27 1.7018)
			(end -1.27 -1.7018)
			(stroke
				(width 0.1524)
				(type default)
			)
			(layer "F.SilkS")
		)
		(fp_line
			(start 1.27 1.7018)
			(end -1.27 1.7018)
			(stroke
				(width 0.1524)
				(type default)
			)
			(layer "F.SilkS")
		)
		(fp_line
			(start -1.27 -1.7018)
			(end 1.27 -1.7018)
			(stroke
				(width 0.1524)
				(type default)
			)
			(layer "F.SilkS")
		)
		(fp_line
			(start 1.27 -1.7018)
			(end 1.27 1.7018)
			(stroke
				(width 0.1524)
				(type default)
			)
			(layer "F.SilkS")
		)
		(fp_line
			(start 0.6604 -1.8034)
			(end 1.3843 -1.8034)
			(stroke
				(width 0.3302)
				(type default)
			)
			(layer "F.SilkS")
		)
		(fp_line
			(start 1.3843 -1.8034)
			(end 1.3843 -1.1176)
			(stroke
				(width 0.3302)
				(type default)
			)
			(layer "F.SilkS")
		)
		(fp_rect
			(start -1.524 1.9558)
			(end 1.524 -1.9558)
			(stroke
				(width 0)
				(type default)
			)
			(fill no)
			(layer "F.CrtYd")
		)
		(fp_poly
			(pts
				(xy -1.524 -1.9558) (xy 1.524 -1.9558) (xy 1.524 1.9558) (xy -1.524 1.9558)
			)
			(stroke
				(width 0)
				(type default)
			)
			(fill no)
			(layer "F.Fab")
		)
		(pad "1" smd rect
			(at 0.65024 -0.8255 270)
			(size 0.4064 1.2192)
			(layers "F.Cu" "F.Mask" "F.Paste")
			(net "SSD14_CLK0_OE_MOS_N")
		)
		(pad "2" smd rect
			(at 0 -0.8255 270)
			(size 0.4064 1.2192)
			(layers "F.Cu" "F.Mask" "F.Paste")
			(net "ATTN_LED_DR14_N")
		)
		(pad "3" smd rect
			(at -0.65024 -0.8255 270)
			(size 0.4064 1.2192)
			(layers "F.Cu" "F.Mask" "F.Paste")
			(net "GND")
		)
		(pad "4" smd rect
			(at -0.65024 0.8255 270)
			(size 0.4064 1.2192)
			(layers "F.Cu" "F.Mask" "F.Paste")
			(net "ATTN_LED_DR14_AND")
		)
		(pad "5" smd rect
			(at 0.65024 0.8255 270)
			(size 0.4064 1.2192)
			(layers "F.Cu" "F.Mask" "F.Paste")
			(net "P3V3")
		)
	)
	(footprint ""
		(layer "F.Cu")
		(at 226.149916 -170.669966 90)
		(property "Reference" "J3"
			(at 0 0 90)
			(layer "F.SilkS")
			(hide yes)
			(effects
				(font
					(size 1.27 1.27)
				)
			)
		)
		(property "Value" "PCISLT68-14-GP-U1"
			(at -22.225 12.7508 90)
			(unlocked yes)
			(layer "F.Fab")
			(hide yes)
			(effects
				(font
					(size 1.016 1.016)
					(thickness 0.1524)
				)
			)
		)
		(property "Device Type" "SD-78827-0001"
			(at -22.225 11.2268 90)
			(unlocked yes)
			(layer "F.Fab")
			(hide yes)
			(effects
				(font
					(size 1.016 1.016)
					(thickness 0.1524)
				)
			)
		)
		(duplicate_pad_numbers_are_jumpers no)
		(fp_line
			(start 20.4724 -3.4036)
			(end 20.4724 0.0254)
			(stroke
				(width 0.1524)
				(type default)
			)
			(layer "F.SilkS")
		)
		(fp_line
			(start -20.4724 -3.4036)
			(end 20.4724 -3.4036)
			(stroke
				(width 0.1524)
				(type default)
			)
			(layer "F.SilkS")
		)
		(fp_line
			(start 23.749 0.0254)
			(end 23.749 4.6736)
			(stroke
				(width 0.1524)
				(type default)
			)
			(layer "F.SilkS")
		)
		(fp_line
			(start 20.4724 0.0254)
			(end 23.749 0.0254)
			(stroke
				(width 0.1524)
				(type default)
			)
			(layer "F.SilkS")
		)
		(fp_line
			(start -20.4724 0.0254)
			(end -20.4724 -3.4036)
			(stroke
				(width 0.1524)
				(type default)
			)
			(layer "F.SilkS")
		)
		(fp_line
			(start -23.749 0.0254)
			(end -20.4724 0.0254)
			(stroke
				(width 0.1524)
				(type default)
			)
			(layer "F.SilkS")
		)
		(fp_line
			(start 23.117556 1.803908)
			(end 23.117556 2.896108)
			(stroke
				(width 0.3048)
				(type default)
			)
			(layer "F.SilkS")
		)
		(fp_line
			(start -20.882356 1.803908)
			(end -20.882356 2.896108)
			(stroke
				(width 0.3048)
				(type default)
			)
			(layer "F.SilkS")
		)
		(fp_line
			(start 20.882356 2.896108)
			(end 20.882356 1.803908)
			(stroke
				(width 0.3048)
				(type default)
			)
			(layer "F.SilkS")
		)
		(fp_line
			(start -23.117556 2.896108)
			(end -23.117556 1.803908)
			(stroke
				(width 0.3048)
				(type default)
			)
			(layer "F.SilkS")
		)
		(fp_line
			(start 23.749 4.6736)
			(end 20.4724 4.6736)
			(stroke
				(width 0.1524)
				(type default)
			)
			(layer "F.SilkS")
		)
		(fp_line
			(start 20.4724 4.6736)
			(end 20.4724 12.0142)
			(stroke
				(width 0.1524)
				(type default)
			)
			(layer "F.SilkS")
		)
		(fp_line
			(start -20.4724 4.6736)
			(end -23.749 4.6736)
			(stroke
				(width 0.1524)
				(type default)
			)
			(layer "F.SilkS")
		)
		(fp_line
			(start -23.749 4.6736)
			(end -23.749 0.0254)
			(stroke
				(width 0.1524)
				(type default)
			)
			(layer "F.SilkS")
		)
		(fp_line
			(start 17.8435 10.3124)
			(end -17.8435 10.3124)
			(stroke
				(width 0.1524)
				(type default)
			)
			(layer "F.SilkS")
		)
		(fp_line
			(start -17.8435 10.3124)
			(end -17.8435 12.0142)
			(stroke
				(width 0.1524)
				(type default)
			)
			(layer "F.SilkS")
		)
		(fp_line
			(start 20.4724 12.0142)
			(end 17.8435 12.0142)
			(stroke
				(width 0.1524)
				(type default)
			)
			(layer "F.SilkS")
		)
		(fp_line
			(start 17.8435 12.0142)
			(end 17.8435 10.3124)
			(stroke
				(width 0.1524)
				(type default)
			)
			(layer "F.SilkS")
		)
		(fp_line
			(start -17.8435 12.0142)
			(end -20.4724 12.0142)
			(stroke
				(width 0.1524)
				(type default)
			)
			(layer "F.SilkS")
		)
		(fp_line
			(start -20.4724 12.0142)
			(end -20.4724 4.6736)
			(stroke
				(width 0.1524)
				(type default)
			)
			(layer "F.SilkS")
		)
		(fp_arc
			(start 20.882356 1.803908)
			(mid 21.999956 0.686308)
			(end 23.117556 1.803908)
			(stroke
				(width 0.3048)
				(type default)
			)
			(layer "F.SilkS")
		)
		(fp_arc
			(start -23.117556 1.803908)
			(mid -21.999956 0.686308)
			(end -20.882356 1.803908)
			(stroke
				(width 0.3048)
				(type default)
			)
			(layer "F.SilkS")
		)
		(fp_arc
			(start 23.117556 2.896108)
			(mid 21.999956 4.013708)
			(end 20.882356 2.896108)
			(stroke
				(width 0.3048)
				(type default)
			)
			(layer "F.SilkS")
		)
		(fp_arc
			(start -20.882356 2.896108)
			(mid -21.999956 4.013708)
			(end -23.117556 2.896108)
			(stroke
				(width 0.3048)
				(type default)
			)
			(layer "F.SilkS")
		)
		(fp_poly
			(pts
				(xy -20.2184 11.7602) (xy -20.2184 4.4196) (xy -23.495 4.4196) (xy -23.495 0.2794) (xy -20.2184 0.2794)
				(xy -20.2184 -3.1496) (xy 20.2184 -3.1496) (xy 20.2184 0.2794) (xy 23.495 0.2794) (xy 23.495 4.4196)
				(xy 20.2184 4.4196) (xy 20.2184 11.7602) (xy 18.0975 11.7602) (xy 18.0975 10.0584) (xy -18.0975 10.0584)
				(xy -18.0975 11.7602)
			)
			(stroke
				(width 0)
				(type default)
			)
			(fill no)
			(layer "F.CrtYd")
		)
		(fp_poly
			(pts
				(xy -21.2471 16.256) (xy -21.2471 4.9276) (xy -24.003 4.9276) (xy -24.003 -0.2286) (xy -20.7264 -0.2286)
				(xy -20.7264 -3.6576) (xy 20.7264 -3.6576) (xy 20.7264 -0.2286) (xy 24.003 -0.2286) (xy 24.003 -0.00635)
				(xy 20.2184 -0.00635) (xy 20.2184 -3.1496) (xy -20.2184 -3.1496) (xy -20.2184 0.2794) (xy -23.495 0.2794)
				(xy -23.495 4.4196) (xy -20.2184 4.4196) (xy -20.2184 11.7602) (xy -18.0975 11.7602) (xy -18.0975 10.0584)
				(xy 18.0975 10.0584) (xy 18.0975 11.7602) (xy 20.2184 11.7602) (xy 20.2184 4.4196) (xy 23.495 4.4196)
				(xy 23.495 0.2794) (xy 20.2184 0.2794) (xy 20.2184 0.00635) (xy 24.003 0.00635) (xy 24.003 4.9276)
				(xy 21.2471 4.9276) (xy 21.2471 16.256)
			)
			(stroke
				(width 0)
				(type default)
			)
			(fill no)
			(layer "F.CrtYd")
		)
		(fp_poly
			(pts
				(xy -21.2471 16.256) (xy -21.2471 4.9276) (xy -24.003 4.9276) (xy -24.003 -0.2286) (xy -20.7264 -0.2286)
				(xy -20.7264 -3.6576) (xy 20.7264 -3.6576) (xy 20.7264 -0.2286) (xy 24.003 -0.2286) (xy 24.003 4.9276)
				(xy 21.2471 4.9276) (xy 21.2471 16.256)
			)
			(stroke
				(width 0)
				(type default)
			)
			(fill no)
			(layer "F.Fab")
		)
		(pad "" np_thru_hole circle
			(at -18.999962 0 90)
			(size 0.254 0.254)
			(drill 1.8542)
			(layers "*.Cu" "*.Mask")
			(clearance 1.1557)
			(thermal_gap 1.1557)
		)
		(pad "" np_thru_hole circle
			(at 18.999962 0 90)
			(size 0.254 0.254)
			(drill 1.8542)
			(layers "*.Cu" "*.Mask")
			(clearance 1.1557)
			(thermal_gap 1.1557)
		)
		(pad "E1" smd rect
			(at -7.079996 1.240028 90)
			(size 0.508 2.0066)
			(layers "F.Cu" "F.Mask" "F.Paste")
			(net "PE_CLK100M_DR3_2_P")
		)
		(pad "E2" smd rect
			(at -6.279896 1.240028 90)
			(size 0.508 2.0066)
			(layers "F.Cu" "F.Mask" "F.Paste")
			(net "PE_CLK100M_DR3_2_N")
		)
		(pad "E3" smd rect
			(at -5.48005 1.240028 90)
			(size 0.508 2.0066)
			(layers "F.Cu" "F.Mask" "F.Paste")
			(net "P3V3")
		)
		(pad "E4" smd rect
			(at -4.67995 1.240028 90)
			(size 0.508 2.0066)
			(layers "F.Cu" "F.Mask" "F.Paste")
			(net "SSD3_PERST_N")
		)
		(pad "E5" smd rect
			(at -3.880104 1.240028 90)
			(size 0.508 2.0066)
			(layers "F.Cu" "F.Mask" "F.Paste")
			(net "SSD3_PERST_N")
		)
		(pad "E6" smd rect
			(at -3.080004 1.240028 90)
			(size 0.508 2.0066)
			(layers "F.Cu" "F.Mask" "F.Paste")
			(net "Net_1179")
		)
		(pad "E7" smd rect
			(at -15.48003 -1.949958 90)
			(size 0.508 2.0066)
			(layers "F.Cu" "F.Mask" "F.Paste")
			(net "PE_CLK100M_DR3_1_P")
		)
		(pad "E8" smd rect
			(at -14.67993 -1.949958 90)
			(size 0.508 2.0066)
			(layers "F.Cu" "F.Mask" "F.Paste")
			(net "PE_CLK100M_DR3_1_N")
		)
		(pad "E9" smd rect
			(at -13.880084 -1.949958 90)
			(size 0.508 2.0066)
			(layers "F.Cu" "F.Mask" "F.Paste")
			(net "GND")
		)
		(pad "E10" smd rect
			(at -13.079984 -1.949958 90)
			(size 0.508 2.0066)
			(layers "F.Cu" "F.Mask" "F.Paste")
			(net "PE_TX1_DR3_N")
		)
		(pad "E11" smd rect
			(at -12.279884 -1.949958 90)
			(size 0.508 2.0066)
			(layers "F.Cu" "F.Mask" "F.Paste")
			(net "PE_TX1_DR3_P")
		)
		(pad "E12" smd rect
			(at -11.480038 -1.949958 90)
			(size 0.508 2.0066)
			(layers "F.Cu" "F.Mask" "F.Paste")
			(net "GND")
		)
		(pad "E13" smd rect
			(at -10.679938 -1.949958 90)
			(size 0.508 2.0066)
			(layers "F.Cu" "F.Mask" "F.Paste")
			(net "PE_RX1_DR3_N")
		)
		(pad "E14" smd rect
			(at -9.880092 -1.949958 90)
			(size 0.508 2.0066)
			(layers "F.Cu" "F.Mask" "F.Paste")
			(net "PE_RX1_DR3_P")
		)
		(pad "E15" smd rect
			(at -9.079992 -1.949958 90)
			(size 0.508 2.0066)
			(layers "F.Cu" "F.Mask" "F.Paste")
			(net "GND")
		)
		(pad "E16" smd rect
			(at -8.279892 -1.949958 90)
			(size 0.508 2.0066)
			(layers "F.Cu" "F.Mask" "F.Paste")
			(net "Net_1186")
		)
		(pad "E17" smd rect
			(at 9.320022 -1.949958 90)
			(size 0.508 2.0066)
			(layers "F.Cu" "F.Mask" "F.Paste")
			(net "PE_TX4_DR3_N")
		)
		(pad "E18" smd rect
			(at 10.120122 -1.949958 90)
			(size 0.508 2.0066)
			(layers "F.Cu" "F.Mask" "F.Paste")
			(net "PE_TX4_DR3_P")
		)
		(pad "E19" smd rect
			(at 10.919968 -1.949958 90)
			(size 0.508 2.0066)
			(layers "F.Cu" "F.Mask" "F.Paste")
			(net "GND")
		)
		(pad "E20" smd rect
			(at 11.720068 -1.949958 90)
			(size 0.508 2.0066)
			(layers "F.Cu" "F.Mask" "F.Paste")
			(net "PE_RX4_DR3_N")
		)
		(pad "E21" smd rect
			(at 12.519914 -1.949958 90)
			(size 0.508 2.0066)
			(layers "F.Cu" "F.Mask" "F.Paste")
			(net "PE_RX4_DR3_P")
		)
		(pad "E22" smd rect
			(at 13.320014 -1.949958 90)
			(size 0.508 2.0066)
			(layers "F.Cu" "F.Mask" "F.Paste")
			(net "GND")
		)
		(pad "E23" smd rect
			(at 14.120114 -1.949958 90)
			(size 0.508 2.0066)
			(layers "F.Cu" "F.Mask" "F.Paste")
			(net "SCL_DR3_R")
		)
		(pad "E24" smd rect
			(at 14.91996 -1.949958 90)
			(size 0.508 2.0066)
			(layers "F.Cu" "F.Mask" "F.Paste")
			(net "SDA_DR3_R")
		)
		(pad "E25" smd rect
			(at 15.72006 -1.949958 90)
			(size 0.508 2.0066)
			(layers "F.Cu" "F.Mask" "F.Paste")
			(net "DUALPORTEN#3")
		)
		(pad "P1" smd rect
			(at -1.905 0.824992 90)
			(size 0.6604 2.0574)
			(layers "F.Cu" "F.Mask" "F.Paste")
			(net "Net_1182")
		)
		(pad "P2" smd rect
			(at -0.635 0.824992 90)
			(size 0.6604 2.0574)
			(layers "F.Cu" "F.Mask" "F.Paste")
			(net "Net_1181")
		)
		(pad "P3" smd rect
			(at 0.635 0.824992 90)
			(size 0.6604 2.0574)
			(layers "F.Cu" "F.Mask" "F.Paste")
			(net "Net_1180")
		)
		(pad "P4" smd rect
			(at 1.905 0.824992 90)
			(size 0.6604 2.0574)
			(layers "F.Cu" "F.Mask" "F.Paste")
			(net "SSD3_CLK0_OE_N")
		)
		(pad "P5" smd rect
			(at 3.175 0.824992 90)
			(size 0.6604 2.0574)
			(layers "F.Cu" "F.Mask" "F.Paste")
			(net "GND")
		)
		(pad "P6" smd rect
			(at 4.445 0.824992 90)
			(size 0.6604 2.0574)
			(layers "F.Cu" "F.Mask" "F.Paste")
			(net "GND")
		)
		(pad "P7" smd rect
			(at 5.715 0.824992 90)
			(size 0.6604 2.0574)
			(layers "F.Cu" "F.Mask" "F.Paste")
			(net "Net_92")
		)
		(pad "P8" smd rect
			(at 6.985 0.824992 90)
			(size 0.6604 2.0574)
			(layers "F.Cu" "F.Mask" "F.Paste")
			(net "Net_64")
		)
		(pad "P9" smd rect
			(at 8.255 0.824992 90)
			(size 0.6604 2.0574)
			(layers "F.Cu" "F.Mask" "F.Paste")
			(net "Net_78")
		)
		(pad "P10" smd rect
			(at 9.525 0.824992 90)
			(size 0.6604 2.0574)
			(layers "F.Cu" "F.Mask" "F.Paste")
			(net "SSD_PRSNT_NET3")
		)
		(pad "P11" smd rect
			(at 10.795 0.824992 90)
			(size 0.6604 2.0574)
			(layers "F.Cu" "F.Mask" "F.Paste")
			(net "SSD_ACT_DR3")
		)
		(pad "P12" smd rect
			(at 12.065 0.824992 90)
			(size 0.6604 2.0574)
			(layers "F.Cu" "F.Mask" "F.Paste")
			(net "GND")
		)
		(pad "P13" smd rect
			(at 13.335 0.824992 90)
			(size 0.6604 2.0574)
			(layers "F.Cu" "F.Mask" "F.Paste")
			(net "12V_PRECH_SSD3")
		)
		(pad "P14" smd rect
			(at 14.605 0.824992 90)
			(size 0.6604 2.0574)
			(layers "F.Cu" "F.Mask" "F.Paste")
			(net "P12V_SSD3")
		)
		(pad "P15" smd rect
			(at 15.875 0.824992 90)
			(size 0.6604 2.0574)
			(layers "F.Cu" "F.Mask" "F.Paste")
			(net "P12V_SSD3")
		)
		(pad "PTH1" thru_hole oval
			(at -21.999956 2.350008 90)
			(size 1.524 2.6162)
			(drill oval 0.8128 1.905)
			(layers "*.Cu" "*.Mask")
			(remove_unused_layers no)
			(net "Net_1191")
			(clearance 0.1524)
			(thermal_gap 0.1524)
		)
		(pad "PTH2" thru_hole oval
			(at 21.999956 2.350008 90)
			(size 1.524 2.6162)
			(drill oval 0.8128 1.905)
			(layers "*.Cu" "*.Mask")
			(remove_unused_layers no)
			(net "Net_1175")
			(clearance 0.1524)
			(thermal_gap 0.1524)
		)
		(pad "S1" smd rect
			(at -15.875 0.824992 90)
			(size 0.6604 2.0574)
			(layers "F.Cu" "F.Mask" "F.Paste")
			(net "GND")
		)
		(pad "S2" smd rect
			(at -14.605 0.824992 90)
			(size 0.6604 2.0574)
			(layers "F.Cu" "F.Mask" "F.Paste")
			(net "Net_1190")
		)
		(pad "S3" smd rect
			(at -13.335 0.824992 90)
			(size 0.6604 2.0574)
			(layers "F.Cu" "F.Mask" "F.Paste")
			(net "Net_1189")
		)
		(pad "S4" smd rect
			(at -12.065 0.824992 90)
			(size 0.6604 2.0574)
			(layers "F.Cu" "F.Mask" "F.Paste")
			(net "GND")
		)
		(pad "S5" smd rect
			(at -10.795 0.824992 90)
			(size 0.6604 2.0574)
			(layers "F.Cu" "F.Mask" "F.Paste")
			(net "Net_1188")
		)
		(pad "S6" smd rect
			(at -9.525 0.824992 90)
			(size 0.6604 2.0574)
			(layers "F.Cu" "F.Mask" "F.Paste")
			(net "Net_1187")
		)
		(pad "S7" smd rect
			(at -8.255 0.824992 90)
			(size 0.6604 2.0574)
			(layers "F.Cu" "F.Mask" "F.Paste")
			(net "GND")
		)
		(pad "S8" smd rect
			(at -7.480046 -1.949958 90)
			(size 0.508 2.0066)
			(layers "F.Cu" "F.Mask" "F.Paste")
			(net "GND")
		)
		(pad "S9" smd rect
			(at -6.679946 -1.949958 90)
			(size 0.508 2.0066)
			(layers "F.Cu" "F.Mask" "F.Paste")
			(net "Net_1185")
		)
		(pad "S10" smd rect
			(at -5.8801 -1.949958 90)
			(size 0.508 2.0066)
			(layers "F.Cu" "F.Mask" "F.Paste")
			(net "Net_1184")
		)
		(pad "S11" smd rect
			(at -5.08 -1.949958 90)
			(size 0.508 2.0066)
			(layers "F.Cu" "F.Mask" "F.Paste")
			(net "GND")
		)
		(pad "S12" smd rect
			(at -4.2799 -1.949958 90)
			(size 0.508 2.0066)
			(layers "F.Cu" "F.Mask" "F.Paste")
			(net "Net_1183")
		)
		(pad "S13" smd rect
			(at -3.480054 -1.949958 90)
			(size 0.508 2.0066)
			(layers "F.Cu" "F.Mask" "F.Paste")
			(net "Net_1178")
		)
		(pad "S14" smd rect
			(at -2.679954 -1.949958 90)
			(size 0.508 2.0066)
			(layers "F.Cu" "F.Mask" "F.Paste")
			(net "GND")
		)
		(pad "S15" smd rect
			(at -1.880108 -1.949958 90)
			(size 0.508 2.0066)
			(layers "F.Cu" "F.Mask" "F.Paste")
			(net "Net_1177")
		)
		(pad "S16" smd rect
			(at -1.080008 -1.949958 90)
			(size 0.508 2.0066)
			(layers "F.Cu" "F.Mask" "F.Paste")
			(net "GND")
		)
		(pad "S17" smd rect
			(at -0.279908 -1.949958 90)
			(size 0.508 2.0066)
			(layers "F.Cu" "F.Mask" "F.Paste")
			(net "PE_TX2_DR3_N")
		)
		(pad "S18" smd rect
			(at 0.519938 -1.949958 90)
			(size 0.508 2.0066)
			(layers "F.Cu" "F.Mask" "F.Paste")
			(net "PE_TX2_DR3_P")
		)
		(pad "S19" smd rect
			(at 1.320038 -1.949958 90)
			(size 0.508 2.0066)
			(layers "F.Cu" "F.Mask" "F.Paste")
			(net "GND")
		)
		(pad "S20" smd rect
			(at 2.119884 -1.949958 90)
			(size 0.508 2.0066)
			(layers "F.Cu" "F.Mask" "F.Paste")
			(net "PE_RX2_DR3_N")
		)
		(pad "S21" smd rect
			(at 2.919984 -1.949958 90)
			(size 0.508 2.0066)
			(layers "F.Cu" "F.Mask" "F.Paste")
			(net "PE_RX2_DR3_P")
		)
		(pad "S22" smd rect
			(at 3.720084 -1.949958 90)
			(size 0.508 2.0066)
			(layers "F.Cu" "F.Mask" "F.Paste")
			(net "GND")
		)
		(pad "S23" smd rect
			(at 4.51993 -1.949958 90)
			(size 0.508 2.0066)
			(layers "F.Cu" "F.Mask" "F.Paste")
			(net "PE_TX3_DR3_N")
		)
		(pad "S24" smd rect
			(at 5.32003 -1.949958 90)
			(size 0.508 2.0066)
			(layers "F.Cu" "F.Mask" "F.Paste")
			(net "PE_TX3_DR3_P")
		)
		(pad "S25" smd rect
			(at 6.119876 -1.949958 90)
			(size 0.508 2.0066)
			(layers "F.Cu" "F.Mask" "F.Paste")
			(net "GND")
		)
		(pad "S26" smd rect
			(at 6.919976 -1.949958 90)
			(size 0.508 2.0066)
			(layers "F.Cu" "F.Mask" "F.Paste")
			(net "PE_RX3_DR3_N")
		)
		(pad "S27" smd rect
			(at 7.720076 -1.949958 90)
			(size 0.508 2.0066)
			(layers "F.Cu" "F.Mask" "F.Paste")
			(net "PE_RX3_DR3_P")
		)
		(pad "S28" smd rect
			(at 8.519922 -1.949958 90)
			(size 0.508 2.0066)
			(layers "F.Cu" "F.Mask" "F.Paste")
			(net "GND")
		)
		(zone
			(layers "F.Cu" "B.Cu" "In1.Cu" "In2.Cu" "In3.Cu" "In4.Cu" "In5.Cu" "In6.Cu")
			(hatch none 0.5)
			(connect_pads
				(clearance 0)
			)
			(min_thickness 0.25)
			(keepout
				(tracks not_allowed)
				(vias allowed)
				(pads allowed)
				(copperpour not_allowed)
				(footprints allowed)
			)
			(placement
				(enabled no)
				(sheetname "")
			)
			(fill
				(thermal_gap 0.5)
				(thermal_bridge_width 0.5)
				(island_removal_mode 0)
			)
			(polygon
				(pts
					(arc
						(start 227.381816 -189.669928)
						(mid 224.918016 -189.669928)
						(end 227.381816 -189.669928)
					)
				)
			)
		)
		(zone
			(layers "F.Cu" "B.Cu" "In1.Cu" "In2.Cu" "In3.Cu" "In4.Cu" "In5.Cu" "In6.Cu")
			(hatch none 0.5)
			(connect_pads
				(clearance 0)
			)
			(min_thickness 0.25)
			(keepout
				(tracks not_allowed)
				(vias allowed)
				(pads allowed)
				(copperpour not_allowed)
				(footprints allowed)
			)
			(placement
				(enabled no)
				(sheetname "")
			)
			(fill
				(thermal_gap 0.5)
				(thermal_bridge_width 0.5)
				(island_removal_mode 0)
			)
			(polygon
				(pts
					(arc
						(start 227.381816 -151.670004)
						(mid 224.918016 -151.670004)
						(end 227.381816 -151.670004)
					)
				)
			)
		)
	)
	(footprint ""
		(layer "F.Cu")
		(at 228.499924 -350.099884)
		(property "Reference" "LED1"
			(at 0 0 0)
			(layer "F.SilkS")
			(hide yes)
			(effects
				(font
					(size 1.27 1.27)
				)
			)
		)
		(property "Value" "LED-RB-4-GP"
			(at 5.88899 1.80848 0)
			(unlocked yes)
			(layer "F.Fab")
			(hide yes)
			(effects
				(font
					(size 1.016 1.016)
					(thickness 0.1524)
				)
			)
		)
		(property "Device Type" "LED1613-4PH20"
			(at 5.88899 0.28448 0)
			(unlocked yes)
			(layer "F.Fab")
			(hide yes)
			(effects
				(font
					(size 1.016 1.016)
					(thickness 0.1524)
				)
			)
		)
		(duplicate_pad_numbers_are_jumpers no)
		(fp_line
			(start -1.4478 -0.9652)
			(end 1.4478 -0.9652)
			(stroke
				(width 0.1524)
				(type default)
			)
			(layer "F.SilkS")
		)
		(fp_line
			(start -1.4478 0.9652)
			(end -1.4478 -0.9652)
			(stroke
				(width 0.1524)
				(type default)
			)
			(layer "F.SilkS")
		)
		(fp_line
			(start -1.4478 0.9652)
			(end -1.4478 -0.9652)
			(stroke
				(width 0.508)
				(type default)
			)
			(layer "F.SilkS")
		)
		(fp_line
			(start 1.4478 -0.9652)
			(end 1.4478 0.9652)
			(stroke
				(width 0.1524)
				(type default)
			)
			(layer "F.SilkS")
		)
		(fp_line
			(start 1.4478 0.9652)
			(end -1.4478 0.9652)
			(stroke
				(width 0.1524)
				(type default)
			)
			(layer "F.SilkS")
		)
		(fp_rect
			(start -0.8001 0.6477)
			(end 0.8001 -0.6477)
			(stroke
				(width 0)
				(type default)
			)
			(fill no)
			(layer "F.CrtYd")
		)
		(fp_poly
			(pts
				(xy -1.7018 1.2192) (xy -1.7018 -0.06223) (xy -0.8001 -0.06223) (xy -0.8001 0.6477) (xy 0.8001 0.6477)
				(xy 0.8001 -0.6477) (xy -0.8001 -0.6477) (xy -0.8001 -0.0635) (xy -1.7018 -0.0635) (xy -1.7018 -1.2192)
				(xy 1.7018 -1.2192) (xy 1.7018 1.2192)
			)
			(stroke
				(width 0)
				(type default)
			)
			(fill no)
			(layer "F.CrtYd")
		)
		(fp_rect
			(start -1.7018 1.2192)
			(end 1.7018 -1.2192)
			(stroke
				(width 0)
				(type default)
			)
			(fill no)
			(layer "F.Fab")
		)
		(pad "1" smd rect
			(at -0.73025 0.4064)
			(size 0.9144 0.6096)
			(layers "F.Cu" "F.Mask" "F.Paste")
			(net "SSD_ACT_DR1_MOS_N")
		)
		(pad "2" smd rect
			(at -0.73025 -0.4064)
			(size 0.9144 0.6096)
			(layers "F.Cu" "F.Mask" "F.Paste")
			(net "ATTN_LED_DR1_MOS_N")
		)
		(pad "3" smd rect
			(at 0.73025 -0.4064)
			(size 0.9144 0.6096)
			(layers "F.Cu" "F.Mask" "F.Paste")
			(net "DRV_ATTN_1")
		)
		(pad "4" smd rect
			(at 0.73025 0.4064)
			(size 0.9144 0.6096)
			(layers "F.Cu" "F.Mask" "F.Paste")
			(net "DRV_ACT_1")
		)
	)
	(footprint ""
		(layer "F.Cu")
		(at 76.2 -148.717)
		(property "Reference" "EU16"
			(at 0 0 0)
			(layer "F.SilkS")
			(hide yes)
			(effects
				(font
					(size 1.27 1.27)
				)
			)
		)
		(property "Value" "PCA9547BS-GP"
			(at 4.064 -5.5372 0)
			(unlocked yes)
			(layer "F.Fab")
			(hide yes)
			(effects
				(font
					(size 1.016 1.016)
					(thickness 0.1524)
				)
			)
		)
		(property "Device Type" "QFN24-G2D25H40"
			(at 4.064 -7.0612 0)
			(unlocked yes)
			(layer "F.Fab")
			(hide yes)
			(effects
				(font
					(size 1.016 1.016)
					(thickness 0.1524)
				)
			)
		)
		(duplicate_pad_numbers_are_jumpers no)
		(fp_line
			(start -3.5306 0.254)
			(end -2.7686 0.254)
			(stroke
				(width 0.1524)
				(type default)
			)
			(layer "F.SilkS")
		)
		(fp_line
			(start -3.0226 -3.0226)
			(end -1.7526 -3.0226)
			(stroke
				(width 0.1524)
				(type default)
			)
			(layer "F.SilkS")
		)
		(fp_line
			(start -3.0226 -1.7526)
			(end -3.0226 -3.0226)
			(stroke
				(width 0.1524)
				(type default)
			)
			(layer "F.SilkS")
		)
		(fp_line
			(start -3.0226 1.7526)
			(end -3.0226 3.0226)
			(stroke
				(width 0.1524)
				(type default)
			)
			(layer "F.SilkS")
		)
		(fp_line
			(start -3.0226 3.0226)
			(end -1.7526 3.0226)
			(stroke
				(width 0.1524)
				(type default)
			)
			(layer "F.SilkS")
		)
		(fp_line
			(start -0.7366 -2.794)
			(end -0.7366 -3.302)
			(stroke
				(width 0.1524)
				(type default)
			)
			(layer "F.SilkS")
		)
		(fp_line
			(start -0.254 3.302)
			(end -0.254 2.794)
			(stroke
				(width 0.1524)
				(type default)
			)
			(layer "F.SilkS")
		)
		(fp_line
			(start 1.7526 3.0226)
			(end 3.0226 3.0226)
			(stroke
				(width 0.1524)
				(type default)
			)
			(layer "F.SilkS")
		)
		(fp_line
			(start 2.8194 0.762)
			(end 3.5814 0.762)
			(stroke
				(width 0.1524)
				(type default)
			)
			(layer "F.SilkS")
		)
		(fp_line
			(start 3.0226 3.0226)
			(end 3.0226 1.7526)
			(stroke
				(width 0.1524)
				(type default)
			)
			(layer "F.SilkS")
		)
		(fp_poly
			(pts
				(xy 1.7526 -3.0226) (xy 3.0226 -1.7526) (xy 3.0226 -3.0226)
			)
			(stroke
				(width 0)
				(type default)
			)
			(fill yes)
			(layer "F.SilkS")
		)
		(fp_rect
			(start -2.0066 2.0066)
			(end 2.0066 -2.0066)
			(stroke
				(width 0)
				(type default)
			)
			(fill no)
			(layer "F.CrtYd")
		)
		(fp_poly
			(pts
				(xy -2.0066 -2.0066) (xy -2.0066 -3.0226) (xy -3.0226 -3.0226) (xy -3.0226 3.0226) (xy 3.0226 3.0226)
				(xy 3.0226 -3.0226) (xy -2.00152 -3.0226) (xy -2.00152 -2.0066) (xy 2.0066 -2.0066) (xy 2.0066 2.0066)
				(xy -2.0066 2.0066)
			)
			(stroke
				(width 0)
				(type default)
			)
			(fill no)
			(layer "F.CrtYd")
		)
		(fp_rect
			(start -3.0226 3.0226)
			(end 3.0226 -3.0226)
			(stroke
				(width 0)
				(type default)
			)
			(fill no)
			(layer "F.Fab")
		)
		(pad "1" smd rect
			(at 1.249934 -2.0574)
			(size 0.3048 0.9144)
			(layers "F.Cu" "F.Mask" "F.Paste")
			(net "SDA_DR3")
		)
		(pad "2" smd rect
			(at 0.750062 -1.9812)
			(size 0.3048 1.0668)
			(layers "F.Cu" "F.Mask" "F.Paste")
			(net "SCL_DR3")
		)
		(pad "3" smd rect
			(at 0.249936 -1.9812)
			(size 0.3048 1.0668)
			(layers "F.Cu" "F.Mask" "F.Paste")
			(net "SDA_DR4")
		)
		(pad "4" smd rect
			(at -0.249936 -1.9812)
			(size 0.3048 1.0668)
			(layers "F.Cu" "F.Mask" "F.Paste")
			(net "SCL_DR4")
		)
		(pad "5" smd rect
			(at -0.750062 -1.9812)
			(size 0.3048 1.0668)
			(layers "F.Cu" "F.Mask" "F.Paste")
			(net "SDA_DR12")
		)
		(pad "6" smd rect
			(at -1.249934 -2.0574)
			(size 0.3048 0.9144)
			(layers "F.Cu" "F.Mask" "F.Paste")
			(net "SCL_DR12")
		)
		(pad "7" smd rect
			(at -2.0574 -1.249934)
			(size 0.9144 0.3048)
			(layers "F.Cu" "F.Mask" "F.Paste")
			(net "SDA_DR8")
		)
		(pad "8" smd rect
			(at -1.9812 -0.750062)
			(size 1.0668 0.3048)
			(layers "F.Cu" "F.Mask" "F.Paste")
			(net "SCL_DR8")
		)
		(pad "9" smd rect
			(at -1.9812 -0.249936)
			(size 1.0668 0.3048)
			(layers "F.Cu" "F.Mask" "F.Paste")
			(net "GND")
		)
		(pad "10" smd rect
			(at -1.9812 0.249936)
			(size 1.0668 0.3048)
			(layers "F.Cu" "F.Mask" "F.Paste")
			(net "SDA_DR13")
		)
		(pad "11" smd rect
			(at -1.9812 0.750062)
			(size 1.0668 0.3048)
			(layers "F.Cu" "F.Mask" "F.Paste")
			(net "SCL_DR13")
		)
		(pad "12" smd rect
			(at -2.0574 1.249934)
			(size 0.9144 0.3048)
			(layers "F.Cu" "F.Mask" "F.Paste")
			(net "SDA_DR9")
		)
		(pad "13" smd rect
			(at -1.249934 2.0574)
			(size 0.3048 0.9144)
			(layers "F.Cu" "F.Mask" "F.Paste")
			(net "SCL_DR9")
		)
		(pad "14" smd rect
			(at -0.750062 1.9812)
			(size 0.3048 1.0668)
			(layers "F.Cu" "F.Mask" "F.Paste")
			(net "SDA_DR14")
		)
		(pad "15" smd rect
			(at -0.249936 1.9812)
			(size 0.3048 1.0668)
			(layers "F.Cu" "F.Mask" "F.Paste")
			(net "SCL_DR14")
		)
		(pad "16" smd rect
			(at 0.249936 1.9812)
			(size 0.3048 1.0668)
			(layers "F.Cu" "F.Mask" "F.Paste")
			(net "Net_419")
		)
		(pad "17" smd rect
			(at 0.750062 1.9812)
			(size 0.3048 1.0668)
			(layers "F.Cu" "F.Mask" "F.Paste")
			(net "Net_418")
		)
		(pad "18" smd rect
			(at 1.249934 2.0574)
			(size 0.3048 0.9144)
			(layers "F.Cu" "F.Mask" "F.Paste")
			(net "I2C_SW_EU16_ADDRESS_A2")
		)
		(pad "19" smd rect
			(at 2.0574 1.249934)
			(size 0.9144 0.3048)
			(layers "F.Cu" "F.Mask" "F.Paste")
			(net "I2C8_SCL_R_SW_EU16")
		)
		(pad "20" smd rect
			(at 1.9812 0.750062)
			(size 1.0668 0.3048)
			(layers "F.Cu" "F.Mask" "F.Paste")
			(net "I2C8_SDA_R_SW_EU16")
		)
		(pad "21" smd rect
			(at 1.9812 0.249936)
			(size 1.0668 0.3048)
			(layers "F.Cu" "F.Mask" "F.Paste")
			(net "P3V3")
		)
		(pad "22" smd rect
			(at 1.9812 -0.249936)
			(size 1.0668 0.3048)
			(layers "F.Cu" "F.Mask" "F.Paste")
			(net "I2C_SW_EU16_ADDRESS_A0")
		)
		(pad "23" smd rect
			(at 1.9812 -0.750062)
			(size 1.0668 0.3048)
			(layers "F.Cu" "F.Mask" "F.Paste")
			(net "I2C_SW_EU16_ADDRESS_A1")
		)
		(pad "24" smd rect
			(at 2.0574 -1.249934)
			(size 0.9144 0.3048)
			(layers "F.Cu" "F.Mask" "F.Paste")
			(net "I2C_MUX_RESET_R_EU16")
		)
		(pad "25" smd rect
			(at 0 0)
			(size 2.2606 2.2606)
			(layers "F.Cu" "F.Mask" "F.Paste")
			(net "GND")
		)
	)
	(footprint ""
		(layer "F.Cu")
		(at 24.003 -51.054 -90)
		(property "Reference" "R9906"
			(at 0 0 270)
			(layer "F.SilkS")
			(hide yes)
			(effects
				(font
					(size 1.27 1.27)
				)
			)
		)
		(property "Value" "1K82R2F-1-GP"
			(at 0.064008 -3.993896 270)
			(unlocked yes)
			(layer "F.Fab")
			(hide yes)
			(effects
				(font
					(size 1.016 1.016)
					(thickness 0.1524)
				)
			)
		)
		(property "Device Type" "R402H16"
			(at 0.064008 -5.517896 270)
			(unlocked yes)
			(layer "F.Fab")
			(hide yes)
			(effects
				(font
					(size 1.016 1.016)
					(thickness 0.1524)
				)
			)
		)
		(duplicate_pad_numbers_are_jumpers no)
		(fp_line
			(start -0.508 -0.9398)
			(end -0.508 0.9398)
			(stroke
				(width 0.1524)
				(type default)
			)
			(layer "F.SilkS")
		)
		(fp_line
			(start 0.508 -0.9398)
			(end -0.508 -0.9398)
			(stroke
				(width 0.1524)
				(type default)
			)
			(layer "F.SilkS")
		)
		(fp_rect
			(start -0.508 0.9398)
			(end 0.508 -0.9398)
			(stroke
				(width 0)
				(type default)
			)
			(fill no)
			(layer "F.CrtYd")
		)
		(fp_rect
			(start -0.508 0.9398)
			(end 0.508 -0.9398)
			(stroke
				(width 0)
				(type default)
			)
			(fill no)
			(layer "F.Fab")
		)
		(pad "1" smd custom
			(at 0 -0.4445 270)
			(size 0.1397 0.1397)
			(layers "F.Cu" "F.Mask" "F.Paste")
			(net "P12V")
			(options
				(clearance outline)
				(anchor circle)
			)
			(primitives
				(gr_poly
					(pts
						(arc
							(start -0.1778 -0.2794)
							(mid -0.249642 -0.249642)
							(end -0.2794 -0.1778)
						)
						(arc
							(start -0.2794 0.1778)
							(mid -0.249642 0.249642)
							(end -0.1778 0.2794)
						)
						(arc
							(start 0.1778 0.2794)
							(mid 0.249642 0.249642)
							(end 0.2794 0.1778)
						)
						(arc
							(start 0.2794 -0.1778)
							(mid 0.249642 -0.249642)
							(end 0.1778 -0.2794)
						)
					)
					(width 0)
					(fill yes)
				)
			)
		)
		(pad "2" smd custom
			(at 0 0.4445 270)
			(size 0.1397 0.1397)
			(layers "F.Cu" "F.Mask" "F.Paste")
			(net "DRV_ACT_14")
			(options
				(clearance outline)
				(anchor circle)
			)
			(primitives
				(gr_poly
					(pts
						(arc
							(start -0.1778 -0.2794)
							(mid -0.249642 -0.249642)
							(end -0.2794 -0.1778)
						)
						(arc
							(start -0.2794 0.1778)
							(mid -0.249642 0.249642)
							(end -0.1778 0.2794)
						)
						(arc
							(start 0.1778 0.2794)
							(mid 0.249642 0.249642)
							(end 0.2794 0.1778)
						)
						(arc
							(start 0.2794 -0.1778)
							(mid 0.249642 -0.249642)
							(end 0.1778 -0.2794)
						)
					)
					(width 0)
					(fill yes)
				)
			)
		)
	)
	(footprint ""
		(layer "F.Cu")
		(at 219.964 -400.685 180)
		(property "Reference" "PC1237"
			(at 0 0 180)
			(layer "F.SilkS")
			(hide yes)
			(effects
				(font
					(size 1.27 1.27)
				)
			)
		)
		(property "Value" "SCD1U50V3KX-GP"
			(at 0 -2.8194 180)
			(unlocked yes)
			(layer "F.Fab")
			(hide yes)
			(effects
				(font
					(size 1.016 1.016)
					(thickness 0.1524)
				)
			)
		)
		(property "Device Type" "C603H36"
			(at 0 -4.3434 180)
			(unlocked yes)
			(layer "F.Fab")
			(hide yes)
			(effects
				(font
					(size 1.016 1.016)
					(thickness 0.1524)
				)
			)
		)
		(duplicate_pad_numbers_are_jumpers no)
		(fp_line
			(start 0.508 0)
			(end -0.508 0)
			(stroke
				(width 0.2032)
				(type default)
			)
			(layer "F.SilkS")
		)
		(fp_rect
			(start -0.5842 1.3335)
			(end 0.5842 -1.3335)
			(stroke
				(width 0)
				(type default)
			)
			(fill no)
			(layer "F.CrtYd")
		)
		(fp_rect
			(start -0.5842 1.3335)
			(end 0.5842 -1.3335)
			(stroke
				(width 0)
				(type default)
			)
			(fill no)
			(layer "F.Fab")
		)
		(pad "1" smd custom
			(at 0 -0.762 180)
			(size 0.2159 0.2159)
			(layers "F.Cu" "F.Mask" "F.Paste")
			(net "P12V_SSD1")
			(options
				(clearance outline)
				(anchor circle)
			)
			(primitives
				(gr_poly
					(pts
						(arc
							(start -0.3302 -0.4318)
							(mid -0.402042 -0.402042)
							(end -0.4318 -0.3302)
						)
						(arc
							(start -0.4318 0.3302)
							(mid -0.402042 0.402042)
							(end -0.3302 0.4318)
						)
						(arc
							(start 0.3302 0.4318)
							(mid 0.402042 0.402042)
							(end 0.4318 0.3302)
						)
						(arc
							(start 0.4318 -0.3302)
							(mid 0.402042 -0.402042)
							(end 0.3302 -0.4318)
						)
					)
					(width 0)
					(fill yes)
				)
			)
		)
		(pad "2" smd custom
			(at 0 0.762 180)
			(size 0.2159 0.2159)
			(layers "F.Cu" "F.Mask" "F.Paste")
			(net "GND")
			(options
				(clearance outline)
				(anchor circle)
			)
			(primitives
				(gr_poly
					(pts
						(arc
							(start -0.3302 -0.4318)
							(mid -0.402042 -0.402042)
							(end -0.4318 -0.3302)
						)
						(arc
							(start -0.4318 0.3302)
							(mid -0.402042 0.402042)
							(end -0.3302 0.4318)
						)
						(arc
							(start 0.3302 0.4318)
							(mid 0.402042 0.402042)
							(end 0.4318 0.3302)
						)
						(arc
							(start 0.4318 -0.3302)
							(mid 0.402042 -0.402042)
							(end 0.3302 -0.4318)
						)
					)
					(width 0)
					(fill yes)
				)
			)
		)
	)
	(footprint ""
		(layer "F.Cu")
		(at 97.028 -290.195 -90)
		(property "Reference" "R9402"
			(at 0 0 270)
			(layer "F.SilkS")
			(hide yes)
			(effects
				(font
					(size 1.27 1.27)
				)
			)
		)
		(property "Value" "4K7R2J-2-GP"
			(at 0.064008 -3.993896 270)
			(unlocked yes)
			(layer "F.Fab")
			(hide yes)
			(effects
				(font
					(size 1.016 1.016)
					(thickness 0.1524)
				)
			)
		)
		(property "Device Type" "R402H16"
			(at 0.064008 -5.517896 270)
			(unlocked yes)
			(layer "F.Fab")
			(hide yes)
			(effects
				(font
					(size 1.016 1.016)
					(thickness 0.1524)
				)
			)
		)
		(duplicate_pad_numbers_are_jumpers no)
		(fp_line
			(start -0.508 -0.9398)
			(end -0.508 0.9398)
			(stroke
				(width 0.1524)
				(type default)
			)
			(layer "F.SilkS")
		)
		(fp_line
			(start 0.508 -0.9398)
			(end -0.508 -0.9398)
			(stroke
				(width 0.1524)
				(type default)
			)
			(layer "F.SilkS")
		)
		(fp_rect
			(start -0.508 0.9398)
			(end 0.508 -0.9398)
			(stroke
				(width 0)
				(type default)
			)
			(fill no)
			(layer "F.CrtYd")
		)
		(fp_rect
			(start -0.508 0.9398)
			(end 0.508 -0.9398)
			(stroke
				(width 0)
				(type default)
			)
			(fill no)
			(layer "F.Fab")
		)
		(pad "1" smd custom
			(at 0 -0.4445 270)
			(size 0.1397 0.1397)
			(layers "F.Cu" "F.Mask" "F.Paste")
			(net "P3V3")
			(options
				(clearance outline)
				(anchor circle)
			)
			(primitives
				(gr_poly
					(pts
						(arc
							(start -0.1778 -0.2794)
							(mid -0.249642 -0.249642)
							(end -0.2794 -0.1778)
						)
						(arc
							(start -0.2794 0.1778)
							(mid -0.249642 0.249642)
							(end -0.1778 0.2794)
						)
						(arc
							(start 0.1778 0.2794)
							(mid 0.249642 0.249642)
							(end 0.2794 0.1778)
						)
						(arc
							(start 0.2794 -0.1778)
							(mid 0.249642 -0.249642)
							(end 0.1778 -0.2794)
						)
					)
					(width 0)
					(fill yes)
				)
			)
		)
		(pad "2" smd custom
			(at 0 0.4445 270)
			(size 0.1397 0.1397)
			(layers "F.Cu" "F.Mask" "F.Paste")
			(net "SSD_PRSNT_NET2")
			(options
				(clearance outline)
				(anchor circle)
			)
			(primitives
				(gr_poly
					(pts
						(arc
							(start -0.1778 -0.2794)
							(mid -0.249642 -0.249642)
							(end -0.2794 -0.1778)
						)
						(arc
							(start -0.2794 0.1778)
							(mid -0.249642 0.249642)
							(end -0.1778 0.2794)
						)
						(arc
							(start 0.1778 0.2794)
							(mid 0.249642 0.249642)
							(end 0.2794 0.1778)
						)
						(arc
							(start 0.2794 -0.1778)
							(mid 0.249642 -0.249642)
							(end 0.1778 -0.2794)
						)
					)
					(width 0)
					(fill yes)
				)
			)
		)
	)
	(footprint ""
		(layer "F.Cu")
		(at 86.487 -219.456 180)
		(property "Reference" "R9089"
			(at 0 0 180)
			(layer "F.SilkS")
			(hide yes)
			(effects
				(font
					(size 1.27 1.27)
				)
			)
		)
		(property "Value" "27R2F-GP"
			(at 0.064008 -3.993896 180)
			(unlocked yes)
			(layer "F.Fab")
			(hide yes)
			(effects
				(font
					(size 1.016 1.016)
					(thickness 0.1524)
				)
			)
		)
		(property "Device Type" "R402H16"
			(at 0.064008 -5.517896 180)
			(unlocked yes)
			(layer "F.Fab")
			(hide yes)
			(effects
				(font
					(size 1.016 1.016)
					(thickness 0.1524)
				)
			)
		)
		(duplicate_pad_numbers_are_jumpers no)
		(fp_line
			(start 0.508 -0.9398)
			(end -0.508 -0.9398)
			(stroke
				(width 0.1524)
				(type default)
			)
			(layer "F.SilkS")
		)
		(fp_line
			(start -0.508 -0.9398)
			(end -0.508 0.9398)
			(stroke
				(width 0.1524)
				(type default)
			)
			(layer "F.SilkS")
		)
		(fp_rect
			(start -0.508 0.9398)
			(end 0.508 -0.9398)
			(stroke
				(width 0)
				(type default)
			)
			(fill no)
			(layer "F.CrtYd")
		)
		(fp_rect
			(start -0.508 0.9398)
			(end 0.508 -0.9398)
			(stroke
				(width 0)
				(type default)
			)
			(fill no)
			(layer "F.Fab")
		)
		(pad "1" smd custom
			(at 0 -0.4445 180)
			(size 0.1397 0.1397)
			(layers "F.Cu" "F.Mask" "F.Paste")
			(net "PE_CLK_100M_DR12_1_R_N")
			(options
				(clearance outline)
				(anchor circle)
			)
			(primitives
				(gr_poly
					(pts
						(arc
							(start -0.1778 -0.2794)
							(mid -0.249642 -0.249642)
							(end -0.2794 -0.1778)
						)
						(arc
							(start -0.2794 0.1778)
							(mid -0.249642 0.249642)
							(end -0.1778 0.2794)
						)
						(arc
							(start 0.1778 0.2794)
							(mid 0.249642 0.249642)
							(end 0.2794 0.1778)
						)
						(arc
							(start 0.2794 -0.1778)
							(mid 0.249642 -0.249642)
							(end 0.1778 -0.2794)
						)
					)
					(width 0)
					(fill yes)
				)
			)
		)
		(pad "2" smd custom
			(at 0 0.4445 180)
			(size 0.1397 0.1397)
			(layers "F.Cu" "F.Mask" "F.Paste")
			(net "PE_CLK100M_DR12_1_N")
			(options
				(clearance outline)
				(anchor circle)
			)
			(primitives
				(gr_poly
					(pts
						(arc
							(start -0.1778 -0.2794)
							(mid -0.249642 -0.249642)
							(end -0.2794 -0.1778)
						)
						(arc
							(start -0.2794 0.1778)
							(mid -0.249642 0.249642)
							(end -0.1778 0.2794)
						)
						(arc
							(start 0.1778 0.2794)
							(mid 0.249642 0.249642)
							(end 0.2794 0.1778)
						)
						(arc
							(start 0.2794 -0.1778)
							(mid 0.249642 -0.249642)
							(end 0.1778 -0.2794)
						)
					)
					(width 0)
					(fill yes)
				)
			)
		)
	)
	(footprint ""
		(layer "F.Cu")
		(at 62.6364 -449.5546 -90)
		(property "Reference" "SR1131"
			(at 0 0 270)
			(layer "F.SilkS")
			(hide yes)
			(effects
				(font
					(size 1.27 1.27)
				)
			)
		)
		(property "Value" "4K7R2F-GP"
			(at 0.064008 -3.993896 270)
			(unlocked yes)
			(layer "F.Fab")
			(hide yes)
			(effects
				(font
					(size 1.016 1.016)
					(thickness 0.1524)
				)
			)
		)
		(property "Device Type" "R402H16"
			(at 0.064008 -5.517896 270)
			(unlocked yes)
			(layer "F.Fab")
			(hide yes)
			(effects
				(font
					(size 1.016 1.016)
					(thickness 0.1524)
				)
			)
		)
		(duplicate_pad_numbers_are_jumpers no)
		(fp_line
			(start -0.508 -0.9398)
			(end -0.508 0.9398)
			(stroke
				(width 0.1524)
				(type default)
			)
			(layer "F.SilkS")
		)
		(fp_line
			(start 0.508 -0.9398)
			(end -0.508 -0.9398)
			(stroke
				(width 0.1524)
				(type default)
			)
			(layer "F.SilkS")
		)
		(fp_rect
			(start -0.508 0.9398)
			(end 0.508 -0.9398)
			(stroke
				(width 0)
				(type default)
			)
			(fill no)
			(layer "F.CrtYd")
		)
		(fp_rect
			(start -0.508 0.9398)
			(end 0.508 -0.9398)
			(stroke
				(width 0)
				(type default)
			)
			(fill no)
			(layer "F.Fab")
		)
		(pad "1" smd custom
			(at 0 -0.4445 270)
			(size 0.1397 0.1397)
			(layers "F.Cu" "F.Mask" "F.Paste")
			(net "P3V3")
			(options
				(clearance outline)
				(anchor circle)
			)
			(primitives
				(gr_poly
					(pts
						(arc
							(start -0.1778 -0.2794)
							(mid -0.249642 -0.249642)
							(end -0.2794 -0.1778)
						)
						(arc
							(start -0.2794 0.1778)
							(mid -0.249642 0.249642)
							(end -0.1778 0.2794)
						)
						(arc
							(start 0.1778 0.2794)
							(mid 0.249642 0.249642)
							(end 0.2794 0.1778)
						)
						(arc
							(start 0.2794 -0.1778)
							(mid 0.249642 -0.249642)
							(end 0.1778 -0.2794)
						)
					)
					(width 0)
					(fill yes)
				)
			)
		)
		(pad "2" smd custom
			(at 0 0.4445 270)
			(size 0.1397 0.1397)
			(layers "F.Cu" "F.Mask" "F.Paste")
			(net "SSD5_CLK0_OE_MOS_N")
			(options
				(clearance outline)
				(anchor circle)
			)
			(primitives
				(gr_poly
					(pts
						(arc
							(start -0.1778 -0.2794)
							(mid -0.249642 -0.249642)
							(end -0.2794 -0.1778)
						)
						(arc
							(start -0.2794 0.1778)
							(mid -0.249642 0.249642)
							(end -0.1778 0.2794)
						)
						(arc
							(start 0.1778 0.2794)
							(mid 0.249642 0.249642)
							(end 0.2794 0.1778)
						)
						(arc
							(start 0.2794 -0.1778)
							(mid 0.249642 -0.249642)
							(end 0.1778 -0.2794)
						)
					)
					(width 0)
					(fill yes)
				)
			)
		)
	)
	(footprint ""
		(layer "F.Cu")
		(at 214.5284 -290.5506)
		(property "Reference" "SR1095"
			(at 0 0 0)
			(layer "F.SilkS")
			(hide yes)
			(effects
				(font
					(size 1.27 1.27)
				)
			)
		)
		(property "Value" "4K7R2F-GP"
			(at 0.064008 -3.993896 0)
			(unlocked yes)
			(layer "F.Fab")
			(hide yes)
			(effects
				(font
					(size 1.016 1.016)
					(thickness 0.1524)
				)
			)
		)
		(property "Device Type" "R402H16"
			(at 0.064008 -5.517896 0)
			(unlocked yes)
			(layer "F.Fab")
			(hide yes)
			(effects
				(font
					(size 1.016 1.016)
					(thickness 0.1524)
				)
			)
		)
		(duplicate_pad_numbers_are_jumpers no)
		(fp_line
			(start -0.508 -0.9398)
			(end -0.508 0.9398)
			(stroke
				(width 0.1524)
				(type default)
			)
			(layer "F.SilkS")
		)
		(fp_line
			(start 0.508 -0.9398)
			(end -0.508 -0.9398)
			(stroke
				(width 0.1524)
				(type default)
			)
			(layer "F.SilkS")
		)
		(fp_rect
			(start -0.508 0.9398)
			(end 0.508 -0.9398)
			(stroke
				(width 0)
				(type default)
			)
			(fill no)
			(layer "F.CrtYd")
		)
		(fp_rect
			(start -0.508 0.9398)
			(end 0.508 -0.9398)
			(stroke
				(width 0)
				(type default)
			)
			(fill no)
			(layer "F.Fab")
		)
		(pad "1" smd custom
			(at 0 -0.4445)
			(size 0.1397 0.1397)
			(layers "F.Cu" "F.Mask" "F.Paste")
			(net "P3V3")
			(options
				(clearance outline)
				(anchor circle)
			)
			(primitives
				(gr_poly
					(pts
						(arc
							(start -0.1778 -0.2794)
							(mid -0.249642 -0.249642)
							(end -0.2794 -0.1778)
						)
						(arc
							(start -0.2794 0.1778)
							(mid -0.249642 0.249642)
							(end -0.1778 0.2794)
						)
						(arc
							(start 0.1778 0.2794)
							(mid 0.249642 0.249642)
							(end 0.2794 0.1778)
						)
						(arc
							(start 0.2794 -0.1778)
							(mid 0.249642 -0.249642)
							(end 0.1778 -0.2794)
						)
					)
					(width 0)
					(fill yes)
				)
			)
		)
		(pad "2" smd custom
			(at 0 0.4445)
			(size 0.1397 0.1397)
			(layers "F.Cu" "F.Mask" "F.Paste")
			(net "DUALPORTEN#2")
			(options
				(clearance outline)
				(anchor circle)
			)
			(primitives
				(gr_poly
					(pts
						(arc
							(start -0.1778 -0.2794)
							(mid -0.249642 -0.249642)
							(end -0.2794 -0.1778)
						)
						(arc
							(start -0.2794 0.1778)
							(mid -0.249642 0.249642)
							(end -0.1778 0.2794)
						)
						(arc
							(start 0.1778 0.2794)
							(mid 0.249642 0.249642)
							(end 0.2794 0.1778)
						)
						(arc
							(start 0.2794 -0.1778)
							(mid 0.249642 -0.249642)
							(end 0.1778 -0.2794)
						)
					)
					(width 0)
					(fill yes)
				)
			)
		)
	)
	(footprint ""
		(layer "F.Cu")
		(at 226.149916 -67.669918 90)
		(property "Reference" "J4"
			(at 0 0 90)
			(layer "F.SilkS")
			(hide yes)
			(effects
				(font
					(size 1.27 1.27)
				)
			)
		)
		(property "Value" "PCISLT68-14-GP-U1"
			(at -22.225 12.7508 90)
			(unlocked yes)
			(layer "F.Fab")
			(hide yes)
			(effects
				(font
					(size 1.016 1.016)
					(thickness 0.1524)
				)
			)
		)
		(property "Device Type" "SD-78827-0001"
			(at -22.225 11.2268 90)
			(unlocked yes)
			(layer "F.Fab")
			(hide yes)
			(effects
				(font
					(size 1.016 1.016)
					(thickness 0.1524)
				)
			)
		)
		(duplicate_pad_numbers_are_jumpers no)
		(fp_line
			(start 20.4724 -3.4036)
			(end 20.4724 0.0254)
			(stroke
				(width 0.1524)
				(type default)
			)
			(layer "F.SilkS")
		)
		(fp_line
			(start -20.4724 -3.4036)
			(end 20.4724 -3.4036)
			(stroke
				(width 0.1524)
				(type default)
			)
			(layer "F.SilkS")
		)
		(fp_line
			(start 23.749 0.0254)
			(end 23.749 4.6736)
			(stroke
				(width 0.1524)
				(type default)
			)
			(layer "F.SilkS")
		)
		(fp_line
			(start 20.4724 0.0254)
			(end 23.749 0.0254)
			(stroke
				(width 0.1524)
				(type default)
			)
			(layer "F.SilkS")
		)
		(fp_line
			(start -20.4724 0.0254)
			(end -20.4724 -3.4036)
			(stroke
				(width 0.1524)
				(type default)
			)
			(layer "F.SilkS")
		)
		(fp_line
			(start -23.749 0.0254)
			(end -20.4724 0.0254)
			(stroke
				(width 0.1524)
				(type default)
			)
			(layer "F.SilkS")
		)
		(fp_line
			(start 23.117556 1.803908)
			(end 23.117556 2.896108)
			(stroke
				(width 0.3048)
				(type default)
			)
			(layer "F.SilkS")
		)
		(fp_line
			(start -20.882356 1.803908)
			(end -20.882356 2.896108)
			(stroke
				(width 0.3048)
				(type default)
			)
			(layer "F.SilkS")
		)
		(fp_line
			(start 20.882356 2.896108)
			(end 20.882356 1.803908)
			(stroke
				(width 0.3048)
				(type default)
			)
			(layer "F.SilkS")
		)
		(fp_line
			(start -23.117556 2.896108)
			(end -23.117556 1.803908)
			(stroke
				(width 0.3048)
				(type default)
			)
			(layer "F.SilkS")
		)
		(fp_line
			(start 23.749 4.6736)
			(end 20.4724 4.6736)
			(stroke
				(width 0.1524)
				(type default)
			)
			(layer "F.SilkS")
		)
		(fp_line
			(start 20.4724 4.6736)
			(end 20.4724 12.0142)
			(stroke
				(width 0.1524)
				(type default)
			)
			(layer "F.SilkS")
		)
		(fp_line
			(start -20.4724 4.6736)
			(end -23.749 4.6736)
			(stroke
				(width 0.1524)
				(type default)
			)
			(layer "F.SilkS")
		)
		(fp_line
			(start -23.749 4.6736)
			(end -23.749 0.0254)
			(stroke
				(width 0.1524)
				(type default)
			)
			(layer "F.SilkS")
		)
		(fp_line
			(start 17.8435 10.3124)
			(end -17.8435 10.3124)
			(stroke
				(width 0.1524)
				(type default)
			)
			(layer "F.SilkS")
		)
		(fp_line
			(start -17.8435 10.3124)
			(end -17.8435 12.0142)
			(stroke
				(width 0.1524)
				(type default)
			)
			(layer "F.SilkS")
		)
		(fp_line
			(start 20.4724 12.0142)
			(end 17.8435 12.0142)
			(stroke
				(width 0.1524)
				(type default)
			)
			(layer "F.SilkS")
		)
		(fp_line
			(start 17.8435 12.0142)
			(end 17.8435 10.3124)
			(stroke
				(width 0.1524)
				(type default)
			)
			(layer "F.SilkS")
		)
		(fp_line
			(start -17.8435 12.0142)
			(end -20.4724 12.0142)
			(stroke
				(width 0.1524)
				(type default)
			)
			(layer "F.SilkS")
		)
		(fp_line
			(start -20.4724 12.0142)
			(end -20.4724 4.6736)
			(stroke
				(width 0.1524)
				(type default)
			)
			(layer "F.SilkS")
		)
		(fp_arc
			(start 20.882356 1.803908)
			(mid 21.999956 0.686308)
			(end 23.117556 1.803908)
			(stroke
				(width 0.3048)
				(type default)
			)
			(layer "F.SilkS")
		)
		(fp_arc
			(start -23.117556 1.803908)
			(mid -21.999956 0.686308)
			(end -20.882356 1.803908)
			(stroke
				(width 0.3048)
				(type default)
			)
			(layer "F.SilkS")
		)
		(fp_arc
			(start 23.117556 2.896108)
			(mid 21.999956 4.013708)
			(end 20.882356 2.896108)
			(stroke
				(width 0.3048)
				(type default)
			)
			(layer "F.SilkS")
		)
		(fp_arc
			(start -20.882356 2.896108)
			(mid -21.999956 4.013708)
			(end -23.117556 2.896108)
			(stroke
				(width 0.3048)
				(type default)
			)
			(layer "F.SilkS")
		)
		(fp_poly
			(pts
				(xy -20.2184 11.7602) (xy -20.2184 4.4196) (xy -23.495 4.4196) (xy -23.495 0.2794) (xy -20.2184 0.2794)
				(xy -20.2184 -3.1496) (xy 20.2184 -3.1496) (xy 20.2184 0.2794) (xy 23.495 0.2794) (xy 23.495 4.4196)
				(xy 20.2184 4.4196) (xy 20.2184 11.7602) (xy 18.0975 11.7602) (xy 18.0975 10.0584) (xy -18.0975 10.0584)
				(xy -18.0975 11.7602)
			)
			(stroke
				(width 0)
				(type default)
			)
			(fill no)
			(layer "F.CrtYd")
		)
		(fp_poly
			(pts
				(xy -21.2471 16.256) (xy -21.2471 4.9276) (xy -24.003 4.9276) (xy -24.003 -0.2286) (xy -20.7264 -0.2286)
				(xy -20.7264 -3.6576) (xy 20.7264 -3.6576) (xy 20.7264 -0.2286) (xy 24.003 -0.2286) (xy 24.003 -0.00635)
				(xy 20.2184 -0.00635) (xy 20.2184 -3.1496) (xy -20.2184 -3.1496) (xy -20.2184 0.2794) (xy -23.495 0.2794)
				(xy -23.495 4.4196) (xy -20.2184 4.4196) (xy -20.2184 11.7602) (xy -18.0975 11.7602) (xy -18.0975 10.0584)
				(xy 18.0975 10.0584) (xy 18.0975 11.7602) (xy 20.2184 11.7602) (xy 20.2184 4.4196) (xy 23.495 4.4196)
				(xy 23.495 0.2794) (xy 20.2184 0.2794) (xy 20.2184 0.00635) (xy 24.003 0.00635) (xy 24.003 4.9276)
				(xy 21.2471 4.9276) (xy 21.2471 16.256)
			)
			(stroke
				(width 0)
				(type default)
			)
			(fill no)
			(layer "F.CrtYd")
		)
		(fp_poly
			(pts
				(xy -21.2471 16.256) (xy -21.2471 4.9276) (xy -24.003 4.9276) (xy -24.003 -0.2286) (xy -20.7264 -0.2286)
				(xy -20.7264 -3.6576) (xy 20.7264 -3.6576) (xy 20.7264 -0.2286) (xy 24.003 -0.2286) (xy 24.003 4.9276)
				(xy 21.2471 4.9276) (xy 21.2471 16.256)
			)
			(stroke
				(width 0)
				(type default)
			)
			(fill no)
			(layer "F.Fab")
		)
		(pad "" np_thru_hole circle
			(at -18.999962 0 90)
			(size 0.254 0.254)
			(drill 1.8542)
			(layers "*.Cu" "*.Mask")
			(clearance 1.1557)
			(thermal_gap 1.1557)
		)
		(pad "" np_thru_hole circle
			(at 18.999962 0 90)
			(size 0.254 0.254)
			(drill 1.8542)
			(layers "*.Cu" "*.Mask")
			(clearance 1.1557)
			(thermal_gap 1.1557)
		)
		(pad "E1" smd rect
			(at -7.079996 1.240028 90)
			(size 0.508 2.0066)
			(layers "F.Cu" "F.Mask" "F.Paste")
			(net "PE_CLK100M_DR4_2_P")
		)
		(pad "E2" smd rect
			(at -6.279896 1.240028 90)
			(size 0.508 2.0066)
			(layers "F.Cu" "F.Mask" "F.Paste")
			(net "PE_CLK100M_DR4_2_N")
		)
		(pad "E3" smd rect
			(at -5.48005 1.240028 90)
			(size 0.508 2.0066)
			(layers "F.Cu" "F.Mask" "F.Paste")
			(net "P3V3")
		)
		(pad "E4" smd rect
			(at -4.67995 1.240028 90)
			(size 0.508 2.0066)
			(layers "F.Cu" "F.Mask" "F.Paste")
			(net "SSD4_PERST_N")
		)
		(pad "E5" smd rect
			(at -3.880104 1.240028 90)
			(size 0.508 2.0066)
			(layers "F.Cu" "F.Mask" "F.Paste")
			(net "SSD4_PERST_N")
		)
		(pad "E6" smd rect
			(at -3.080004 1.240028 90)
			(size 0.508 2.0066)
			(layers "F.Cu" "F.Mask" "F.Paste")
			(net "Net_1161")
		)
		(pad "E7" smd rect
			(at -15.48003 -1.949958 90)
			(size 0.508 2.0066)
			(layers "F.Cu" "F.Mask" "F.Paste")
			(net "PE_CLK100M_DR4_1_P")
		)
		(pad "E8" smd rect
			(at -14.67993 -1.949958 90)
			(size 0.508 2.0066)
			(layers "F.Cu" "F.Mask" "F.Paste")
			(net "PE_CLK100M_DR4_1_N")
		)
		(pad "E9" smd rect
			(at -13.880084 -1.949958 90)
			(size 0.508 2.0066)
			(layers "F.Cu" "F.Mask" "F.Paste")
			(net "GND")
		)
		(pad "E10" smd rect
			(at -13.079984 -1.949958 90)
			(size 0.508 2.0066)
			(layers "F.Cu" "F.Mask" "F.Paste")
			(net "PE_TX1_DR4_N")
		)
		(pad "E11" smd rect
			(at -12.279884 -1.949958 90)
			(size 0.508 2.0066)
			(layers "F.Cu" "F.Mask" "F.Paste")
			(net "PE_TX1_DR4_P")
		)
		(pad "E12" smd rect
			(at -11.480038 -1.949958 90)
			(size 0.508 2.0066)
			(layers "F.Cu" "F.Mask" "F.Paste")
			(net "GND")
		)
		(pad "E13" smd rect
			(at -10.679938 -1.949958 90)
			(size 0.508 2.0066)
			(layers "F.Cu" "F.Mask" "F.Paste")
			(net "PE_RX1_DR4_N")
		)
		(pad "E14" smd rect
			(at -9.880092 -1.949958 90)
			(size 0.508 2.0066)
			(layers "F.Cu" "F.Mask" "F.Paste")
			(net "PE_RX1_DR4_P")
		)
		(pad "E15" smd rect
			(at -9.079992 -1.949958 90)
			(size 0.508 2.0066)
			(layers "F.Cu" "F.Mask" "F.Paste")
			(net "GND")
		)
		(pad "E16" smd rect
			(at -8.279892 -1.949958 90)
			(size 0.508 2.0066)
			(layers "F.Cu" "F.Mask" "F.Paste")
			(net "Net_1168")
		)
		(pad "E17" smd rect
			(at 9.320022 -1.949958 90)
			(size 0.508 2.0066)
			(layers "F.Cu" "F.Mask" "F.Paste")
			(net "PE_TX4_DR4_N")
		)
		(pad "E18" smd rect
			(at 10.120122 -1.949958 90)
			(size 0.508 2.0066)
			(layers "F.Cu" "F.Mask" "F.Paste")
			(net "PE_TX4_DR4_P")
		)
		(pad "E19" smd rect
			(at 10.919968 -1.949958 90)
			(size 0.508 2.0066)
			(layers "F.Cu" "F.Mask" "F.Paste")
			(net "GND")
		)
		(pad "E20" smd rect
			(at 11.720068 -1.949958 90)
			(size 0.508 2.0066)
			(layers "F.Cu" "F.Mask" "F.Paste")
			(net "PE_RX4_DR4_N")
		)
		(pad "E21" smd rect
			(at 12.519914 -1.949958 90)
			(size 0.508 2.0066)
			(layers "F.Cu" "F.Mask" "F.Paste")
			(net "PE_RX4_DR4_P")
		)
		(pad "E22" smd rect
			(at 13.320014 -1.949958 90)
			(size 0.508 2.0066)
			(layers "F.Cu" "F.Mask" "F.Paste")
			(net "GND")
		)
		(pad "E23" smd rect
			(at 14.120114 -1.949958 90)
			(size 0.508 2.0066)
			(layers "F.Cu" "F.Mask" "F.Paste")
			(net "SCL_DR4_R")
		)
		(pad "E24" smd rect
			(at 14.91996 -1.949958 90)
			(size 0.508 2.0066)
			(layers "F.Cu" "F.Mask" "F.Paste")
			(net "SDA_DR4_R")
		)
		(pad "E25" smd rect
			(at 15.72006 -1.949958 90)
			(size 0.508 2.0066)
			(layers "F.Cu" "F.Mask" "F.Paste")
			(net "DUALPORTEN#4")
		)
		(pad "P1" smd rect
			(at -1.905 0.824992 90)
			(size 0.6604 2.0574)
			(layers "F.Cu" "F.Mask" "F.Paste")
			(net "Net_1164")
		)
		(pad "P2" smd rect
			(at -0.635 0.824992 90)
			(size 0.6604 2.0574)
			(layers "F.Cu" "F.Mask" "F.Paste")
			(net "Net_1163")
		)
		(pad "P3" smd rect
			(at 0.635 0.824992 90)
			(size 0.6604 2.0574)
			(layers "F.Cu" "F.Mask" "F.Paste")
			(net "Net_1162")
		)
		(pad "P4" smd rect
			(at 1.905 0.824992 90)
			(size 0.6604 2.0574)
			(layers "F.Cu" "F.Mask" "F.Paste")
			(net "SSD4_CLK0_OE_N")
		)
		(pad "P5" smd rect
			(at 3.175 0.824992 90)
			(size 0.6604 2.0574)
			(layers "F.Cu" "F.Mask" "F.Paste")
			(net "GND")
		)
		(pad "P6" smd rect
			(at 4.445 0.824992 90)
			(size 0.6604 2.0574)
			(layers "F.Cu" "F.Mask" "F.Paste")
			(net "GND")
		)
		(pad "P7" smd rect
			(at 5.715 0.824992 90)
			(size 0.6604 2.0574)
			(layers "F.Cu" "F.Mask" "F.Paste")
			(net "Net_91")
		)
		(pad "P8" smd rect
			(at 6.985 0.824992 90)
			(size 0.6604 2.0574)
			(layers "F.Cu" "F.Mask" "F.Paste")
			(net "Net_63")
		)
		(pad "P9" smd rect
			(at 8.255 0.824992 90)
			(size 0.6604 2.0574)
			(layers "F.Cu" "F.Mask" "F.Paste")
			(net "Net_77")
		)
		(pad "P10" smd rect
			(at 9.525 0.824992 90)
			(size 0.6604 2.0574)
			(layers "F.Cu" "F.Mask" "F.Paste")
			(net "SSD_PRSNT_NET4")
		)
		(pad "P11" smd rect
			(at 10.795 0.824992 90)
			(size 0.6604 2.0574)
			(layers "F.Cu" "F.Mask" "F.Paste")
			(net "SSD_ACT_DR4")
		)
		(pad "P12" smd rect
			(at 12.065 0.824992 90)
			(size 0.6604 2.0574)
			(layers "F.Cu" "F.Mask" "F.Paste")
			(net "GND")
		)
		(pad "P13" smd rect
			(at 13.335 0.824992 90)
			(size 0.6604 2.0574)
			(layers "F.Cu" "F.Mask" "F.Paste")
			(net "12V_PRECH_SSD4")
		)
		(pad "P14" smd rect
			(at 14.605 0.824992 90)
			(size 0.6604 2.0574)
			(layers "F.Cu" "F.Mask" "F.Paste")
			(net "P12V_SSD4")
		)
		(pad "P15" smd rect
			(at 15.875 0.824992 90)
			(size 0.6604 2.0574)
			(layers "F.Cu" "F.Mask" "F.Paste")
			(net "P12V_SSD4")
		)
		(pad "PTH1" thru_hole oval
			(at -21.999956 2.350008 90)
			(size 1.524 2.6162)
			(drill oval 0.8128 1.905)
			(layers "*.Cu" "*.Mask")
			(remove_unused_layers no)
			(net "Net_1173")
			(clearance 0.1524)
			(thermal_gap 0.1524)
		)
		(pad "PTH2" thru_hole oval
			(at 21.999956 2.350008 90)
			(size 1.524 2.6162)
			(drill oval 0.8128 1.905)
			(layers "*.Cu" "*.Mask")
			(remove_unused_layers no)
			(net "Net_1157")
			(clearance 0.1524)
			(thermal_gap 0.1524)
		)
		(pad "S1" smd rect
			(at -15.875 0.824992 90)
			(size 0.6604 2.0574)
			(layers "F.Cu" "F.Mask" "F.Paste")
			(net "GND")
		)
		(pad "S2" smd rect
			(at -14.605 0.824992 90)
			(size 0.6604 2.0574)
			(layers "F.Cu" "F.Mask" "F.Paste")
			(net "Net_1172")
		)
		(pad "S3" smd rect
			(at -13.335 0.824992 90)
			(size 0.6604 2.0574)
			(layers "F.Cu" "F.Mask" "F.Paste")
			(net "Net_1171")
		)
		(pad "S4" smd rect
			(at -12.065 0.824992 90)
			(size 0.6604 2.0574)
			(layers "F.Cu" "F.Mask" "F.Paste")
			(net "GND")
		)
		(pad "S5" smd rect
			(at -10.795 0.824992 90)
			(size 0.6604 2.0574)
			(layers "F.Cu" "F.Mask" "F.Paste")
			(net "Net_1170")
		)
		(pad "S6" smd rect
			(at -9.525 0.824992 90)
			(size 0.6604 2.0574)
			(layers "F.Cu" "F.Mask" "F.Paste")
			(net "Net_1169")
		)
		(pad "S7" smd rect
			(at -8.255 0.824992 90)
			(size 0.6604 2.0574)
			(layers "F.Cu" "F.Mask" "F.Paste")
			(net "GND")
		)
		(pad "S8" smd rect
			(at -7.480046 -1.949958 90)
			(size 0.508 2.0066)
			(layers "F.Cu" "F.Mask" "F.Paste")
			(net "GND")
		)
		(pad "S9" smd rect
			(at -6.679946 -1.949958 90)
			(size 0.508 2.0066)
			(layers "F.Cu" "F.Mask" "F.Paste")
			(net "Net_1167")
		)
		(pad "S10" smd rect
			(at -5.8801 -1.949958 90)
			(size 0.508 2.0066)
			(layers "F.Cu" "F.Mask" "F.Paste")
			(net "Net_1166")
		)
		(pad "S11" smd rect
			(at -5.08 -1.949958 90)
			(size 0.508 2.0066)
			(layers "F.Cu" "F.Mask" "F.Paste")
			(net "GND")
		)
		(pad "S12" smd rect
			(at -4.2799 -1.949958 90)
			(size 0.508 2.0066)
			(layers "F.Cu" "F.Mask" "F.Paste")
			(net "Net_1165")
		)
		(pad "S13" smd rect
			(at -3.480054 -1.949958 90)
			(size 0.508 2.0066)
			(layers "F.Cu" "F.Mask" "F.Paste")
			(net "Net_1160")
		)
		(pad "S14" smd rect
			(at -2.679954 -1.949958 90)
			(size 0.508 2.0066)
			(layers "F.Cu" "F.Mask" "F.Paste")
			(net "GND")
		)
		(pad "S15" smd rect
			(at -1.880108 -1.949958 90)
			(size 0.508 2.0066)
			(layers "F.Cu" "F.Mask" "F.Paste")
			(net "Net_1159")
		)
		(pad "S16" smd rect
			(at -1.080008 -1.949958 90)
			(size 0.508 2.0066)
			(layers "F.Cu" "F.Mask" "F.Paste")
			(net "GND")
		)
		(pad "S17" smd rect
			(at -0.279908 -1.949958 90)
			(size 0.508 2.0066)
			(layers "F.Cu" "F.Mask" "F.Paste")
			(net "PE_TX2_DR4_N")
		)
		(pad "S18" smd rect
			(at 0.519938 -1.949958 90)
			(size 0.508 2.0066)
			(layers "F.Cu" "F.Mask" "F.Paste")
			(net "PE_TX2_DR4_P")
		)
		(pad "S19" smd rect
			(at 1.320038 -1.949958 90)
			(size 0.508 2.0066)
			(layers "F.Cu" "F.Mask" "F.Paste")
			(net "GND")
		)
		(pad "S20" smd rect
			(at 2.119884 -1.949958 90)
			(size 0.508 2.0066)
			(layers "F.Cu" "F.Mask" "F.Paste")
			(net "PE_RX2_DR4_N")
		)
		(pad "S21" smd rect
			(at 2.919984 -1.949958 90)
			(size 0.508 2.0066)
			(layers "F.Cu" "F.Mask" "F.Paste")
			(net "PE_RX2_DR4_P")
		)
		(pad "S22" smd rect
			(at 3.720084 -1.949958 90)
			(size 0.508 2.0066)
			(layers "F.Cu" "F.Mask" "F.Paste")
			(net "GND")
		)
		(pad "S23" smd rect
			(at 4.51993 -1.949958 90)
			(size 0.508 2.0066)
			(layers "F.Cu" "F.Mask" "F.Paste")
			(net "PE_TX3_DR4_N")
		)
		(pad "S24" smd rect
			(at 5.32003 -1.949958 90)
			(size 0.508 2.0066)
			(layers "F.Cu" "F.Mask" "F.Paste")
			(net "PE_TX3_DR4_P")
		)
		(pad "S25" smd rect
			(at 6.119876 -1.949958 90)
			(size 0.508 2.0066)
			(layers "F.Cu" "F.Mask" "F.Paste")
			(net "GND")
		)
		(pad "S26" smd rect
			(at 6.919976 -1.949958 90)
			(size 0.508 2.0066)
			(layers "F.Cu" "F.Mask" "F.Paste")
			(net "PE_RX3_DR4_N")
		)
		(pad "S27" smd rect
			(at 7.720076 -1.949958 90)
			(size 0.508 2.0066)
			(layers "F.Cu" "F.Mask" "F.Paste")
			(net "PE_RX3_DR4_P")
		)
		(pad "S28" smd rect
			(at 8.519922 -1.949958 90)
			(size 0.508 2.0066)
			(layers "F.Cu" "F.Mask" "F.Paste")
			(net "GND")
		)
		(zone
			(layers "F.Cu" "B.Cu" "In1.Cu" "In2.Cu" "In3.Cu" "In4.Cu" "In5.Cu" "In6.Cu")
			(hatch none 0.5)
			(connect_pads
				(clearance 0)
			)
			(min_thickness 0.25)
			(keepout
				(tracks not_allowed)
				(vias allowed)
				(pads allowed)
				(copperpour not_allowed)
				(footprints allowed)
			)
			(placement
				(enabled no)
				(sheetname "")
			)
			(fill
				(thermal_gap 0.5)
				(thermal_bridge_width 0.5)
				(island_removal_mode 0)
			)
			(polygon
				(pts
					(arc
						(start 227.381816 -86.66988)
						(mid 224.918016 -86.66988)
						(end 227.381816 -86.66988)
					)
				)
			)
		)
		(zone
			(layers "F.Cu" "B.Cu" "In1.Cu" "In2.Cu" "In3.Cu" "In4.Cu" "In5.Cu" "In6.Cu")
			(hatch none 0.5)
			(connect_pads
				(clearance 0)
			)
			(min_thickness 0.25)
			(keepout
				(tracks not_allowed)
				(vias allowed)
				(pads allowed)
				(copperpour not_allowed)
				(footprints allowed)
			)
			(placement
				(enabled no)
				(sheetname "")
			)
			(fill
				(thermal_gap 0.5)
				(thermal_bridge_width 0.5)
				(island_removal_mode 0)
			)
			(polygon
				(pts
					(arc
						(start 227.381816 -48.669956)
						(mid 224.918016 -48.669956)
						(end 227.381816 -48.669956)
					)
				)
			)
		)
	)
	(footprint ""
		(layer "F.Cu")
		(at 87.503 -110.236 180)
		(property "Reference" "R9059"
			(at 0 0 180)
			(layer "F.SilkS")
			(hide yes)
			(effects
				(font
					(size 1.27 1.27)
				)
			)
		)
		(property "Value" "27R2F-GP"
			(at 0.064008 -3.993896 180)
			(unlocked yes)
			(layer "F.Fab")
			(hide yes)
			(effects
				(font
					(size 1.016 1.016)
					(thickness 0.1524)
				)
			)
		)
		(property "Device Type" "R402H16"
			(at 0.064008 -5.517896 180)
			(unlocked yes)
			(layer "F.Fab")
			(hide yes)
			(effects
				(font
					(size 1.016 1.016)
					(thickness 0.1524)
				)
			)
		)
		(duplicate_pad_numbers_are_jumpers no)
		(fp_line
			(start 0.508 -0.9398)
			(end -0.508 -0.9398)
			(stroke
				(width 0.1524)
				(type default)
			)
			(layer "F.SilkS")
		)
		(fp_line
			(start -0.508 -0.9398)
			(end -0.508 0.9398)
			(stroke
				(width 0.1524)
				(type default)
			)
			(layer "F.SilkS")
		)
		(fp_rect
			(start -0.508 0.9398)
			(end 0.508 -0.9398)
			(stroke
				(width 0)
				(type default)
			)
			(fill no)
			(layer "F.CrtYd")
		)
		(fp_rect
			(start -0.508 0.9398)
			(end 0.508 -0.9398)
			(stroke
				(width 0)
				(type default)
			)
			(fill no)
			(layer "F.Fab")
		)
		(pad "1" smd custom
			(at 0 -0.4445 180)
			(size 0.1397 0.1397)
			(layers "F.Cu" "F.Mask" "F.Paste")
			(net "PE_CLK_100M_DR13_1_R_P")
			(options
				(clearance outline)
				(anchor circle)
			)
			(primitives
				(gr_poly
					(pts
						(arc
							(start -0.1778 -0.2794)
							(mid -0.249642 -0.249642)
							(end -0.2794 -0.1778)
						)
						(arc
							(start -0.2794 0.1778)
							(mid -0.249642 0.249642)
							(end -0.1778 0.2794)
						)
						(arc
							(start 0.1778 0.2794)
							(mid 0.249642 0.249642)
							(end 0.2794 0.1778)
						)
						(arc
							(start 0.2794 -0.1778)
							(mid 0.249642 -0.249642)
							(end 0.1778 -0.2794)
						)
					)
					(width 0)
					(fill yes)
				)
			)
		)
		(pad "2" smd custom
			(at 0 0.4445 180)
			(size 0.1397 0.1397)
			(layers "F.Cu" "F.Mask" "F.Paste")
			(net "PE_CLK100M_DR13_1_P")
			(options
				(clearance outline)
				(anchor circle)
			)
			(primitives
				(gr_poly
					(pts
						(arc
							(start -0.1778 -0.2794)
							(mid -0.249642 -0.249642)
							(end -0.2794 -0.1778)
						)
						(arc
							(start -0.2794 0.1778)
							(mid -0.249642 0.249642)
							(end -0.1778 0.2794)
						)
						(arc
							(start 0.1778 0.2794)
							(mid 0.249642 0.249642)
							(end 0.2794 0.1778)
						)
						(arc
							(start 0.2794 -0.1778)
							(mid 0.249642 -0.249642)
							(end 0.1778 -0.2794)
						)
					)
					(width 0)
					(fill yes)
				)
			)
		)
	)
	(footprint ""
		(layer "F.Cu")
		(at 87.503 -440.436 180)
		(property "Reference" "R9063"
			(at 0 0 180)
			(layer "F.SilkS")
			(hide yes)
			(effects
				(font
					(size 1.27 1.27)
				)
			)
		)
		(property "Value" "27R2F-GP"
			(at 0.064008 -3.993896 180)
			(unlocked yes)
			(layer "F.Fab")
			(hide yes)
			(effects
				(font
					(size 1.016 1.016)
					(thickness 0.1524)
				)
			)
		)
		(property "Device Type" "R402H16"
			(at 0.064008 -5.517896 180)
			(unlocked yes)
			(layer "F.Fab")
			(hide yes)
			(effects
				(font
					(size 1.016 1.016)
					(thickness 0.1524)
				)
			)
		)
		(duplicate_pad_numbers_are_jumpers no)
		(fp_line
			(start 0.508 -0.9398)
			(end -0.508 -0.9398)
			(stroke
				(width 0.1524)
				(type default)
			)
			(layer "F.SilkS")
		)
		(fp_line
			(start -0.508 -0.9398)
			(end -0.508 0.9398)
			(stroke
				(width 0.1524)
				(type default)
			)
			(layer "F.SilkS")
		)
		(fp_rect
			(start -0.508 0.9398)
			(end 0.508 -0.9398)
			(stroke
				(width 0)
				(type default)
			)
			(fill no)
			(layer "F.CrtYd")
		)
		(fp_rect
			(start -0.508 0.9398)
			(end 0.508 -0.9398)
			(stroke
				(width 0)
				(type default)
			)
			(fill no)
			(layer "F.Fab")
		)
		(pad "1" smd custom
			(at 0 -0.4445 180)
			(size 0.1397 0.1397)
			(layers "F.Cu" "F.Mask" "F.Paste")
			(net "PE_CLK_100M_DR5_1_R_P")
			(options
				(clearance outline)
				(anchor circle)
			)
			(primitives
				(gr_poly
					(pts
						(arc
							(start -0.1778 -0.2794)
							(mid -0.249642 -0.249642)
							(end -0.2794 -0.1778)
						)
						(arc
							(start -0.2794 0.1778)
							(mid -0.249642 0.249642)
							(end -0.1778 0.2794)
						)
						(arc
							(start 0.1778 0.2794)
							(mid 0.249642 0.249642)
							(end 0.2794 0.1778)
						)
						(arc
							(start 0.2794 -0.1778)
							(mid 0.249642 -0.249642)
							(end 0.1778 -0.2794)
						)
					)
					(width 0)
					(fill yes)
				)
			)
		)
		(pad "2" smd custom
			(at 0 0.4445 180)
			(size 0.1397 0.1397)
			(layers "F.Cu" "F.Mask" "F.Paste")
			(net "PE_CLK100M_DR5_1_P")
			(options
				(clearance outline)
				(anchor circle)
			)
			(primitives
				(gr_poly
					(pts
						(arc
							(start -0.1778 -0.2794)
							(mid -0.249642 -0.249642)
							(end -0.2794 -0.1778)
						)
						(arc
							(start -0.2794 0.1778)
							(mid -0.249642 0.249642)
							(end -0.1778 0.2794)
						)
						(arc
							(start 0.1778 0.2794)
							(mid 0.249642 0.249642)
							(end 0.2794 0.1778)
						)
						(arc
							(start 0.2794 -0.1778)
							(mid 0.249642 -0.249642)
							(end 0.1778 -0.2794)
						)
					)
					(width 0)
					(fill yes)
				)
			)
		)
	)
	(footprint ""
		(layer "F.Cu")
		(at 222.123 -297.688 180)
		(property "Reference" "PC1192"
			(at 0 0 180)
			(layer "F.SilkS")
			(hide yes)
			(effects
				(font
					(size 1.27 1.27)
				)
			)
		)
		(property "Value" "SCD1U50V3KX-GP"
			(at 0 -2.8194 180)
			(unlocked yes)
			(layer "F.Fab")
			(hide yes)
			(effects
				(font
					(size 1.016 1.016)
					(thickness 0.1524)
				)
			)
		)
		(property "Device Type" "C603H36"
			(at 0 -4.3434 180)
			(unlocked yes)
			(layer "F.Fab")
			(hide yes)
			(effects
				(font
					(size 1.016 1.016)
					(thickness 0.1524)
				)
			)
		)
		(duplicate_pad_numbers_are_jumpers no)
		(fp_line
			(start 0.508 0)
			(end -0.508 0)
			(stroke
				(width 0.2032)
				(type default)
			)
			(layer "F.SilkS")
		)
		(fp_rect
			(start -0.5842 1.3335)
			(end 0.5842 -1.3335)
			(stroke
				(width 0)
				(type default)
			)
			(fill no)
			(layer "F.CrtYd")
		)
		(fp_rect
			(start -0.5842 1.3335)
			(end 0.5842 -1.3335)
			(stroke
				(width 0)
				(type default)
			)
			(fill no)
			(layer "F.Fab")
		)
		(pad "1" smd custom
			(at 0 -0.762 180)
			(size 0.2159 0.2159)
			(layers "F.Cu" "F.Mask" "F.Paste")
			(net "P12V_SSD2")
			(options
				(clearance outline)
				(anchor circle)
			)
			(primitives
				(gr_poly
					(pts
						(arc
							(start -0.3302 -0.4318)
							(mid -0.402042 -0.402042)
							(end -0.4318 -0.3302)
						)
						(arc
							(start -0.4318 0.3302)
							(mid -0.402042 0.402042)
							(end -0.3302 0.4318)
						)
						(arc
							(start 0.3302 0.4318)
							(mid 0.402042 0.402042)
							(end 0.4318 0.3302)
						)
						(arc
							(start 0.4318 -0.3302)
							(mid 0.402042 -0.402042)
							(end 0.3302 -0.4318)
						)
					)
					(width 0)
					(fill yes)
				)
			)
		)
		(pad "2" smd custom
			(at 0 0.762 180)
			(size 0.2159 0.2159)
			(layers "F.Cu" "F.Mask" "F.Paste")
			(net "GND")
			(options
				(clearance outline)
				(anchor circle)
			)
			(primitives
				(gr_poly
					(pts
						(arc
							(start -0.3302 -0.4318)
							(mid -0.402042 -0.402042)
							(end -0.4318 -0.3302)
						)
						(arc
							(start -0.4318 0.3302)
							(mid -0.402042 0.402042)
							(end -0.3302 0.4318)
						)
						(arc
							(start 0.3302 0.4318)
							(mid 0.402042 0.402042)
							(end 0.4318 0.3302)
						)
						(arc
							(start 0.4318 -0.3302)
							(mid 0.402042 -0.402042)
							(end 0.3302 -0.4318)
						)
					)
					(width 0)
					(fill yes)
				)
			)
		)
	)
	(footprint ""
		(layer "F.Cu")
		(at 220.208094 -40.045894)
		(property "Reference" "SR1129"
			(at 0 0 0)
			(layer "F.SilkS")
			(hide yes)
			(effects
				(font
					(size 1.27 1.27)
				)
			)
		)
		(property "Value" "4K7R2F-GP"
			(at 0.064008 -3.993896 0)
			(unlocked yes)
			(layer "F.Fab")
			(hide yes)
			(effects
				(font
					(size 1.016 1.016)
					(thickness 0.1524)
				)
			)
		)
		(property "Device Type" "R402H16"
			(at 0.064008 -5.517896 0)
			(unlocked yes)
			(layer "F.Fab")
			(hide yes)
			(effects
				(font
					(size 1.016 1.016)
					(thickness 0.1524)
				)
			)
		)
		(duplicate_pad_numbers_are_jumpers no)
		(fp_line
			(start -0.508 -0.9398)
			(end -0.508 0.9398)
			(stroke
				(width 0.1524)
				(type default)
			)
			(layer "F.SilkS")
		)
		(fp_line
			(start 0.508 -0.9398)
			(end -0.508 -0.9398)
			(stroke
				(width 0.1524)
				(type default)
			)
			(layer "F.SilkS")
		)
		(fp_rect
			(start -0.508 0.9398)
			(end 0.508 -0.9398)
			(stroke
				(width 0)
				(type default)
			)
			(fill no)
			(layer "F.CrtYd")
		)
		(fp_rect
			(start -0.508 0.9398)
			(end 0.508 -0.9398)
			(stroke
				(width 0)
				(type default)
			)
			(fill no)
			(layer "F.Fab")
		)
		(pad "1" smd custom
			(at 0 -0.4445)
			(size 0.1397 0.1397)
			(layers "F.Cu" "F.Mask" "F.Paste")
			(net "P3V3")
			(options
				(clearance outline)
				(anchor circle)
			)
			(primitives
				(gr_poly
					(pts
						(arc
							(start -0.1778 -0.2794)
							(mid -0.249642 -0.249642)
							(end -0.2794 -0.1778)
						)
						(arc
							(start -0.2794 0.1778)
							(mid -0.249642 0.249642)
							(end -0.1778 0.2794)
						)
						(arc
							(start 0.1778 0.2794)
							(mid 0.249642 0.249642)
							(end 0.2794 0.1778)
						)
						(arc
							(start 0.2794 -0.1778)
							(mid 0.249642 -0.249642)
							(end 0.1778 -0.2794)
						)
					)
					(width 0)
					(fill yes)
				)
			)
		)
		(pad "2" smd custom
			(at 0 0.4445)
			(size 0.1397 0.1397)
			(layers "F.Cu" "F.Mask" "F.Paste")
			(net "SSD4_CLK0_OE_MOS_N")
			(options
				(clearance outline)
				(anchor circle)
			)
			(primitives
				(gr_poly
					(pts
						(arc
							(start -0.1778 -0.2794)
							(mid -0.249642 -0.249642)
							(end -0.2794 -0.1778)
						)
						(arc
							(start -0.2794 0.1778)
							(mid -0.249642 0.249642)
							(end -0.1778 0.2794)
						)
						(arc
							(start 0.1778 0.2794)
							(mid 0.249642 0.249642)
							(end 0.2794 0.1778)
						)
						(arc
							(start 0.2794 -0.1778)
							(mid 0.249642 -0.249642)
							(end 0.1778 -0.2794)
						)
					)
					(width 0)
					(fill yes)
				)
			)
		)
	)
	(footprint ""
		(layer "F.Cu")
		(at 228.281992 -346.833952 180)
		(property "Reference" "SR1124"
			(at 0 0 180)
			(layer "F.SilkS")
			(hide yes)
			(effects
				(font
					(size 1.27 1.27)
				)
			)
		)
		(property "Value" "4K7R2J-2-GP"
			(at 0.064008 -3.993896 180)
			(unlocked yes)
			(layer "F.Fab")
			(hide yes)
			(effects
				(font
					(size 1.016 1.016)
					(thickness 0.1524)
				)
			)
		)
		(property "Device Type" "R402H16"
			(at 0.064008 -5.517896 180)
			(unlocked yes)
			(layer "F.Fab")
			(hide yes)
			(effects
				(font
					(size 1.016 1.016)
					(thickness 0.1524)
				)
			)
		)
		(duplicate_pad_numbers_are_jumpers no)
		(fp_line
			(start 0.508 -0.9398)
			(end -0.508 -0.9398)
			(stroke
				(width 0.1524)
				(type default)
			)
			(layer "F.SilkS")
		)
		(fp_line
			(start -0.508 -0.9398)
			(end -0.508 0.9398)
			(stroke
				(width 0.1524)
				(type default)
			)
			(layer "F.SilkS")
		)
		(fp_rect
			(start -0.508 0.9398)
			(end 0.508 -0.9398)
			(stroke
				(width 0)
				(type default)
			)
			(fill no)
			(layer "F.CrtYd")
		)
		(fp_rect
			(start -0.508 0.9398)
			(end 0.508 -0.9398)
			(stroke
				(width 0)
				(type default)
			)
			(fill no)
			(layer "F.Fab")
		)
		(pad "1" smd custom
			(at 0 -0.4445 180)
			(size 0.1397 0.1397)
			(layers "F.Cu" "F.Mask" "F.Paste")
			(net "P3V3")
			(options
				(clearance outline)
				(anchor circle)
			)
			(primitives
				(gr_poly
					(pts
						(arc
							(start -0.1778 -0.2794)
							(mid -0.249642 -0.249642)
							(end -0.2794 -0.1778)
						)
						(arc
							(start -0.2794 0.1778)
							(mid -0.249642 0.249642)
							(end -0.1778 0.2794)
						)
						(arc
							(start 0.1778 0.2794)
							(mid 0.249642 0.249642)
							(end 0.2794 0.1778)
						)
						(arc
							(start 0.2794 -0.1778)
							(mid 0.249642 -0.249642)
							(end 0.1778 -0.2794)
						)
					)
					(width 0)
					(fill yes)
				)
			)
		)
		(pad "2" smd custom
			(at 0 0.4445 180)
			(size 0.1397 0.1397)
			(layers "F.Cu" "F.Mask" "F.Paste")
			(net "SSD_ACT_DR1")
			(options
				(clearance outline)
				(anchor circle)
			)
			(primitives
				(gr_poly
					(pts
						(arc
							(start -0.1778 -0.2794)
							(mid -0.249642 -0.249642)
							(end -0.2794 -0.1778)
						)
						(arc
							(start -0.2794 0.1778)
							(mid -0.249642 0.249642)
							(end -0.1778 0.2794)
						)
						(arc
							(start 0.1778 0.2794)
							(mid 0.249642 0.249642)
							(end 0.2794 0.1778)
						)
						(arc
							(start 0.2794 -0.1778)
							(mid 0.249642 -0.249642)
							(end 0.1778 -0.2794)
						)
					)
					(width 0)
					(fill yes)
				)
			)
		)
	)
	(footprint ""
		(layer "F.Cu")
		(at 74.0664 -366.522)
		(property "Reference" "SR985"
			(at 0 0 0)
			(layer "F.SilkS")
			(hide yes)
			(effects
				(font
					(size 1.27 1.27)
				)
			)
		)
		(property "Value" "2KR2F-3-GP"
			(at 0.064008 -3.993896 0)
			(unlocked yes)
			(layer "F.Fab")
			(hide yes)
			(effects
				(font
					(size 1.016 1.016)
					(thickness 0.1524)
				)
			)
		)
		(property "Device Type" "R402H16"
			(at 0.064008 -5.517896 0)
			(unlocked yes)
			(layer "F.Fab")
			(hide yes)
			(effects
				(font
					(size 1.016 1.016)
					(thickness 0.1524)
				)
			)
		)
		(duplicate_pad_numbers_are_jumpers no)
		(fp_line
			(start -0.508 -0.9398)
			(end -0.508 0.9398)
			(stroke
				(width 0.1524)
				(type default)
			)
			(layer "F.SilkS")
		)
		(fp_line
			(start 0.508 -0.9398)
			(end -0.508 -0.9398)
			(stroke
				(width 0.1524)
				(type default)
			)
			(layer "F.SilkS")
		)
		(fp_rect
			(start -0.508 0.9398)
			(end 0.508 -0.9398)
			(stroke
				(width 0)
				(type default)
			)
			(fill no)
			(layer "F.CrtYd")
		)
		(fp_rect
			(start -0.508 0.9398)
			(end 0.508 -0.9398)
			(stroke
				(width 0)
				(type default)
			)
			(fill no)
			(layer "F.Fab")
		)
		(pad "1" smd custom
			(at 0 -0.4445)
			(size 0.1397 0.1397)
			(layers "F.Cu" "F.Mask" "F.Paste")
			(net "P3V3")
			(options
				(clearance outline)
				(anchor circle)
			)
			(primitives
				(gr_poly
					(pts
						(arc
							(start -0.1778 -0.2794)
							(mid -0.249642 -0.249642)
							(end -0.2794 -0.1778)
						)
						(arc
							(start -0.2794 0.1778)
							(mid -0.249642 0.249642)
							(end -0.1778 0.2794)
						)
						(arc
							(start 0.1778 0.2794)
							(mid 0.249642 0.249642)
							(end 0.2794 0.1778)
						)
						(arc
							(start 0.2794 -0.1778)
							(mid 0.249642 -0.249642)
							(end 0.1778 -0.2794)
						)
					)
					(width 0)
					(fill yes)
				)
			)
		)
		(pad "2" smd custom
			(at 0 0.4445)
			(size 0.1397 0.1397)
			(layers "F.Cu" "F.Mask" "F.Paste")
			(net "SCL_DR10")
			(options
				(clearance outline)
				(anchor circle)
			)
			(primitives
				(gr_poly
					(pts
						(arc
							(start -0.1778 -0.2794)
							(mid -0.249642 -0.249642)
							(end -0.2794 -0.1778)
						)
						(arc
							(start -0.2794 0.1778)
							(mid -0.249642 0.249642)
							(end -0.1778 0.2794)
						)
						(arc
							(start 0.1778 0.2794)
							(mid 0.249642 0.249642)
							(end 0.2794 0.1778)
						)
						(arc
							(start 0.2794 -0.1778)
							(mid 0.249642 -0.249642)
							(end 0.1778 -0.2794)
						)
					)
					(width 0)
					(fill yes)
				)
			)
		)
	)
	(footprint ""
		(layer "F.Cu")
		(at 213.741 -431.927)
		(property "Reference" "PC1280"
			(at 0 0 0)
			(layer "F.SilkS")
			(hide yes)
			(effects
				(font
					(size 1.27 1.27)
				)
			)
		)
		(property "Value" "SCD1U16V2KX-3GP"
			(at 1.1811 -2.7051 0)
			(unlocked yes)
			(layer "F.Fab")
			(hide yes)
			(effects
				(font
					(size 1.016 1.016)
					(thickness 0.1524)
				)
			)
		)
		(property "Device Type" "C402H22"
			(at 1.1811 -4.2291 0)
			(unlocked yes)
			(layer "F.Fab")
			(hide yes)
			(effects
				(font
					(size 1.016 1.016)
					(thickness 0.1524)
				)
			)
		)
		(duplicate_pad_numbers_are_jumpers no)
		(fp_rect
			(start -0.4318 0.9525)
			(end 0.4318 -0.9525)
			(stroke
				(width 0)
				(type default)
			)
			(fill no)
			(layer "F.CrtYd")
		)
		(fp_rect
			(start -0.4318 0.9525)
			(end 0.4318 -0.9525)
			(stroke
				(width 0)
				(type default)
			)
			(fill no)
			(layer "F.Fab")
		)
		(pad "1" smd custom
			(at 0 -0.4445)
			(size 0.1524 0.1524)
			(layers "F.Cu" "F.Mask" "F.Paste")
			(net "P3V3_OUT")
			(options
				(clearance outline)
				(anchor circle)
			)
			(primitives
				(gr_poly
					(pts
						(arc
							(start 0.3048 -0.2032)
							(mid 0.275042 -0.275042)
							(end 0.2032 -0.3048)
						)
						(arc
							(start -0.2032 -0.3048)
							(mid -0.275042 -0.275042)
							(end -0.3048 -0.2032)
						)
						(arc
							(start -0.3048 0.2032)
							(mid -0.275042 0.275042)
							(end -0.2032 0.3048)
						)
						(arc
							(start 0.2032 0.3048)
							(mid 0.275042 0.275042)
							(end 0.3048 0.2032)
						)
					)
					(width 0)
					(fill yes)
				)
			)
		)
		(pad "2" smd custom
			(at 0 0.4445)
			(size 0.1524 0.1524)
			(layers "F.Cu" "F.Mask" "F.Paste")
			(net "GND")
			(options
				(clearance outline)
				(anchor circle)
			)
			(primitives
				(gr_poly
					(pts
						(arc
							(start 0.3048 -0.2032)
							(mid 0.275042 -0.275042)
							(end 0.2032 -0.3048)
						)
						(arc
							(start -0.2032 -0.3048)
							(mid -0.275042 -0.275042)
							(end -0.3048 -0.2032)
						)
						(arc
							(start -0.3048 0.2032)
							(mid -0.275042 0.275042)
							(end -0.2032 0.3048)
						)
						(arc
							(start 0.2032 0.3048)
							(mid 0.275042 0.275042)
							(end 0.3048 0.2032)
						)
					)
					(width 0)
					(fill yes)
				)
			)
		)
	)
	(footprint ""
		(layer "F.Cu")
		(at 24.003 -362.331 -90)
		(property "Reference" "R9435"
			(at 0 0 270)
			(layer "F.SilkS")
			(hide yes)
			(effects
				(font
					(size 1.27 1.27)
				)
			)
		)
		(property "Value" "330R2F-GP"
			(at 0.064008 -3.993896 270)
			(unlocked yes)
			(layer "F.Fab")
			(hide yes)
			(effects
				(font
					(size 1.016 1.016)
					(thickness 0.1524)
				)
			)
		)
		(property "Device Type" "R402H16"
			(at 0.064008 -5.517896 270)
			(unlocked yes)
			(layer "F.Fab")
			(hide yes)
			(effects
				(font
					(size 1.016 1.016)
					(thickness 0.1524)
				)
			)
		)
		(duplicate_pad_numbers_are_jumpers no)
		(fp_line
			(start -0.508 -0.9398)
			(end -0.508 0.9398)
			(stroke
				(width 0.1524)
				(type default)
			)
			(layer "F.SilkS")
		)
		(fp_line
			(start 0.508 -0.9398)
			(end -0.508 -0.9398)
			(stroke
				(width 0.1524)
				(type default)
			)
			(layer "F.SilkS")
		)
		(fp_rect
			(start -0.508 0.9398)
			(end 0.508 -0.9398)
			(stroke
				(width 0)
				(type default)
			)
			(fill no)
			(layer "F.CrtYd")
		)
		(fp_rect
			(start -0.508 0.9398)
			(end 0.508 -0.9398)
			(stroke
				(width 0)
				(type default)
			)
			(fill no)
			(layer "F.Fab")
		)
		(pad "1" smd custom
			(at 0 -0.4445 270)
			(size 0.1397 0.1397)
			(layers "F.Cu" "F.Mask" "F.Paste")
			(net "P3V3")
			(options
				(clearance outline)
				(anchor circle)
			)
			(primitives
				(gr_poly
					(pts
						(arc
							(start -0.1778 -0.2794)
							(mid -0.249642 -0.249642)
							(end -0.2794 -0.1778)
						)
						(arc
							(start -0.2794 0.1778)
							(mid -0.249642 0.249642)
							(end -0.1778 0.2794)
						)
						(arc
							(start 0.1778 0.2794)
							(mid 0.249642 0.249642)
							(end 0.2794 0.1778)
						)
						(arc
							(start 0.2794 -0.1778)
							(mid 0.249642 -0.249642)
							(end 0.1778 -0.2794)
						)
					)
					(width 0)
					(fill yes)
				)
			)
		)
		(pad "2" smd custom
			(at 0 0.4445 270)
			(size 0.1397 0.1397)
			(layers "F.Cu" "F.Mask" "F.Paste")
			(net "DRV_ATTN_11")
			(options
				(clearance outline)
				(anchor circle)
			)
			(primitives
				(gr_poly
					(pts
						(arc
							(start -0.1778 -0.2794)
							(mid -0.249642 -0.249642)
							(end -0.2794 -0.1778)
						)
						(arc
							(start -0.2794 0.1778)
							(mid -0.249642 0.249642)
							(end -0.1778 0.2794)
						)
						(arc
							(start 0.1778 0.2794)
							(mid 0.249642 0.249642)
							(end 0.2794 0.1778)
						)
						(arc
							(start 0.2794 -0.1778)
							(mid 0.249642 -0.249642)
							(end 0.1778 -0.2794)
						)
					)
					(width 0)
					(fill yes)
				)
			)
		)
	)
	(footprint ""
		(layer "F.Cu")
		(at 35.46475 -101.91115 90)
		(property "Reference" "Q92"
			(at 0 0 90)
			(layer "F.SilkS")
			(hide yes)
			(effects
				(font
					(size 1.27 1.27)
				)
			)
		)
		(property "Value" "2N7002A-7-GP"
			(at 0.127 -8.9662 90)
			(unlocked yes)
			(layer "F.Fab")
			(hide yes)
			(effects
				(font
					(size 1.016 1.016)
					(thickness 0.1524)
				)
			)
		)
		(property "Device Type" "SOT23DGS2D4H48"
			(at 0.127 -10.4902 90)
			(unlocked yes)
			(layer "F.Fab")
			(hide yes)
			(effects
				(font
					(size 1.016 1.016)
					(thickness 0.1524)
				)
			)
		)
		(duplicate_pad_numbers_are_jumpers no)
		(fp_line
			(start 1.651 -1.778)
			(end -1.651 -1.778)
			(stroke
				(width 0.1524)
				(type default)
			)
			(layer "F.SilkS")
		)
		(fp_line
			(start -1.651 -1.778)
			(end -1.651 1.778)
			(stroke
				(width 0.1524)
				(type default)
			)
			(layer "F.SilkS")
		)
		(fp_line
			(start 1.651 1.778)
			(end 1.651 -1.778)
			(stroke
				(width 0.1524)
				(type default)
			)
			(layer "F.SilkS")
		)
		(fp_line
			(start -1.651 1.778)
			(end 1.651 1.778)
			(stroke
				(width 0.1524)
				(type default)
			)
			(layer "F.SilkS")
		)
		(fp_poly
			(pts
				(xy -1.778 1.8796) (xy -1.778 -1.8796) (xy 1.778 -1.8796) (xy 1.778 1.8796)
			)
			(stroke
				(width 0)
				(type default)
			)
			(fill no)
			(layer "F.CrtYd")
		)
		(fp_poly
			(pts
				(xy -1.778 1.8796) (xy -1.778 -1.8796) (xy 1.778 -1.8796) (xy 1.778 1.8796)
			)
			(stroke
				(width 0)
				(type default)
			)
			(fill no)
			(layer "F.Fab")
		)
		(pad "D" smd custom
			(at 0 -0.9525 90)
			(size 0.1905 0.1905)
			(layers "F.Cu" "F.Mask" "F.Paste")
			(net "P12V_MOST13_GATE")
			(options
				(clearance outline)
				(anchor circle)
			)
			(primitives
				(gr_poly
					(pts
						(arc
							(start -0.1778 0.5715)
							(mid -0.321484 0.511984)
							(end -0.381 0.3683)
						)
						(arc
							(start -0.381 -0.3683)
							(mid -0.321484 -0.511984)
							(end -0.1778 -0.5715)
						)
						(arc
							(start 0.1778 -0.5715)
							(mid 0.321484 -0.511984)
							(end 0.381 -0.3683)
						)
						(arc
							(start 0.381 0.3683)
							(mid 0.321484 0.511984)
							(end 0.1778 0.5715)
						)
					)
					(width 0)
					(fill yes)
				)
			)
		)
		(pad "G" smd custom
			(at -0.98425 0.9525 90)
			(size 0.1905 0.1905)
			(layers "F.Cu" "F.Mask" "F.Paste")
			(net "SSD13_PWREN_R")
			(options
				(clearance outline)
				(anchor circle)
			)
			(primitives
				(gr_poly
					(pts
						(arc
							(start -0.1778 0.5715)
							(mid -0.321484 0.511984)
							(end -0.381 0.3683)
						)
						(arc
							(start -0.381 -0.3683)
							(mid -0.321484 -0.511984)
							(end -0.1778 -0.5715)
						)
						(arc
							(start 0.1778 -0.5715)
							(mid 0.321484 -0.511984)
							(end 0.381 -0.3683)
						)
						(arc
							(start 0.381 0.3683)
							(mid 0.321484 0.511984)
							(end 0.1778 0.5715)
						)
					)
					(width 0)
					(fill yes)
				)
			)
		)
		(pad "S" smd custom
			(at 0.98425 0.9525 90)
			(size 0.1905 0.1905)
			(layers "F.Cu" "F.Mask" "F.Paste")
			(net "GND")
			(options
				(clearance outline)
				(anchor circle)
			)
			(primitives
				(gr_poly
					(pts
						(arc
							(start -0.1778 0.5715)
							(mid -0.321484 0.511984)
							(end -0.381 0.3683)
						)
						(arc
							(start -0.381 -0.3683)
							(mid -0.321484 -0.511984)
							(end -0.1778 -0.5715)
						)
						(arc
							(start 0.1778 -0.5715)
							(mid 0.321484 -0.511984)
							(end 0.381 -0.3683)
						)
						(arc
							(start 0.381 0.3683)
							(mid 0.321484 0.511984)
							(end 0.1778 0.5715)
						)
					)
					(width 0)
					(fill yes)
				)
			)
		)
	)
	(footprint ""
		(layer "F.Cu")
		(at 95.504 -92.964)
		(property "Reference" "R9128"
			(at 0 0 0)
			(layer "F.SilkS")
			(hide yes)
			(effects
				(font
					(size 1.27 1.27)
				)
			)
		)
		(property "Value" "27R2F-GP"
			(at 0.064008 -3.993896 0)
			(unlocked yes)
			(layer "F.Fab")
			(hide yes)
			(effects
				(font
					(size 1.016 1.016)
					(thickness 0.1524)
				)
			)
		)
		(property "Device Type" "R402H16"
			(at 0.064008 -5.517896 0)
			(unlocked yes)
			(layer "F.Fab")
			(hide yes)
			(effects
				(font
					(size 1.016 1.016)
					(thickness 0.1524)
				)
			)
		)
		(duplicate_pad_numbers_are_jumpers no)
		(fp_line
			(start -0.508 -0.9398)
			(end -0.508 0.9398)
			(stroke
				(width 0.1524)
				(type default)
			)
			(layer "F.SilkS")
		)
		(fp_line
			(start 0.508 -0.9398)
			(end -0.508 -0.9398)
			(stroke
				(width 0.1524)
				(type default)
			)
			(layer "F.SilkS")
		)
		(fp_rect
			(start -0.508 0.9398)
			(end 0.508 -0.9398)
			(stroke
				(width 0)
				(type default)
			)
			(fill no)
			(layer "F.CrtYd")
		)
		(fp_rect
			(start -0.508 0.9398)
			(end 0.508 -0.9398)
			(stroke
				(width 0)
				(type default)
			)
			(fill no)
			(layer "F.Fab")
		)
		(pad "1" smd custom
			(at 0 -0.4445)
			(size 0.1397 0.1397)
			(layers "F.Cu" "F.Mask" "F.Paste")
			(net "PE_CLK_100M_DR14_2_R_P")
			(options
				(clearance outline)
				(anchor circle)
			)
			(primitives
				(gr_poly
					(pts
						(arc
							(start -0.1778 -0.2794)
							(mid -0.249642 -0.249642)
							(end -0.2794 -0.1778)
						)
						(arc
							(start -0.2794 0.1778)
							(mid -0.249642 0.249642)
							(end -0.1778 0.2794)
						)
						(arc
							(start 0.1778 0.2794)
							(mid 0.249642 0.249642)
							(end 0.2794 0.1778)
						)
						(arc
							(start 0.2794 -0.1778)
							(mid 0.249642 -0.249642)
							(end 0.1778 -0.2794)
						)
					)
					(width 0)
					(fill yes)
				)
			)
		)
		(pad "2" smd custom
			(at 0 0.4445)
			(size 0.1397 0.1397)
			(layers "F.Cu" "F.Mask" "F.Paste")
			(net "PE_CLK100M_DR14_2_P")
			(options
				(clearance outline)
				(anchor circle)
			)
			(primitives
				(gr_poly
					(pts
						(arc
							(start -0.1778 -0.2794)
							(mid -0.249642 -0.249642)
							(end -0.2794 -0.1778)
						)
						(arc
							(start -0.2794 0.1778)
							(mid -0.249642 0.249642)
							(end -0.1778 0.2794)
						)
						(arc
							(start 0.1778 0.2794)
							(mid 0.249642 0.249642)
							(end 0.2794 0.1778)
						)
						(arc
							(start 0.2794 -0.1778)
							(mid 0.249642 -0.249642)
							(end 0.1778 -0.2794)
						)
					)
					(width 0)
					(fill yes)
				)
			)
		)
	)
	(footprint ""
		(layer "F.Cu")
		(at 98.806 -113.665 -90)
		(property "Reference" "C9347"
			(at 0 0 270)
			(layer "F.SilkS")
			(hide yes)
			(effects
				(font
					(size 1.27 1.27)
				)
			)
		)
		(property "Value" "SC1KP50V2KX-1GP"
			(at 1.1811 -2.7051 270)
			(unlocked yes)
			(layer "F.Fab")
			(hide yes)
			(effects
				(font
					(size 1.016 1.016)
					(thickness 0.1524)
				)
			)
		)
		(property "Device Type" "C402H22"
			(at 1.1811 -4.2291 270)
			(unlocked yes)
			(layer "F.Fab")
			(hide yes)
			(effects
				(font
					(size 1.016 1.016)
					(thickness 0.1524)
				)
			)
		)
		(duplicate_pad_numbers_are_jumpers no)
		(fp_rect
			(start -0.4318 0.9525)
			(end 0.4318 -0.9525)
			(stroke
				(width 0)
				(type default)
			)
			(fill no)
			(layer "F.CrtYd")
		)
		(fp_rect
			(start -0.4318 0.9525)
			(end 0.4318 -0.9525)
			(stroke
				(width 0)
				(type default)
			)
			(fill no)
			(layer "F.Fab")
		)
		(pad "1" smd custom
			(at 0 -0.4445 270)
			(size 0.1524 0.1524)
			(layers "F.Cu" "F.Mask" "F.Paste")
			(net "SSD_PRSNT8")
			(options
				(clearance outline)
				(anchor circle)
			)
			(primitives
				(gr_poly
					(pts
						(arc
							(start 0.3048 -0.2032)
							(mid 0.275042 -0.275042)
							(end 0.2032 -0.3048)
						)
						(arc
							(start -0.2032 -0.3048)
							(mid -0.275042 -0.275042)
							(end -0.3048 -0.2032)
						)
						(arc
							(start -0.3048 0.2032)
							(mid -0.275042 0.275042)
							(end -0.2032 0.3048)
						)
						(arc
							(start 0.2032 0.3048)
							(mid 0.275042 0.275042)
							(end 0.3048 0.2032)
						)
					)
					(width 0)
					(fill yes)
				)
			)
		)
		(pad "2" smd custom
			(at 0 0.4445 270)
			(size 0.1524 0.1524)
			(layers "F.Cu" "F.Mask" "F.Paste")
			(net "GND")
			(options
				(clearance outline)
				(anchor circle)
			)
			(primitives
				(gr_poly
					(pts
						(arc
							(start 0.3048 -0.2032)
							(mid 0.275042 -0.275042)
							(end 0.2032 -0.3048)
						)
						(arc
							(start -0.2032 -0.3048)
							(mid -0.275042 -0.275042)
							(end -0.3048 -0.2032)
						)
						(arc
							(start -0.3048 0.2032)
							(mid -0.275042 0.275042)
							(end -0.2032 0.3048)
						)
						(arc
							(start 0.2032 0.3048)
							(mid 0.275042 0.275042)
							(end 0.3048 0.2032)
						)
					)
					(width 0)
					(fill yes)
				)
			)
		)
	)
	(footprint ""
		(layer "F.Cu")
		(at 95.377 -195.834 -90)
		(property "Reference" "R9409"
			(at 0 0 270)
			(layer "F.SilkS")
			(hide yes)
			(effects
				(font
					(size 1.27 1.27)
				)
			)
		)
		(property "Value" "4K7R2J-2-GP"
			(at 0.064008 -3.993896 270)
			(unlocked yes)
			(layer "F.Fab")
			(hide yes)
			(effects
				(font
					(size 1.016 1.016)
					(thickness 0.1524)
				)
			)
		)
		(property "Device Type" "R402H16"
			(at 0.064008 -5.517896 270)
			(unlocked yes)
			(layer "F.Fab")
			(hide yes)
			(effects
				(font
					(size 1.016 1.016)
					(thickness 0.1524)
				)
			)
		)
		(duplicate_pad_numbers_are_jumpers no)
		(fp_line
			(start -0.508 -0.9398)
			(end -0.508 0.9398)
			(stroke
				(width 0.1524)
				(type default)
			)
			(layer "F.SilkS")
		)
		(fp_line
			(start 0.508 -0.9398)
			(end -0.508 -0.9398)
			(stroke
				(width 0.1524)
				(type default)
			)
			(layer "F.SilkS")
		)
		(fp_rect
			(start -0.508 0.9398)
			(end 0.508 -0.9398)
			(stroke
				(width 0)
				(type default)
			)
			(fill no)
			(layer "F.CrtYd")
		)
		(fp_rect
			(start -0.508 0.9398)
			(end 0.508 -0.9398)
			(stroke
				(width 0)
				(type default)
			)
			(fill no)
			(layer "F.Fab")
		)
		(pad "1" smd custom
			(at 0 -0.4445 270)
			(size 0.1397 0.1397)
			(layers "F.Cu" "F.Mask" "F.Paste")
			(net "P3V3")
			(options
				(clearance outline)
				(anchor circle)
			)
			(primitives
				(gr_poly
					(pts
						(arc
							(start -0.1778 -0.2794)
							(mid -0.249642 -0.249642)
							(end -0.2794 -0.1778)
						)
						(arc
							(start -0.2794 0.1778)
							(mid -0.249642 0.249642)
							(end -0.1778 0.2794)
						)
						(arc
							(start 0.1778 0.2794)
							(mid 0.249642 0.249642)
							(end 0.2794 0.1778)
						)
						(arc
							(start 0.2794 -0.1778)
							(mid 0.249642 -0.249642)
							(end 0.1778 -0.2794)
						)
					)
					(width 0)
					(fill yes)
				)
			)
		)
		(pad "2" smd custom
			(at 0 0.4445 270)
			(size 0.1397 0.1397)
			(layers "F.Cu" "F.Mask" "F.Paste")
			(net "SSD_PRSNT_NET4")
			(options
				(clearance outline)
				(anchor circle)
			)
			(primitives
				(gr_poly
					(pts
						(arc
							(start -0.1778 -0.2794)
							(mid -0.249642 -0.249642)
							(end -0.2794 -0.1778)
						)
						(arc
							(start -0.2794 0.1778)
							(mid -0.249642 0.249642)
							(end -0.1778 0.2794)
						)
						(arc
							(start 0.1778 0.2794)
							(mid 0.249642 0.249642)
							(end 0.2794 0.1778)
						)
						(arc
							(start 0.2794 -0.1778)
							(mid 0.249642 -0.249642)
							(end 0.1778 -0.2794)
						)
					)
					(width 0)
					(fill yes)
				)
			)
		)
	)
	(footprint ""
		(layer "F.Cu")
		(at 75.5904 -355.219)
		(property "Reference" "C9321"
			(at 0 0 0)
			(layer "F.SilkS")
			(hide yes)
			(effects
				(font
					(size 1.27 1.27)
				)
			)
		)
		(property "Value" "SCD1U25V3KX-GP"
			(at 0 -2.8194 0)
			(unlocked yes)
			(layer "F.Fab")
			(hide yes)
			(effects
				(font
					(size 1.016 1.016)
					(thickness 0.1524)
				)
			)
		)
		(property "Device Type" "C603H36"
			(at 0 -4.3434 0)
			(unlocked yes)
			(layer "F.Fab")
			(hide yes)
			(effects
				(font
					(size 1.016 1.016)
					(thickness 0.1524)
				)
			)
		)
		(duplicate_pad_numbers_are_jumpers no)
		(fp_line
			(start 0.508 0)
			(end -0.508 0)
			(stroke
				(width 0.2032)
				(type default)
			)
			(layer "F.SilkS")
		)
		(fp_rect
			(start -0.5842 1.3335)
			(end 0.5842 -1.3335)
			(stroke
				(width 0)
				(type default)
			)
			(fill no)
			(layer "F.CrtYd")
		)
		(fp_rect
			(start -0.5842 1.3335)
			(end 0.5842 -1.3335)
			(stroke
				(width 0)
				(type default)
			)
			(fill no)
			(layer "F.Fab")
		)
		(pad "1" smd custom
			(at 0 -0.762)
			(size 0.2159 0.2159)
			(layers "F.Cu" "F.Mask" "F.Paste")
			(net "P3V3")
			(options
				(clearance outline)
				(anchor circle)
			)
			(primitives
				(gr_poly
					(pts
						(arc
							(start -0.3302 -0.4318)
							(mid -0.402042 -0.402042)
							(end -0.4318 -0.3302)
						)
						(arc
							(start -0.4318 0.3302)
							(mid -0.402042 0.402042)
							(end -0.3302 0.4318)
						)
						(arc
							(start 0.3302 0.4318)
							(mid 0.402042 0.402042)
							(end 0.4318 0.3302)
						)
						(arc
							(start 0.4318 -0.3302)
							(mid 0.402042 -0.402042)
							(end 0.3302 -0.4318)
						)
					)
					(width 0)
					(fill yes)
				)
			)
		)
		(pad "2" smd custom
			(at 0 0.762)
			(size 0.2159 0.2159)
			(layers "F.Cu" "F.Mask" "F.Paste")
			(net "GND")
			(options
				(clearance outline)
				(anchor circle)
			)
			(primitives
				(gr_poly
					(pts
						(arc
							(start -0.3302 -0.4318)
							(mid -0.402042 -0.402042)
							(end -0.4318 -0.3302)
						)
						(arc
							(start -0.4318 0.3302)
							(mid -0.402042 0.402042)
							(end -0.3302 0.4318)
						)
						(arc
							(start 0.3302 0.4318)
							(mid 0.402042 0.402042)
							(end 0.4318 0.3302)
						)
						(arc
							(start 0.4318 -0.3302)
							(mid 0.402042 -0.402042)
							(end 0.3302 -0.4318)
						)
					)
					(width 0)
					(fill yes)
				)
			)
		)
	)
	(footprint ""
		(layer "F.Cu")
		(at 69.977 -454.66)
		(property "Reference" "R347"
			(at 0 0 0)
			(layer "F.SilkS")
			(hide yes)
			(effects
				(font
					(size 1.27 1.27)
				)
			)
		)
		(property "Value" "4K7R2F-GP"
			(at 0.064008 -3.993896 0)
			(unlocked yes)
			(layer "F.Fab")
			(hide yes)
			(effects
				(font
					(size 1.016 1.016)
					(thickness 0.1524)
				)
			)
		)
		(property "Device Type" "R402H16"
			(at 0.064008 -5.517896 0)
			(unlocked yes)
			(layer "F.Fab")
			(hide yes)
			(effects
				(font
					(size 1.016 1.016)
					(thickness 0.1524)
				)
			)
		)
		(duplicate_pad_numbers_are_jumpers no)
		(fp_line
			(start -0.508 -0.9398)
			(end -0.508 0.9398)
			(stroke
				(width 0.1524)
				(type default)
			)
			(layer "F.SilkS")
		)
		(fp_line
			(start 0.508 -0.9398)
			(end -0.508 -0.9398)
			(stroke
				(width 0.1524)
				(type default)
			)
			(layer "F.SilkS")
		)
		(fp_rect
			(start -0.508 0.9398)
			(end 0.508 -0.9398)
			(stroke
				(width 0)
				(type default)
			)
			(fill no)
			(layer "F.CrtYd")
		)
		(fp_rect
			(start -0.508 0.9398)
			(end 0.508 -0.9398)
			(stroke
				(width 0)
				(type default)
			)
			(fill no)
			(layer "F.Fab")
		)
		(pad "1" smd custom
			(at 0 -0.4445)
			(size 0.1397 0.1397)
			(layers "F.Cu" "F.Mask" "F.Paste")
			(net "P3V3")
			(options
				(clearance outline)
				(anchor circle)
			)
			(primitives
				(gr_poly
					(pts
						(arc
							(start -0.1778 -0.2794)
							(mid -0.249642 -0.249642)
							(end -0.2794 -0.1778)
						)
						(arc
							(start -0.2794 0.1778)
							(mid -0.249642 0.249642)
							(end -0.1778 0.2794)
						)
						(arc
							(start 0.1778 0.2794)
							(mid 0.249642 0.249642)
							(end 0.2794 0.1778)
						)
						(arc
							(start 0.2794 -0.1778)
							(mid 0.249642 -0.249642)
							(end 0.1778 -0.2794)
						)
					)
					(width 0)
					(fill yes)
				)
			)
		)
		(pad "2" smd custom
			(at 0 0.4445)
			(size 0.1397 0.1397)
			(layers "F.Cu" "F.Mask" "F.Paste")
			(net "EEPROM_A2")
			(options
				(clearance outline)
				(anchor circle)
			)
			(primitives
				(gr_poly
					(pts
						(arc
							(start -0.1778 -0.2794)
							(mid -0.249642 -0.249642)
							(end -0.2794 -0.1778)
						)
						(arc
							(start -0.2794 0.1778)
							(mid -0.249642 0.249642)
							(end -0.1778 0.2794)
						)
						(arc
							(start 0.1778 0.2794)
							(mid 0.249642 0.249642)
							(end 0.2794 0.1778)
						)
						(arc
							(start 0.2794 -0.1778)
							(mid 0.249642 -0.249642)
							(end 0.1778 -0.2794)
						)
					)
					(width 0)
					(fill yes)
				)
			)
		)
	)
	(footprint ""
		(layer "F.Cu")
		(at 227.203 -439.166 180)
		(property "Reference" "PC1275"
			(at 0 0 180)
			(layer "F.SilkS")
			(hide yes)
			(effects
				(font
					(size 1.27 1.27)
				)
			)
		)
		(property "Value" "SC2D2U16V2KX-GP"
			(at -1.524 -1.905 180)
			(unlocked yes)
			(layer "F.Fab")
			(hide yes)
			(effects
				(font
					(size 1.016 1.016)
					(thickness 0.1524)
				)
			)
		)
		(property "Device Type" "C402-TO0D2H28"
			(at -1.524 -3.429 180)
			(unlocked yes)
			(layer "F.Fab")
			(hide yes)
			(effects
				(font
					(size 1.016 1.016)
					(thickness 0.1524)
				)
			)
		)
		(duplicate_pad_numbers_are_jumpers no)
		(fp_rect
			(start -0.4826 0.889)
			(end 0.4826 -0.889)
			(stroke
				(width 0)
				(type default)
			)
			(fill no)
			(layer "F.CrtYd")
		)
		(fp_rect
			(start -0.4826 0.889)
			(end 0.4826 -0.889)
			(stroke
				(width 0)
				(type default)
			)
			(fill no)
			(layer "F.Fab")
		)
		(pad "1" smd custom
			(at 0 -0.4572 180)
			(size 0.1524 0.1524)
			(layers "F.Cu" "F.Mask" "F.Paste")
			(net "P3V3_EN_R")
			(options
				(clearance outline)
				(anchor circle)
			)
			(primitives
				(gr_poly
					(pts
						(arc
							(start -0.254 0.3048)
							(mid -0.325842 0.275042)
							(end -0.3556 0.2032)
						)
						(arc
							(start -0.3556 -0.2032)
							(mid -0.325842 -0.275042)
							(end -0.254 -0.3048)
						)
						(arc
							(start 0.254 -0.3048)
							(mid 0.325842 -0.275042)
							(end 0.3556 -0.2032)
						)
						(arc
							(start 0.3556 0.2032)
							(mid 0.325842 0.275042)
							(end 0.254 0.3048)
						)
					)
					(width 0)
					(fill yes)
				)
			)
		)
		(pad "2" smd custom
			(at 0 0.4572 180)
			(size 0.1524 0.1524)
			(layers "F.Cu" "F.Mask" "F.Paste")
			(net "AGND_P3V3")
			(options
				(clearance outline)
				(anchor circle)
			)
			(primitives
				(gr_poly
					(pts
						(arc
							(start -0.254 0.3048)
							(mid -0.325842 0.275042)
							(end -0.3556 0.2032)
						)
						(arc
							(start -0.3556 -0.2032)
							(mid -0.325842 -0.275042)
							(end -0.254 -0.3048)
						)
						(arc
							(start 0.254 -0.3048)
							(mid 0.325842 -0.275042)
							(end 0.3556 -0.2032)
						)
						(arc
							(start 0.3556 0.2032)
							(mid 0.325842 0.275042)
							(end 0.254 0.3048)
						)
					)
					(width 0)
					(fill yes)
				)
			)
		)
	)
	(footprint ""
		(layer "F.Cu")
		(at 223.012 -438.404 180)
		(property "Reference" "PC1287"
			(at 0 0 180)
			(layer "F.SilkS")
			(hide yes)
			(effects
				(font
					(size 1.27 1.27)
				)
			)
		)
		(property "Value" "SC2K2P50V3KX-GP"
			(at 0 -2.8194 180)
			(unlocked yes)
			(layer "F.Fab")
			(hide yes)
			(effects
				(font
					(size 1.016 1.016)
					(thickness 0.1524)
				)
			)
		)
		(property "Device Type" "C603"
			(at 0 -4.3434 180)
			(unlocked yes)
			(layer "F.Fab")
			(hide yes)
			(effects
				(font
					(size 1.016 1.016)
					(thickness 0.1524)
				)
			)
		)
		(duplicate_pad_numbers_are_jumpers no)
		(fp_line
			(start 0.508 0)
			(end -0.508 0)
			(stroke
				(width 0.2032)
				(type default)
			)
			(layer "F.SilkS")
		)
		(fp_rect
			(start -0.5842 1.3335)
			(end 0.5842 -1.3335)
			(stroke
				(width 0)
				(type default)
			)
			(fill no)
			(layer "F.CrtYd")
		)
		(fp_rect
			(start -0.5842 1.3335)
			(end 0.5842 -1.3335)
			(stroke
				(width 0)
				(type default)
			)
			(fill no)
			(layer "F.Fab")
		)
		(pad "1" smd custom
			(at 0 -0.762 180)
			(size 0.2159 0.2159)
			(layers "F.Cu" "F.Mask" "F.Paste")
			(net "P3V3_SW")
			(options
				(clearance outline)
				(anchor circle)
			)
			(primitives
				(gr_poly
					(pts
						(arc
							(start -0.3302 -0.4318)
							(mid -0.402042 -0.402042)
							(end -0.4318 -0.3302)
						)
						(arc
							(start -0.4318 0.3302)
							(mid -0.402042 0.402042)
							(end -0.3302 0.4318)
						)
						(arc
							(start 0.3302 0.4318)
							(mid 0.402042 0.402042)
							(end 0.4318 0.3302)
						)
						(arc
							(start 0.4318 -0.3302)
							(mid 0.402042 -0.402042)
							(end 0.3302 -0.4318)
						)
					)
					(width 0)
					(fill yes)
				)
			)
		)
		(pad "2" smd custom
			(at 0 0.762 180)
			(size 0.2159 0.2159)
			(layers "F.Cu" "F.Mask" "F.Paste")
			(net "P3V3_SNB")
			(options
				(clearance outline)
				(anchor circle)
			)
			(primitives
				(gr_poly
					(pts
						(arc
							(start -0.3302 -0.4318)
							(mid -0.402042 -0.402042)
							(end -0.4318 -0.3302)
						)
						(arc
							(start -0.4318 0.3302)
							(mid -0.402042 0.402042)
							(end -0.3302 0.4318)
						)
						(arc
							(start 0.3302 0.4318)
							(mid 0.402042 0.402042)
							(end 0.4318 0.3302)
						)
						(arc
							(start 0.4318 -0.3302)
							(mid 0.402042 -0.402042)
							(end 0.3302 -0.4318)
						)
					)
					(width 0)
					(fill yes)
				)
			)
		)
	)
	(footprint ""
		(layer "F.Cu")
		(at 210.49996 -459.000098 -90)
		(property "Reference" "U47"
			(at 0 0 270)
			(layer "F.SilkS")
			(hide yes)
			(effects
				(font
					(size 1.27 1.27)
				)
			)
		)
		(property "Value" "TMP75AIDGKR-GP"
			(at -0.1143 -9.1948 270)
			(unlocked yes)
			(layer "F.Fab")
			(hide yes)
			(effects
				(font
					(size 1.016 1.016)
					(thickness 0.1524)
				)
			)
		)
		(property "Device Type" "MSOP8-1H44"
			(at -0.1143 -10.795 270)
			(unlocked yes)
			(layer "F.Fab")
			(hide yes)
			(effects
				(font
					(size 1.016 1.016)
					(thickness 0.1524)
				)
			)
		)
		(duplicate_pad_numbers_are_jumpers no)
		(fp_line
			(start -1.778 1.0922)
			(end -1.778 3.048)
			(stroke
				(width 0.508)
				(type default)
			)
			(layer "F.SilkS")
		)
		(fp_line
			(start -1.9558 1.016)
			(end 1.0795 1.016)
			(stroke
				(width 0.1524)
				(type default)
			)
			(layer "F.SilkS")
		)
		(fp_line
			(start 1.0795 1.016)
			(end 1.0795 -1.016)
			(stroke
				(width 0.1524)
				(type default)
			)
			(layer "F.SilkS")
		)
		(fp_line
			(start -1.4478 -0.0381)
			(end -1.9558 0.4699)
			(stroke
				(width 0.1524)
				(type default)
			)
			(layer "F.SilkS")
		)
		(fp_line
			(start -1.9558 -0.5461)
			(end -1.4478 -0.0381)
			(stroke
				(width 0.1524)
				(type default)
			)
			(layer "F.SilkS")
		)
		(fp_line
			(start -1.9558 -1.016)
			(end -1.9558 1.016)
			(stroke
				(width 0.1524)
				(type default)
			)
			(layer "F.SilkS")
		)
		(fp_line
			(start 1.0795 -1.016)
			(end -1.9558 -1.016)
			(stroke
				(width 0.1524)
				(type default)
			)
			(layer "F.SilkS")
		)
		(fp_poly
			(pts
				(xy -1.1557 -1.016) (xy -1.1557 1.016) (xy 1.1557 1.016) (xy 1.1557 -1.016)
			)
			(stroke
				(width 0)
				(type default)
			)
			(fill yes)
			(layer "F.SilkS")
		)
		(fp_rect
			(start -1.4986 2.4511)
			(end 1.4986 -2.4511)
			(stroke
				(width 0)
				(type default)
			)
			(fill no)
			(layer "F.CrtYd")
		)
		(fp_poly
			(pts
				(xy -2.032 3.302) (xy -2.032 -3.302) (xy 2.032 -3.302) (xy 2.032 -2.1209) (xy 1.4986 -2.1209) (xy 1.4986 -2.4511)
				(xy -1.4986 -2.4511) (xy -1.4986 2.4511) (xy 1.4986 2.4511) (xy 1.4986 -2.1082) (xy 2.032 -2.1082)
				(xy 2.032 3.302)
			)
			(stroke
				(width 0)
				(type default)
			)
			(fill no)
			(layer "F.CrtYd")
		)
		(fp_rect
			(start -2.032 3.302)
			(end 2.032 -3.302)
			(stroke
				(width 0)
				(type default)
			)
			(fill no)
			(layer "F.Fab")
		)
		(pad "1" smd rect
			(at -0.97536 2.05486 270)
			(size 0.3556 1.524)
			(layers "F.Cu" "F.Mask" "F.Paste")
			(net "TMP2_SDA")
		)
		(pad "2" smd rect
			(at -0.32512 2.05486 270)
			(size 0.3556 1.524)
			(layers "F.Cu" "F.Mask" "F.Paste")
			(net "TMP2_SCL")
		)
		(pad "3" smd rect
			(at 0.32512 2.05486 270)
			(size 0.3556 1.524)
			(layers "F.Cu" "F.Mask" "F.Paste")
			(net "I2C_B_TMP2_ALERT")
		)
		(pad "4" smd rect
			(at 0.97536 2.05486 270)
			(size 0.3556 1.524)
			(layers "F.Cu" "F.Mask" "F.Paste")
			(net "GND")
		)
		(pad "5" smd rect
			(at 0.97536 -2.05486 270)
			(size 0.3556 1.524)
			(layers "F.Cu" "F.Mask" "F.Paste")
			(net "I2C_B_TMP2_A2")
		)
		(pad "6" smd rect
			(at 0.32512 -2.05486 270)
			(size 0.3556 1.524)
			(layers "F.Cu" "F.Mask" "F.Paste")
			(net "I2C_B_TMP2_A1")
		)
		(pad "7" smd rect
			(at -0.32512 -2.05486 270)
			(size 0.3556 1.524)
			(layers "F.Cu" "F.Mask" "F.Paste")
			(net "I2C_B_TMP2_A0")
		)
		(pad "8" smd rect
			(at -0.97536 -2.05486 270)
			(size 0.3556 1.524)
			(layers "F.Cu" "F.Mask" "F.Paste")
			(net "P3V3")
		)
	)
	(footprint ""
		(layer "F.Cu")
		(at 19.4945 -59.073288 180)
		(property "Reference" "R9875"
			(at 0 0 180)
			(layer "F.SilkS")
			(hide yes)
			(effects
				(font
					(size 1.27 1.27)
				)
			)
		)
		(property "Value" "0R2J-2-GP"
			(at 0.064008 -3.993896 180)
			(unlocked yes)
			(layer "F.Fab")
			(hide yes)
			(effects
				(font
					(size 1.016 1.016)
					(thickness 0.1524)
				)
			)
		)
		(property "Device Type" "R402H16"
			(at 0.064008 -5.517896 180)
			(unlocked yes)
			(layer "F.Fab")
			(hide yes)
			(effects
				(font
					(size 1.016 1.016)
					(thickness 0.1524)
				)
			)
		)
		(duplicate_pad_numbers_are_jumpers no)
		(fp_line
			(start 0.508 -0.9398)
			(end -0.508 -0.9398)
			(stroke
				(width 0.1524)
				(type default)
			)
			(layer "F.SilkS")
		)
		(fp_line
			(start -0.508 -0.9398)
			(end -0.508 0.9398)
			(stroke
				(width 0.1524)
				(type default)
			)
			(layer "F.SilkS")
		)
		(fp_rect
			(start -0.508 0.9398)
			(end 0.508 -0.9398)
			(stroke
				(width 0)
				(type default)
			)
			(fill no)
			(layer "F.CrtYd")
		)
		(fp_rect
			(start -0.508 0.9398)
			(end 0.508 -0.9398)
			(stroke
				(width 0)
				(type default)
			)
			(fill no)
			(layer "F.Fab")
		)
		(pad "1" smd custom
			(at 0 -0.4445 180)
			(size 0.1397 0.1397)
			(layers "F.Cu" "F.Mask" "F.Paste")
			(net "SSD_ACT_DR14_R")
			(options
				(clearance outline)
				(anchor circle)
			)
			(primitives
				(gr_poly
					(pts
						(arc
							(start -0.1778 -0.2794)
							(mid -0.249642 -0.249642)
							(end -0.2794 -0.1778)
						)
						(arc
							(start -0.2794 0.1778)
							(mid -0.249642 0.249642)
							(end -0.1778 0.2794)
						)
						(arc
							(start 0.1778 0.2794)
							(mid 0.249642 0.249642)
							(end 0.2794 0.1778)
						)
						(arc
							(start 0.2794 -0.1778)
							(mid 0.249642 -0.249642)
							(end 0.1778 -0.2794)
						)
					)
					(width 0)
					(fill yes)
				)
			)
		)
		(pad "2" smd custom
			(at 0 0.4445 180)
			(size 0.1397 0.1397)
			(layers "F.Cu" "F.Mask" "F.Paste")
			(net "SSD_ACT_DR14")
			(options
				(clearance outline)
				(anchor circle)
			)
			(primitives
				(gr_poly
					(pts
						(arc
							(start -0.1778 -0.2794)
							(mid -0.249642 -0.249642)
							(end -0.2794 -0.1778)
						)
						(arc
							(start -0.2794 0.1778)
							(mid -0.249642 0.249642)
							(end -0.1778 0.2794)
						)
						(arc
							(start 0.1778 0.2794)
							(mid 0.249642 0.249642)
							(end 0.2794 0.1778)
						)
						(arc
							(start 0.2794 -0.1778)
							(mid 0.249642 -0.249642)
							(end 0.1778 -0.2794)
						)
					)
					(width 0)
					(fill yes)
				)
			)
		)
	)
	(footprint ""
		(layer "F.Cu")
		(at 25.1206 -420.1922 180)
		(property "Reference" "PC1183"
			(at 0 0 180)
			(layer "F.SilkS")
			(hide yes)
			(effects
				(font
					(size 1.27 1.27)
				)
			)
		)
		(property "Value" "SCD01U50V2KX-1GP"
			(at 1.1811 -2.7051 180)
			(unlocked yes)
			(layer "F.Fab")
			(hide yes)
			(effects
				(font
					(size 1.016 1.016)
					(thickness 0.1524)
				)
			)
		)
		(property "Device Type" "C402H22"
			(at 1.1811 -4.2291 180)
			(unlocked yes)
			(layer "F.Fab")
			(hide yes)
			(effects
				(font
					(size 1.016 1.016)
					(thickness 0.1524)
				)
			)
		)
		(duplicate_pad_numbers_are_jumpers no)
		(fp_rect
			(start -0.4318 0.9525)
			(end 0.4318 -0.9525)
			(stroke
				(width 0)
				(type default)
			)
			(fill no)
			(layer "F.CrtYd")
		)
		(fp_rect
			(start -0.4318 0.9525)
			(end 0.4318 -0.9525)
			(stroke
				(width 0)
				(type default)
			)
			(fill no)
			(layer "F.Fab")
		)
		(pad "1" smd custom
			(at 0 -0.4445 180)
			(size 0.1524 0.1524)
			(layers "F.Cu" "F.Mask" "F.Paste")
			(net "P12V_SSD10")
			(options
				(clearance outline)
				(anchor circle)
			)
			(primitives
				(gr_poly
					(pts
						(arc
							(start 0.3048 -0.2032)
							(mid 0.275042 -0.275042)
							(end 0.2032 -0.3048)
						)
						(arc
							(start -0.2032 -0.3048)
							(mid -0.275042 -0.275042)
							(end -0.3048 -0.2032)
						)
						(arc
							(start -0.3048 0.2032)
							(mid -0.275042 0.275042)
							(end -0.2032 0.3048)
						)
						(arc
							(start 0.2032 0.3048)
							(mid 0.275042 0.275042)
							(end 0.3048 0.2032)
						)
					)
					(width 0)
					(fill yes)
				)
			)
		)
		(pad "2" smd custom
			(at 0 0.4445 180)
			(size 0.1524 0.1524)
			(layers "F.Cu" "F.Mask" "F.Paste")
			(net "GND")
			(options
				(clearance outline)
				(anchor circle)
			)
			(primitives
				(gr_poly
					(pts
						(arc
							(start 0.3048 -0.2032)
							(mid 0.275042 -0.275042)
							(end 0.2032 -0.3048)
						)
						(arc
							(start -0.2032 -0.3048)
							(mid -0.275042 -0.275042)
							(end -0.3048 -0.2032)
						)
						(arc
							(start -0.3048 0.2032)
							(mid -0.275042 0.275042)
							(end -0.2032 0.3048)
						)
						(arc
							(start 0.2032 0.3048)
							(mid 0.275042 0.275042)
							(end 0.3048 0.2032)
						)
					)
					(width 0)
					(fill yes)
				)
			)
		)
	)
	(footprint ""
		(layer "F.Cu")
		(at 41.672764 -347.936058 180)
		(property "Reference" "R9940"
			(at 0 0 180)
			(layer "F.SilkS")
			(hide yes)
			(effects
				(font
					(size 1.27 1.27)
				)
			)
		)
		(property "Value" "4K7R2J-2-GP"
			(at 0.064008 -3.993896 180)
			(unlocked yes)
			(layer "F.Fab")
			(hide yes)
			(effects
				(font
					(size 1.016 1.016)
					(thickness 0.1524)
				)
			)
		)
		(property "Device Type" "R402H16"
			(at 0.064008 -5.517896 180)
			(unlocked yes)
			(layer "F.Fab")
			(hide yes)
			(effects
				(font
					(size 1.016 1.016)
					(thickness 0.1524)
				)
			)
		)
		(duplicate_pad_numbers_are_jumpers no)
		(fp_line
			(start 0.508 -0.9398)
			(end -0.508 -0.9398)
			(stroke
				(width 0.1524)
				(type default)
			)
			(layer "F.SilkS")
		)
		(fp_line
			(start -0.508 -0.9398)
			(end -0.508 0.9398)
			(stroke
				(width 0.1524)
				(type default)
			)
			(layer "F.SilkS")
		)
		(fp_rect
			(start -0.508 0.9398)
			(end 0.508 -0.9398)
			(stroke
				(width 0)
				(type default)
			)
			(fill no)
			(layer "F.CrtYd")
		)
		(fp_rect
			(start -0.508 0.9398)
			(end 0.508 -0.9398)
			(stroke
				(width 0)
				(type default)
			)
			(fill no)
			(layer "F.Fab")
		)
		(pad "1" smd custom
			(at 0 -0.4445 180)
			(size 0.1397 0.1397)
			(layers "F.Cu" "F.Mask" "F.Paste")
			(net "P3V3")
			(options
				(clearance outline)
				(anchor circle)
			)
			(primitives
				(gr_poly
					(pts
						(arc
							(start -0.1778 -0.2794)
							(mid -0.249642 -0.249642)
							(end -0.2794 -0.1778)
						)
						(arc
							(start -0.2794 0.1778)
							(mid -0.249642 0.249642)
							(end -0.1778 0.2794)
						)
						(arc
							(start 0.1778 0.2794)
							(mid 0.249642 0.249642)
							(end 0.2794 0.1778)
						)
						(arc
							(start 0.2794 -0.1778)
							(mid 0.249642 -0.249642)
							(end 0.1778 -0.2794)
						)
					)
					(width 0)
					(fill yes)
				)
			)
		)
		(pad "2" smd custom
			(at 0 0.4445 180)
			(size 0.1397 0.1397)
			(layers "F.Cu" "F.Mask" "F.Paste")
			(net "SSD_ACT_DR6_MOS_N")
			(options
				(clearance outline)
				(anchor circle)
			)
			(primitives
				(gr_poly
					(pts
						(arc
							(start -0.1778 -0.2794)
							(mid -0.249642 -0.249642)
							(end -0.2794 -0.1778)
						)
						(arc
							(start -0.2794 0.1778)
							(mid -0.249642 0.249642)
							(end -0.1778 0.2794)
						)
						(arc
							(start 0.1778 0.2794)
							(mid 0.249642 0.249642)
							(end 0.2794 0.1778)
						)
						(arc
							(start 0.2794 -0.1778)
							(mid 0.249642 -0.249642)
							(end 0.1778 -0.2794)
						)
					)
					(width 0)
					(fill yes)
				)
			)
		)
	)
	(footprint ""
		(layer "F.Cu")
		(at 78.8162 -430.3395 180)
		(property "Reference" "R9957"
			(at 0 0 180)
			(layer "F.SilkS")
			(hide yes)
			(effects
				(font
					(size 1.27 1.27)
				)
			)
		)
		(property "Value" "470R2F-GP"
			(at 0.064008 -3.993896 180)
			(unlocked yes)
			(layer "F.Fab")
			(hide yes)
			(effects
				(font
					(size 1.016 1.016)
					(thickness 0.1524)
				)
			)
		)
		(property "Device Type" "R402H16"
			(at 0.064008 -5.517896 180)
			(unlocked yes)
			(layer "F.Fab")
			(hide yes)
			(effects
				(font
					(size 1.016 1.016)
					(thickness 0.1524)
				)
			)
		)
		(duplicate_pad_numbers_are_jumpers no)
		(fp_line
			(start 0.508 -0.9398)
			(end -0.508 -0.9398)
			(stroke
				(width 0.1524)
				(type default)
			)
			(layer "F.SilkS")
		)
		(fp_line
			(start -0.508 -0.9398)
			(end -0.508 0.9398)
			(stroke
				(width 0.1524)
				(type default)
			)
			(layer "F.SilkS")
		)
		(fp_rect
			(start -0.508 0.9398)
			(end 0.508 -0.9398)
			(stroke
				(width 0)
				(type default)
			)
			(fill no)
			(layer "F.CrtYd")
		)
		(fp_rect
			(start -0.508 0.9398)
			(end 0.508 -0.9398)
			(stroke
				(width 0)
				(type default)
			)
			(fill no)
			(layer "F.Fab")
		)
		(pad "1" smd custom
			(at 0 -0.4445 180)
			(size 0.1397 0.1397)
			(layers "F.Cu" "F.Mask" "F.Paste")
			(net "VDD_DIFF_1")
			(options
				(clearance outline)
				(anchor circle)
			)
			(primitives
				(gr_poly
					(pts
						(arc
							(start -0.1778 -0.2794)
							(mid -0.249642 -0.249642)
							(end -0.2794 -0.1778)
						)
						(arc
							(start -0.2794 0.1778)
							(mid -0.249642 0.249642)
							(end -0.1778 0.2794)
						)
						(arc
							(start 0.1778 0.2794)
							(mid 0.249642 0.249642)
							(end 0.2794 0.1778)
						)
						(arc
							(start 0.2794 -0.1778)
							(mid 0.249642 -0.249642)
							(end 0.1778 -0.2794)
						)
					)
					(width 0)
					(fill yes)
				)
			)
		)
		(pad "2" smd custom
			(at 0 0.4445 180)
			(size 0.1397 0.1397)
			(layers "F.Cu" "F.Mask" "F.Paste")
			(net "PE_100M_CLK4_N")
			(options
				(clearance outline)
				(anchor circle)
			)
			(primitives
				(gr_poly
					(pts
						(arc
							(start -0.1778 -0.2794)
							(mid -0.249642 -0.249642)
							(end -0.2794 -0.1778)
						)
						(arc
							(start -0.2794 0.1778)
							(mid -0.249642 0.249642)
							(end -0.1778 0.2794)
						)
						(arc
							(start 0.1778 0.2794)
							(mid 0.249642 0.249642)
							(end 0.2794 0.1778)
						)
						(arc
							(start 0.2794 -0.1778)
							(mid 0.249642 -0.249642)
							(end 0.1778 -0.2794)
						)
					)
					(width 0)
					(fill yes)
				)
			)
		)
	)
	(footprint ""
		(layer "F.Cu")
		(at 27.9146 -498.5258 180)
		(property "Reference" "PC1205"
			(at 0 0 180)
			(layer "F.SilkS")
			(hide yes)
			(effects
				(font
					(size 1.27 1.27)
				)
			)
		)
		(property "Value" "SC22U25V6KX-GP-U"
			(at -2.860802 -5.279644 180)
			(unlocked yes)
			(layer "F.Fab")
			(hide yes)
			(effects
				(font
					(size 1.016 1.016)
					(thickness 0.1524)
				)
			)
		)
		(property "Device Type" "C1206-TO0D3H75"
			(at -2.860802 -6.803644 180)
			(unlocked yes)
			(layer "F.Fab")
			(hide yes)
			(effects
				(font
					(size 1.016 1.016)
					(thickness 0.1524)
				)
			)
		)
		(duplicate_pad_numbers_are_jumpers no)
		(fp_line
			(start 1.3081 2.3749)
			(end -1.3081 2.3749)
			(stroke
				(width 0.1524)
				(type default)
			)
			(layer "F.SilkS")
		)
		(fp_line
			(start 1.3081 -2.3749)
			(end 1.3081 2.3749)
			(stroke
				(width 0.1524)
				(type default)
			)
			(layer "F.SilkS")
		)
		(fp_line
			(start -1.3081 2.3749)
			(end -1.3081 -2.3749)
			(stroke
				(width 0.1524)
				(type default)
			)
			(layer "F.SilkS")
		)
		(fp_line
			(start -1.3081 -2.3749)
			(end 1.3081 -2.3749)
			(stroke
				(width 0.1524)
				(type default)
			)
			(layer "F.SilkS")
		)
		(fp_rect
			(start -0.8001 1.6002)
			(end 0.8001 -1.6002)
			(stroke
				(width 0)
				(type default)
			)
			(fill no)
			(layer "F.CrtYd")
		)
		(fp_poly
			(pts
				(xy -1.5621 2.4511) (xy -1.5621 1.6002) (xy 0.8001 1.6002) (xy 0.8001 -1.6002) (xy -0.8001 -1.6002)
				(xy -0.8001 1.5875) (xy -1.5621 1.5875) (xy -1.5621 -2.4511) (xy 1.5621 -2.4511) (xy 1.5621 2.4511)
			)
			(stroke
				(width 0)
				(type default)
			)
			(fill no)
			(layer "F.CrtYd")
		)
		(fp_rect
			(start -1.5621 2.4511)
			(end 1.5621 -2.4511)
			(stroke
				(width 0)
				(type default)
			)
			(fill no)
			(layer "F.Fab")
		)
		(pad "1" smd rect
			(at 0 -1.392936 180)
			(size 2.1082 1.4478)
			(layers "F.Cu" "F.Mask" "F.Paste")
			(net "P12V_SSD5")
		)
		(pad "2" smd rect
			(at 0 1.392936 180)
			(size 2.1082 1.4478)
			(layers "F.Cu" "F.Mask" "F.Paste")
			(net "GND")
		)
	)
	(footprint ""
		(layer "F.Cu")
		(at 82.931 -107.95 90)
		(property "Reference" "R9358"
			(at 0 0 90)
			(layer "F.SilkS")
			(hide yes)
			(effects
				(font
					(size 1.27 1.27)
				)
			)
		)
		(property "Value" "2D2R2F-GP"
			(at 0.064008 -3.993896 90)
			(unlocked yes)
			(layer "F.Fab")
			(hide yes)
			(effects
				(font
					(size 1.016 1.016)
					(thickness 0.1524)
				)
			)
		)
		(property "Device Type" "R402H16"
			(at 0.064008 -5.517896 90)
			(unlocked yes)
			(layer "F.Fab")
			(hide yes)
			(effects
				(font
					(size 1.016 1.016)
					(thickness 0.1524)
				)
			)
		)
		(duplicate_pad_numbers_are_jumpers no)
		(fp_line
			(start 0.508 -0.9398)
			(end -0.508 -0.9398)
			(stroke
				(width 0.1524)
				(type default)
			)
			(layer "F.SilkS")
		)
		(fp_line
			(start -0.508 -0.9398)
			(end -0.508 0.9398)
			(stroke
				(width 0.1524)
				(type default)
			)
			(layer "F.SilkS")
		)
		(fp_rect
			(start -0.508 0.9398)
			(end 0.508 -0.9398)
			(stroke
				(width 0)
				(type default)
			)
			(fill no)
			(layer "F.CrtYd")
		)
		(fp_rect
			(start -0.508 0.9398)
			(end 0.508 -0.9398)
			(stroke
				(width 0)
				(type default)
			)
			(fill no)
			(layer "F.Fab")
		)
		(pad "1" smd custom
			(at 0 -0.4445 90)
			(size 0.1397 0.1397)
			(layers "F.Cu" "F.Mask" "F.Paste")
			(net "VDD_DIFF_4")
			(options
				(clearance outline)
				(anchor circle)
			)
			(primitives
				(gr_poly
					(pts
						(arc
							(start -0.1778 -0.2794)
							(mid -0.249642 -0.249642)
							(end -0.2794 -0.1778)
						)
						(arc
							(start -0.2794 0.1778)
							(mid -0.249642 0.249642)
							(end -0.1778 0.2794)
						)
						(arc
							(start 0.1778 0.2794)
							(mid 0.249642 0.249642)
							(end 0.2794 0.1778)
						)
						(arc
							(start 0.2794 -0.1778)
							(mid 0.249642 -0.249642)
							(end 0.1778 -0.2794)
						)
					)
					(width 0)
					(fill yes)
				)
			)
		)
		(pad "2" smd custom
			(at 0 0.4445 90)
			(size 0.1397 0.1397)
			(layers "F.Cu" "F.Mask" "F.Paste")
			(net "VDDA_4")
			(options
				(clearance outline)
				(anchor circle)
			)
			(primitives
				(gr_poly
					(pts
						(arc
							(start -0.1778 -0.2794)
							(mid -0.249642 -0.249642)
							(end -0.2794 -0.1778)
						)
						(arc
							(start -0.2794 0.1778)
							(mid -0.249642 0.249642)
							(end -0.1778 0.2794)
						)
						(arc
							(start 0.1778 0.2794)
							(mid 0.249642 0.249642)
							(end 0.2794 0.1778)
						)
						(arc
							(start 0.2794 -0.1778)
							(mid 0.249642 -0.249642)
							(end 0.1778 -0.2794)
						)
					)
					(width 0)
					(fill yes)
				)
			)
		)
	)
	(footprint ""
		(layer "F.Cu")
		(at 48.26 -242.062 180)
		(property "Reference" "U204"
			(at 0 0 180)
			(layer "F.SilkS")
			(hide yes)
			(effects
				(font
					(size 1.27 1.27)
				)
			)
		)
		(property "Value" "SN74LVC1G08DCKR-GP"
			(at -2.3368 -8.6868 180)
			(unlocked yes)
			(layer "F.Fab")
			(hide yes)
			(effects
				(font
					(size 1.016 1.016)
					(thickness 0.1524)
				)
			)
		)
		(property "Device Type" "SC70-5H44"
			(at -2.3114 -10.414 180)
			(unlocked yes)
			(layer "F.Fab")
			(hide yes)
			(effects
				(font
					(size 1.016 1.016)
					(thickness 0.1524)
				)
			)
		)
		(duplicate_pad_numbers_are_jumpers no)
		(fp_line
			(start 1.3843 -1.8034)
			(end 1.3843 -1.1176)
			(stroke
				(width 0.3302)
				(type default)
			)
			(layer "F.SilkS")
		)
		(fp_line
			(start 1.27 1.7018)
			(end -1.27 1.7018)
			(stroke
				(width 0.1524)
				(type default)
			)
			(layer "F.SilkS")
		)
		(fp_line
			(start 1.27 -1.7018)
			(end 1.27 1.7018)
			(stroke
				(width 0.1524)
				(type default)
			)
			(layer "F.SilkS")
		)
		(fp_line
			(start 0.6604 -1.8034)
			(end 1.3843 -1.8034)
			(stroke
				(width 0.3302)
				(type default)
			)
			(layer "F.SilkS")
		)
		(fp_line
			(start -1.27 1.7018)
			(end -1.27 -1.7018)
			(stroke
				(width 0.1524)
				(type default)
			)
			(layer "F.SilkS")
		)
		(fp_line
			(start -1.27 -1.7018)
			(end 1.27 -1.7018)
			(stroke
				(width 0.1524)
				(type default)
			)
			(layer "F.SilkS")
		)
		(fp_rect
			(start -1.524 1.9558)
			(end 1.524 -1.9558)
			(stroke
				(width 0)
				(type default)
			)
			(fill no)
			(layer "F.CrtYd")
		)
		(fp_poly
			(pts
				(xy -1.524 -1.9558) (xy 1.524 -1.9558) (xy 1.524 1.9558) (xy -1.524 1.9558)
			)
			(stroke
				(width 0)
				(type default)
			)
			(fill no)
			(layer "F.Fab")
		)
		(pad "1" smd rect
			(at 0.65024 -0.8255 180)
			(size 0.4064 1.2192)
			(layers "F.Cu" "F.Mask" "F.Paste")
			(net "SSD7_CLK0_OE_MOS_N")
		)
		(pad "2" smd rect
			(at 0 -0.8255 180)
			(size 0.4064 1.2192)
			(layers "F.Cu" "F.Mask" "F.Paste")
			(net "ATTN_LED_DR7_N")
		)
		(pad "3" smd rect
			(at -0.65024 -0.8255 180)
			(size 0.4064 1.2192)
			(layers "F.Cu" "F.Mask" "F.Paste")
			(net "GND")
		)
		(pad "4" smd rect
			(at -0.65024 0.8255 180)
			(size 0.4064 1.2192)
			(layers "F.Cu" "F.Mask" "F.Paste")
			(net "ATTN_LED_DR7_AND")
		)
		(pad "5" smd rect
			(at 0.65024 0.8255 180)
			(size 0.4064 1.2192)
			(layers "F.Cu" "F.Mask" "F.Paste")
			(net "P3V3")
		)
	)
	(footprint ""
		(layer "F.Cu")
		(at 38.1 -137.922 180)
		(property "Reference" "R9836"
			(at 0 0 180)
			(layer "F.SilkS")
			(hide yes)
			(effects
				(font
					(size 1.27 1.27)
				)
			)
		)
		(property "Value" "0R2J-2-GP"
			(at 0.064008 -3.993896 180)
			(unlocked yes)
			(layer "F.Fab")
			(hide yes)
			(effects
				(font
					(size 1.016 1.016)
					(thickness 0.1524)
				)
			)
		)
		(property "Device Type" "R402H16"
			(at 0.064008 -5.517896 180)
			(unlocked yes)
			(layer "F.Fab")
			(hide yes)
			(effects
				(font
					(size 1.016 1.016)
					(thickness 0.1524)
				)
			)
		)
		(duplicate_pad_numbers_are_jumpers no)
		(fp_line
			(start 0.508 -0.9398)
			(end -0.508 -0.9398)
			(stroke
				(width 0.1524)
				(type default)
			)
			(layer "F.SilkS")
		)
		(fp_line
			(start -0.508 -0.9398)
			(end -0.508 0.9398)
			(stroke
				(width 0.1524)
				(type default)
			)
			(layer "F.SilkS")
		)
		(fp_rect
			(start -0.508 0.9398)
			(end 0.508 -0.9398)
			(stroke
				(width 0)
				(type default)
			)
			(fill no)
			(layer "F.CrtYd")
		)
		(fp_rect
			(start -0.508 0.9398)
			(end 0.508 -0.9398)
			(stroke
				(width 0)
				(type default)
			)
			(fill no)
			(layer "F.Fab")
		)
		(pad "1" smd custom
			(at 0 -0.4445 180)
			(size 0.1397 0.1397)
			(layers "F.Cu" "F.Mask" "F.Paste")
			(net "ATTN_LED_DR8_R")
			(options
				(clearance outline)
				(anchor circle)
			)
			(primitives
				(gr_poly
					(pts
						(arc
							(start -0.1778 -0.2794)
							(mid -0.249642 -0.249642)
							(end -0.2794 -0.1778)
						)
						(arc
							(start -0.2794 0.1778)
							(mid -0.249642 0.249642)
							(end -0.1778 0.2794)
						)
						(arc
							(start 0.1778 0.2794)
							(mid 0.249642 0.249642)
							(end 0.2794 0.1778)
						)
						(arc
							(start 0.2794 -0.1778)
							(mid 0.249642 -0.249642)
							(end 0.1778 -0.2794)
						)
					)
					(width 0)
					(fill yes)
				)
			)
		)
		(pad "2" smd custom
			(at 0 0.4445 180)
			(size 0.1397 0.1397)
			(layers "F.Cu" "F.Mask" "F.Paste")
			(net "ATTN_LED_DR8_N")
			(options
				(clearance outline)
				(anchor circle)
			)
			(primitives
				(gr_poly
					(pts
						(arc
							(start -0.1778 -0.2794)
							(mid -0.249642 -0.249642)
							(end -0.2794 -0.1778)
						)
						(arc
							(start -0.2794 0.1778)
							(mid -0.249642 0.249642)
							(end -0.1778 0.2794)
						)
						(arc
							(start 0.1778 0.2794)
							(mid 0.249642 0.249642)
							(end 0.2794 0.1778)
						)
						(arc
							(start 0.2794 -0.1778)
							(mid 0.249642 -0.249642)
							(end 0.1778 -0.2794)
						)
					)
					(width 0)
					(fill yes)
				)
			)
		)
	)
	(footprint ""
		(layer "F.Cu")
		(at 24.892 -56.88711 90)
		(property "Reference" "Q99"
			(at 0 0 90)
			(layer "F.SilkS")
			(hide yes)
			(effects
				(font
					(size 1.27 1.27)
				)
			)
		)
		(property "Value" "2N7002A-7-GP"
			(at 0.127 -8.9662 90)
			(unlocked yes)
			(layer "F.Fab")
			(hide yes)
			(effects
				(font
					(size 1.016 1.016)
					(thickness 0.1524)
				)
			)
		)
		(property "Device Type" "SOT23DGS2D4H48"
			(at 0.127 -10.4902 90)
			(unlocked yes)
			(layer "F.Fab")
			(hide yes)
			(effects
				(font
					(size 1.016 1.016)
					(thickness 0.1524)
				)
			)
		)
		(duplicate_pad_numbers_are_jumpers no)
		(fp_line
			(start 1.651 -1.778)
			(end -1.651 -1.778)
			(stroke
				(width 0.1524)
				(type default)
			)
			(layer "F.SilkS")
		)
		(fp_line
			(start -1.651 -1.778)
			(end -1.651 1.778)
			(stroke
				(width 0.1524)
				(type default)
			)
			(layer "F.SilkS")
		)
		(fp_line
			(start 1.651 1.778)
			(end 1.651 -1.778)
			(stroke
				(width 0.1524)
				(type default)
			)
			(layer "F.SilkS")
		)
		(fp_line
			(start -1.651 1.778)
			(end 1.651 1.778)
			(stroke
				(width 0.1524)
				(type default)
			)
			(layer "F.SilkS")
		)
		(fp_poly
			(pts
				(xy -1.778 1.8796) (xy -1.778 -1.8796) (xy 1.778 -1.8796) (xy 1.778 1.8796)
			)
			(stroke
				(width 0)
				(type default)
			)
			(fill no)
			(layer "F.CrtYd")
		)
		(fp_poly
			(pts
				(xy -1.778 1.8796) (xy -1.778 -1.8796) (xy 1.778 -1.8796) (xy 1.778 1.8796)
			)
			(stroke
				(width 0)
				(type default)
			)
			(fill no)
			(layer "F.Fab")
		)
		(pad "D" smd custom
			(at 0 -0.9525 90)
			(size 0.1905 0.1905)
			(layers "F.Cu" "F.Mask" "F.Paste")
			(net "SSD14_CLK0_OE_MOS_N")
			(options
				(clearance outline)
				(anchor circle)
			)
			(primitives
				(gr_poly
					(pts
						(arc
							(start -0.1778 0.5715)
							(mid -0.321484 0.511984)
							(end -0.381 0.3683)
						)
						(arc
							(start -0.381 -0.3683)
							(mid -0.321484 -0.511984)
							(end -0.1778 -0.5715)
						)
						(arc
							(start 0.1778 -0.5715)
							(mid 0.321484 -0.511984)
							(end 0.381 -0.3683)
						)
						(arc
							(start 0.381 0.3683)
							(mid 0.321484 0.511984)
							(end 0.1778 0.5715)
						)
					)
					(width 0)
					(fill yes)
				)
			)
		)
		(pad "G" smd custom
			(at -0.98425 0.9525 90)
			(size 0.1905 0.1905)
			(layers "F.Cu" "F.Mask" "F.Paste")
			(net "SSD14_CLK0_OE_R_N")
			(options
				(clearance outline)
				(anchor circle)
			)
			(primitives
				(gr_poly
					(pts
						(arc
							(start -0.1778 0.5715)
							(mid -0.321484 0.511984)
							(end -0.381 0.3683)
						)
						(arc
							(start -0.381 -0.3683)
							(mid -0.321484 -0.511984)
							(end -0.1778 -0.5715)
						)
						(arc
							(start 0.1778 -0.5715)
							(mid 0.321484 -0.511984)
							(end 0.381 -0.3683)
						)
						(arc
							(start 0.381 0.3683)
							(mid 0.321484 0.511984)
							(end 0.1778 0.5715)
						)
					)
					(width 0)
					(fill yes)
				)
			)
		)
		(pad "S" smd custom
			(at 0.98425 0.9525 90)
			(size 0.1905 0.1905)
			(layers "F.Cu" "F.Mask" "F.Paste")
			(net "GND")
			(options
				(clearance outline)
				(anchor circle)
			)
			(primitives
				(gr_poly
					(pts
						(arc
							(start -0.1778 0.5715)
							(mid -0.321484 0.511984)
							(end -0.381 0.3683)
						)
						(arc
							(start -0.381 -0.3683)
							(mid -0.321484 -0.511984)
							(end -0.1778 -0.5715)
						)
						(arc
							(start 0.1778 -0.5715)
							(mid 0.321484 -0.511984)
							(end 0.381 -0.3683)
						)
						(arc
							(start 0.381 0.3683)
							(mid 0.321484 0.511984)
							(end 0.1778 0.5715)
						)
					)
					(width 0)
					(fill yes)
				)
			)
		)
	)
	(footprint ""
		(layer "F.Cu")
		(at 23.1648 -190.119)
		(property "Reference" "R559"
			(at 0 0 0)
			(layer "F.SilkS")
			(hide yes)
			(effects
				(font
					(size 1.27 1.27)
				)
			)
		)
		(property "Value" "200KR2F-L-GP"
			(at 0.064008 -3.993896 0)
			(unlocked yes)
			(layer "F.Fab")
			(hide yes)
			(effects
				(font
					(size 1.016 1.016)
					(thickness 0.1524)
				)
			)
		)
		(property "Device Type" "R402H16"
			(at 0.064008 -5.517896 0)
			(unlocked yes)
			(layer "F.Fab")
			(hide yes)
			(effects
				(font
					(size 1.016 1.016)
					(thickness 0.1524)
				)
			)
		)
		(duplicate_pad_numbers_are_jumpers no)
		(fp_line
			(start -0.508 -0.9398)
			(end -0.508 0.9398)
			(stroke
				(width 0.1524)
				(type default)
			)
			(layer "F.SilkS")
		)
		(fp_line
			(start 0.508 -0.9398)
			(end -0.508 -0.9398)
			(stroke
				(width 0.1524)
				(type default)
			)
			(layer "F.SilkS")
		)
		(fp_rect
			(start -0.508 0.9398)
			(end 0.508 -0.9398)
			(stroke
				(width 0)
				(type default)
			)
			(fill no)
			(layer "F.CrtYd")
		)
		(fp_rect
			(start -0.508 0.9398)
			(end 0.508 -0.9398)
			(stroke
				(width 0)
				(type default)
			)
			(fill no)
			(layer "F.Fab")
		)
		(pad "1" smd custom
			(at 0 -0.4445)
			(size 0.1397 0.1397)
			(layers "F.Cu" "F.Mask" "F.Paste")
			(net "SW_SSD8_R")
			(options
				(clearance outline)
				(anchor circle)
			)
			(primitives
				(gr_poly
					(pts
						(arc
							(start -0.1778 -0.2794)
							(mid -0.249642 -0.249642)
							(end -0.2794 -0.1778)
						)
						(arc
							(start -0.2794 0.1778)
							(mid -0.249642 0.249642)
							(end -0.1778 0.2794)
						)
						(arc
							(start 0.1778 0.2794)
							(mid 0.249642 0.249642)
							(end 0.2794 0.1778)
						)
						(arc
							(start 0.2794 -0.1778)
							(mid 0.249642 -0.249642)
							(end 0.1778 -0.2794)
						)
					)
					(width 0)
					(fill yes)
				)
			)
		)
		(pad "2" smd custom
			(at 0 0.4445)
			(size 0.1397 0.1397)
			(layers "F.Cu" "F.Mask" "F.Paste")
			(net "SW_SSD8_N")
			(options
				(clearance outline)
				(anchor circle)
			)
			(primitives
				(gr_poly
					(pts
						(arc
							(start -0.1778 -0.2794)
							(mid -0.249642 -0.249642)
							(end -0.2794 -0.1778)
						)
						(arc
							(start -0.2794 0.1778)
							(mid -0.249642 0.249642)
							(end -0.1778 0.2794)
						)
						(arc
							(start 0.1778 0.2794)
							(mid 0.249642 0.249642)
							(end 0.2794 0.1778)
						)
						(arc
							(start 0.2794 -0.1778)
							(mid 0.249642 -0.249642)
							(end 0.1778 -0.2794)
						)
					)
					(width 0)
					(fill yes)
				)
			)
		)
	)
	(footprint ""
		(layer "F.Cu")
		(at 222.123 -451.104)
		(property "Reference" "Q30"
			(at 0 0 0)
			(layer "F.SilkS")
			(hide yes)
			(effects
				(font
					(size 1.27 1.27)
				)
			)
		)
		(property "Value" "2N7002A-7-GP"
			(at 0.127 -8.9662 0)
			(unlocked yes)
			(layer "F.Fab")
			(hide yes)
			(effects
				(font
					(size 1.016 1.016)
					(thickness 0.1524)
				)
			)
		)
		(property "Device Type" "SOT23DGS2D4H48"
			(at 0.127 -10.4902 0)
			(unlocked yes)
			(layer "F.Fab")
			(hide yes)
			(effects
				(font
					(size 1.016 1.016)
					(thickness 0.1524)
				)
			)
		)
		(duplicate_pad_numbers_are_jumpers no)
		(fp_line
			(start -1.651 -1.778)
			(end -1.651 1.778)
			(stroke
				(width 0.1524)
				(type default)
			)
			(layer "F.SilkS")
		)
		(fp_line
			(start -1.651 1.778)
			(end 1.651 1.778)
			(stroke
				(width 0.1524)
				(type default)
			)
			(layer "F.SilkS")
		)
		(fp_line
			(start 1.651 -1.778)
			(end -1.651 -1.778)
			(stroke
				(width 0.1524)
				(type default)
			)
			(layer "F.SilkS")
		)
		(fp_line
			(start 1.651 1.778)
			(end 1.651 -1.778)
			(stroke
				(width 0.1524)
				(type default)
			)
			(layer "F.SilkS")
		)
		(fp_poly
			(pts
				(xy -1.778 1.8796) (xy -1.778 -1.8796) (xy 1.778 -1.8796) (xy 1.778 1.8796)
			)
			(stroke
				(width 0)
				(type default)
			)
			(fill no)
			(layer "F.CrtYd")
		)
		(fp_poly
			(pts
				(xy -1.778 1.8796) (xy -1.778 -1.8796) (xy 1.778 -1.8796) (xy 1.778 1.8796)
			)
			(stroke
				(width 0)
				(type default)
			)
			(fill no)
			(layer "F.Fab")
		)
		(pad "D" smd custom
			(at 0 -0.9525)
			(size 0.1905 0.1905)
			(layers "F.Cu" "F.Mask" "F.Paste")
			(net "ATTN_LED_DR0_MOS_N")
			(options
				(clearance outline)
				(anchor circle)
			)
			(primitives
				(gr_poly
					(pts
						(arc
							(start -0.1778 0.5715)
							(mid -0.321484 0.511984)
							(end -0.381 0.3683)
						)
						(arc
							(start -0.381 -0.3683)
							(mid -0.321484 -0.511984)
							(end -0.1778 -0.5715)
						)
						(arc
							(start 0.1778 -0.5715)
							(mid 0.321484 -0.511984)
							(end 0.381 -0.3683)
						)
						(arc
							(start 0.381 0.3683)
							(mid 0.321484 0.511984)
							(end 0.1778 0.5715)
						)
					)
					(width 0)
					(fill yes)
				)
			)
		)
		(pad "G" smd custom
			(at -0.98425 0.9525)
			(size 0.1905 0.1905)
			(layers "F.Cu" "F.Mask" "F.Paste")
			(net "SSD0_CLK0_OE_MOS_N")
			(options
				(clearance outline)
				(anchor circle)
			)
			(primitives
				(gr_poly
					(pts
						(arc
							(start -0.1778 0.5715)
							(mid -0.321484 0.511984)
							(end -0.381 0.3683)
						)
						(arc
							(start -0.381 -0.3683)
							(mid -0.321484 -0.511984)
							(end -0.1778 -0.5715)
						)
						(arc
							(start 0.1778 -0.5715)
							(mid 0.321484 -0.511984)
							(end 0.381 -0.3683)
						)
						(arc
							(start 0.381 0.3683)
							(mid 0.321484 0.511984)
							(end 0.1778 0.5715)
						)
					)
					(width 0)
					(fill yes)
				)
			)
		)
		(pad "S" smd custom
			(at 0.98425 0.9525)
			(size 0.1905 0.1905)
			(layers "F.Cu" "F.Mask" "F.Paste")
			(net "ATTN_LED_DR0_R")
			(options
				(clearance outline)
				(anchor circle)
			)
			(primitives
				(gr_poly
					(pts
						(arc
							(start -0.1778 0.5715)
							(mid -0.321484 0.511984)
							(end -0.381 0.3683)
						)
						(arc
							(start -0.381 -0.3683)
							(mid -0.321484 -0.511984)
							(end -0.1778 -0.5715)
						)
						(arc
							(start 0.1778 -0.5715)
							(mid 0.321484 -0.511984)
							(end 0.381 -0.3683)
						)
						(arc
							(start 0.381 0.3683)
							(mid 0.321484 0.511984)
							(end 0.1778 0.5715)
						)
					)
					(width 0)
					(fill yes)
				)
			)
		)
	)
	(footprint ""
		(layer "F.Cu")
		(at 22.1488 -498.9068)
		(property "Reference" "R9812"
			(at 0 0 0)
			(layer "F.SilkS")
			(hide yes)
			(effects
				(font
					(size 1.27 1.27)
				)
			)
		)
		(property "Value" "2K2R5F-GP"
			(at 0 -8.9535 0)
			(unlocked yes)
			(layer "F.Fab")
			(hide yes)
			(effects
				(font
					(size 1.27 1.016)
					(thickness 0.1524)
				)
			)
		)
		(property "Device Type" "R805H24"
			(at 0 -10.6299 0)
			(unlocked yes)
			(layer "F.Fab")
			(hide yes)
			(effects
				(font
					(size 1.27 1.016)
					(thickness 0.1524)
				)
			)
		)
		(duplicate_pad_numbers_are_jumpers no)
		(fp_line
			(start -0.889 -1.7018)
			(end -0.889 0.2794)
			(stroke
				(width 0.1524)
				(type default)
			)
			(layer "F.SilkS")
		)
		(fp_line
			(start -0.889 0.0762)
			(end -0.889 1.7018)
			(stroke
				(width 0.1524)
				(type default)
			)
			(layer "F.SilkS")
		)
		(fp_line
			(start -0.889 1.7018)
			(end 0.889 1.7018)
			(stroke
				(width 0.1524)
				(type default)
			)
			(layer "F.SilkS")
		)
		(fp_line
			(start 0.889 -1.7018)
			(end -0.889 -1.7018)
			(stroke
				(width 0.1524)
				(type default)
			)
			(layer "F.SilkS")
		)
		(fp_line
			(start 0.889 -1.7018)
			(end 0.889 -0.381)
			(stroke
				(width 0.1524)
				(type default)
			)
			(layer "F.SilkS")
		)
		(fp_line
			(start 0.889 1.7018)
			(end 0.889 -0.508)
			(stroke
				(width 0.1524)
				(type default)
			)
			(layer "F.SilkS")
		)
		(fp_poly
			(pts
				(xy 0.9652 -1.778) (xy 0.9652 1.778) (xy -0.9652 1.778) (xy -0.9652 -1.778)
			)
			(stroke
				(width 0)
				(type default)
			)
			(fill no)
			(layer "F.CrtYd")
		)
		(fp_rect
			(start -0.9652 1.778)
			(end 0.9652 -1.778)
			(stroke
				(width 0)
				(type default)
			)
			(fill no)
			(layer "F.Fab")
		)
		(pad "1" smd rect
			(at 0 -0.9652)
			(size 1.397 1.143)
			(layers "F.Cu" "F.Mask" "F.Paste")
			(net "P12V_SSD5")
		)
		(pad "2" smd rect
			(at 0 0.9652)
			(size 1.397 1.143)
			(layers "F.Cu" "F.Mask" "F.Paste")
			(net "P12V_MOST5_GATE_D")
		)
	)
	(footprint ""
		(layer "F.Cu")
		(at 215.9 -300.9646 -90)
		(property "Reference" "Q37"
			(at 0 0 270)
			(layer "F.SilkS")
			(hide yes)
			(effects
				(font
					(size 1.27 1.27)
				)
			)
		)
		(property "Value" "2N7002A-7-GP"
			(at 0.127 -8.9662 270)
			(unlocked yes)
			(layer "F.Fab")
			(hide yes)
			(effects
				(font
					(size 1.016 1.016)
					(thickness 0.1524)
				)
			)
		)
		(property "Device Type" "SOT23DGS2D4H48"
			(at 0.127 -10.4902 270)
			(unlocked yes)
			(layer "F.Fab")
			(hide yes)
			(effects
				(font
					(size 1.016 1.016)
					(thickness 0.1524)
				)
			)
		)
		(duplicate_pad_numbers_are_jumpers no)
		(fp_line
			(start -1.651 1.778)
			(end 1.651 1.778)
			(stroke
				(width 0.1524)
				(type default)
			)
			(layer "F.SilkS")
		)
		(fp_line
			(start 1.651 1.778)
			(end 1.651 -1.778)
			(stroke
				(width 0.1524)
				(type default)
			)
			(layer "F.SilkS")
		)
		(fp_line
			(start -1.651 -1.778)
			(end -1.651 1.778)
			(stroke
				(width 0.1524)
				(type default)
			)
			(layer "F.SilkS")
		)
		(fp_line
			(start 1.651 -1.778)
			(end -1.651 -1.778)
			(stroke
				(width 0.1524)
				(type default)
			)
			(layer "F.SilkS")
		)
		(fp_poly
			(pts
				(xy -1.778 1.8796) (xy -1.778 -1.8796) (xy 1.778 -1.8796) (xy 1.778 1.8796)
			)
			(stroke
				(width 0)
				(type default)
			)
			(fill no)
			(layer "F.CrtYd")
		)
		(fp_poly
			(pts
				(xy -1.778 1.8796) (xy -1.778 -1.8796) (xy 1.778 -1.8796) (xy 1.778 1.8796)
			)
			(stroke
				(width 0)
				(type default)
			)
			(fill no)
			(layer "F.Fab")
		)
		(pad "D" smd custom
			(at 0 -0.9525 270)
			(size 0.1905 0.1905)
			(layers "F.Cu" "F.Mask" "F.Paste")
			(net "P12V_MOST2_GATE_D")
			(options
				(clearance outline)
				(anchor circle)
			)
			(primitives
				(gr_poly
					(pts
						(arc
							(start -0.1778 0.5715)
							(mid -0.321484 0.511984)
							(end -0.381 0.3683)
						)
						(arc
							(start -0.381 -0.3683)
							(mid -0.321484 -0.511984)
							(end -0.1778 -0.5715)
						)
						(arc
							(start 0.1778 -0.5715)
							(mid 0.321484 -0.511984)
							(end 0.381 -0.3683)
						)
						(arc
							(start 0.381 0.3683)
							(mid 0.321484 0.511984)
							(end 0.1778 0.5715)
						)
					)
					(width 0)
					(fill yes)
				)
			)
		)
		(pad "G" smd custom
			(at -0.98425 0.9525 270)
			(size 0.1905 0.1905)
			(layers "F.Cu" "F.Mask" "F.Paste")
			(net "P12V_MOST2_GATE")
			(options
				(clearance outline)
				(anchor circle)
			)
			(primitives
				(gr_poly
					(pts
						(arc
							(start -0.1778 0.5715)
							(mid -0.321484 0.511984)
							(end -0.381 0.3683)
						)
						(arc
							(start -0.381 -0.3683)
							(mid -0.321484 -0.511984)
							(end -0.1778 -0.5715)
						)
						(arc
							(start 0.1778 -0.5715)
							(mid 0.321484 -0.511984)
							(end 0.381 -0.3683)
						)
						(arc
							(start 0.381 0.3683)
							(mid 0.321484 0.511984)
							(end 0.1778 0.5715)
						)
					)
					(width 0)
					(fill yes)
				)
			)
		)
		(pad "S" smd custom
			(at 0.98425 0.9525 270)
			(size 0.1905 0.1905)
			(layers "F.Cu" "F.Mask" "F.Paste")
			(net "GND")
			(options
				(clearance outline)
				(anchor circle)
			)
			(primitives
				(gr_poly
					(pts
						(arc
							(start -0.1778 0.5715)
							(mid -0.321484 0.511984)
							(end -0.381 0.3683)
						)
						(arc
							(start -0.381 -0.3683)
							(mid -0.321484 -0.511984)
							(end -0.1778 -0.5715)
						)
						(arc
							(start 0.1778 -0.5715)
							(mid 0.321484 -0.511984)
							(end 0.381 -0.3683)
						)
						(arc
							(start 0.381 0.3683)
							(mid 0.321484 0.511984)
							(end 0.1778 0.5715)
						)
					)
					(width 0)
					(fill yes)
				)
			)
		)
	)
	(footprint ""
		(layer "F.Cu")
		(at 31.369 -197.9676 -90)
		(property "Reference" "Q67"
			(at 0 0 270)
			(layer "F.SilkS")
			(hide yes)
			(effects
				(font
					(size 1.27 1.27)
				)
			)
		)
		(property "Value" "2N7002A-7-GP"
			(at 0.127 -8.9662 270)
			(unlocked yes)
			(layer "F.Fab")
			(hide yes)
			(effects
				(font
					(size 1.016 1.016)
					(thickness 0.1524)
				)
			)
		)
		(property "Device Type" "SOT23DGS2D4H48"
			(at 0.127 -10.4902 270)
			(unlocked yes)
			(layer "F.Fab")
			(hide yes)
			(effects
				(font
					(size 1.016 1.016)
					(thickness 0.1524)
				)
			)
		)
		(duplicate_pad_numbers_are_jumpers no)
		(fp_line
			(start -1.651 1.778)
			(end 1.651 1.778)
			(stroke
				(width 0.1524)
				(type default)
			)
			(layer "F.SilkS")
		)
		(fp_line
			(start 1.651 1.778)
			(end 1.651 -1.778)
			(stroke
				(width 0.1524)
				(type default)
			)
			(layer "F.SilkS")
		)
		(fp_line
			(start -1.651 -1.778)
			(end -1.651 1.778)
			(stroke
				(width 0.1524)
				(type default)
			)
			(layer "F.SilkS")
		)
		(fp_line
			(start 1.651 -1.778)
			(end -1.651 -1.778)
			(stroke
				(width 0.1524)
				(type default)
			)
			(layer "F.SilkS")
		)
		(fp_poly
			(pts
				(xy -1.778 1.8796) (xy -1.778 -1.8796) (xy 1.778 -1.8796) (xy 1.778 1.8796)
			)
			(stroke
				(width 0)
				(type default)
			)
			(fill no)
			(layer "F.CrtYd")
		)
		(fp_poly
			(pts
				(xy -1.778 1.8796) (xy -1.778 -1.8796) (xy 1.778 -1.8796) (xy 1.778 1.8796)
			)
			(stroke
				(width 0)
				(type default)
			)
			(fill no)
			(layer "F.Fab")
		)
		(pad "D" smd custom
			(at 0 -0.9525 270)
			(size 0.1905 0.1905)
			(layers "F.Cu" "F.Mask" "F.Paste")
			(net "P12V_MOST8_GATE_D")
			(options
				(clearance outline)
				(anchor circle)
			)
			(primitives
				(gr_poly
					(pts
						(arc
							(start -0.1778 0.5715)
							(mid -0.321484 0.511984)
							(end -0.381 0.3683)
						)
						(arc
							(start -0.381 -0.3683)
							(mid -0.321484 -0.511984)
							(end -0.1778 -0.5715)
						)
						(arc
							(start 0.1778 -0.5715)
							(mid 0.321484 -0.511984)
							(end 0.381 -0.3683)
						)
						(arc
							(start 0.381 0.3683)
							(mid 0.321484 0.511984)
							(end 0.1778 0.5715)
						)
					)
					(width 0)
					(fill yes)
				)
			)
		)
		(pad "G" smd custom
			(at -0.98425 0.9525 270)
			(size 0.1905 0.1905)
			(layers "F.Cu" "F.Mask" "F.Paste")
			(net "P12V_MOST8_GATE")
			(options
				(clearance outline)
				(anchor circle)
			)
			(primitives
				(gr_poly
					(pts
						(arc
							(start -0.1778 0.5715)
							(mid -0.321484 0.511984)
							(end -0.381 0.3683)
						)
						(arc
							(start -0.381 -0.3683)
							(mid -0.321484 -0.511984)
							(end -0.1778 -0.5715)
						)
						(arc
							(start 0.1778 -0.5715)
							(mid 0.321484 -0.511984)
							(end 0.381 -0.3683)
						)
						(arc
							(start 0.381 0.3683)
							(mid 0.321484 0.511984)
							(end 0.1778 0.5715)
						)
					)
					(width 0)
					(fill yes)
				)
			)
		)
		(pad "S" smd custom
			(at 0.98425 0.9525 270)
			(size 0.1905 0.1905)
			(layers "F.Cu" "F.Mask" "F.Paste")
			(net "GND")
			(options
				(clearance outline)
				(anchor circle)
			)
			(primitives
				(gr_poly
					(pts
						(arc
							(start -0.1778 0.5715)
							(mid -0.321484 0.511984)
							(end -0.381 0.3683)
						)
						(arc
							(start -0.381 -0.3683)
							(mid -0.321484 -0.511984)
							(end -0.1778 -0.5715)
						)
						(arc
							(start 0.1778 -0.5715)
							(mid 0.321484 -0.511984)
							(end 0.381 -0.3683)
						)
						(arc
							(start 0.381 0.3683)
							(mid 0.321484 0.511984)
							(end 0.1778 0.5715)
						)
					)
					(width 0)
					(fill yes)
				)
			)
		)
	)
	(footprint ""
		(layer "F.Cu")
		(at 24.003 -260.473952 -90)
		(property "Reference" "SR1145"
			(at 0 0 270)
			(layer "F.SilkS")
			(hide yes)
			(effects
				(font
					(size 1.27 1.27)
				)
			)
		)
		(property "Value" "4K7R2F-GP"
			(at 0.064008 -3.993896 270)
			(unlocked yes)
			(layer "F.Fab")
			(hide yes)
			(effects
				(font
					(size 1.016 1.016)
					(thickness 0.1524)
				)
			)
		)
		(property "Device Type" "R402H16"
			(at 0.064008 -5.517896 270)
			(unlocked yes)
			(layer "F.Fab")
			(hide yes)
			(effects
				(font
					(size 1.016 1.016)
					(thickness 0.1524)
				)
			)
		)
		(duplicate_pad_numbers_are_jumpers no)
		(fp_line
			(start -0.508 -0.9398)
			(end -0.508 0.9398)
			(stroke
				(width 0.1524)
				(type default)
			)
			(layer "F.SilkS")
		)
		(fp_line
			(start 0.508 -0.9398)
			(end -0.508 -0.9398)
			(stroke
				(width 0.1524)
				(type default)
			)
			(layer "F.SilkS")
		)
		(fp_rect
			(start -0.508 0.9398)
			(end 0.508 -0.9398)
			(stroke
				(width 0)
				(type default)
			)
			(fill no)
			(layer "F.CrtYd")
		)
		(fp_rect
			(start -0.508 0.9398)
			(end 0.508 -0.9398)
			(stroke
				(width 0)
				(type default)
			)
			(fill no)
			(layer "F.Fab")
		)
		(pad "1" smd custom
			(at 0 -0.4445 270)
			(size 0.1397 0.1397)
			(layers "F.Cu" "F.Mask" "F.Paste")
			(net "P3V3")
			(options
				(clearance outline)
				(anchor circle)
			)
			(primitives
				(gr_poly
					(pts
						(arc
							(start -0.1778 -0.2794)
							(mid -0.249642 -0.249642)
							(end -0.2794 -0.1778)
						)
						(arc
							(start -0.2794 0.1778)
							(mid -0.249642 0.249642)
							(end -0.1778 0.2794)
						)
						(arc
							(start 0.1778 0.2794)
							(mid 0.249642 0.249642)
							(end 0.2794 0.1778)
						)
						(arc
							(start 0.2794 -0.1778)
							(mid 0.249642 -0.249642)
							(end 0.1778 -0.2794)
						)
					)
					(width 0)
					(fill yes)
				)
			)
		)
		(pad "2" smd custom
			(at 0 0.4445 270)
			(size 0.1397 0.1397)
			(layers "F.Cu" "F.Mask" "F.Paste")
			(net "SSD12_CLK0_OE_MOS_N")
			(options
				(clearance outline)
				(anchor circle)
			)
			(primitives
				(gr_poly
					(pts
						(arc
							(start -0.1778 -0.2794)
							(mid -0.249642 -0.249642)
							(end -0.2794 -0.1778)
						)
						(arc
							(start -0.2794 0.1778)
							(mid -0.249642 0.249642)
							(end -0.1778 0.2794)
						)
						(arc
							(start 0.1778 0.2794)
							(mid 0.249642 0.249642)
							(end 0.2794 0.1778)
						)
						(arc
							(start 0.2794 -0.1778)
							(mid 0.249642 -0.249642)
							(end 0.1778 -0.2794)
						)
					)
					(width 0)
					(fill yes)
				)
			)
		)
	)
	(footprint ""
		(layer "F.Cu")
		(at 15.5067 -498.7417 180)
		(property "Reference" "R9814"
			(at 0 0 180)
			(layer "F.SilkS")
			(hide yes)
			(effects
				(font
					(size 1.27 1.27)
				)
			)
		)
		(property "Value" "47KR2J-2-GP"
			(at 0.064008 -3.993896 180)
			(unlocked yes)
			(layer "F.Fab")
			(hide yes)
			(effects
				(font
					(size 1.016 1.016)
					(thickness 0.1524)
				)
			)
		)
		(property "Device Type" "R402H16"
			(at 0.064008 -5.517896 180)
			(unlocked yes)
			(layer "F.Fab")
			(hide yes)
			(effects
				(font
					(size 1.016 1.016)
					(thickness 0.1524)
				)
			)
		)
		(duplicate_pad_numbers_are_jumpers no)
		(fp_line
			(start 0.508 -0.9398)
			(end -0.508 -0.9398)
			(stroke
				(width 0.1524)
				(type default)
			)
			(layer "F.SilkS")
		)
		(fp_line
			(start -0.508 -0.9398)
			(end -0.508 0.9398)
			(stroke
				(width 0.1524)
				(type default)
			)
			(layer "F.SilkS")
		)
		(fp_rect
			(start -0.508 0.9398)
			(end 0.508 -0.9398)
			(stroke
				(width 0)
				(type default)
			)
			(fill no)
			(layer "F.CrtYd")
		)
		(fp_rect
			(start -0.508 0.9398)
			(end 0.508 -0.9398)
			(stroke
				(width 0)
				(type default)
			)
			(fill no)
			(layer "F.Fab")
		)
		(pad "1" smd custom
			(at 0 -0.4445 180)
			(size 0.1397 0.1397)
			(layers "F.Cu" "F.Mask" "F.Paste")
			(net "P12V")
			(options
				(clearance outline)
				(anchor circle)
			)
			(primitives
				(gr_poly
					(pts
						(arc
							(start -0.1778 -0.2794)
							(mid -0.249642 -0.249642)
							(end -0.2794 -0.1778)
						)
						(arc
							(start -0.2794 0.1778)
							(mid -0.249642 0.249642)
							(end -0.1778 0.2794)
						)
						(arc
							(start 0.1778 0.2794)
							(mid 0.249642 0.249642)
							(end 0.2794 0.1778)
						)
						(arc
							(start 0.2794 -0.1778)
							(mid 0.249642 -0.249642)
							(end 0.1778 -0.2794)
						)
					)
					(width 0)
					(fill yes)
				)
			)
		)
		(pad "2" smd custom
			(at 0 0.4445 180)
			(size 0.1397 0.1397)
			(layers "F.Cu" "F.Mask" "F.Paste")
			(net "P12V_MOST5_GATE")
			(options
				(clearance outline)
				(anchor circle)
			)
			(primitives
				(gr_poly
					(pts
						(arc
							(start -0.1778 -0.2794)
							(mid -0.249642 -0.249642)
							(end -0.2794 -0.1778)
						)
						(arc
							(start -0.2794 0.1778)
							(mid -0.249642 0.249642)
							(end -0.1778 0.2794)
						)
						(arc
							(start 0.1778 0.2794)
							(mid 0.249642 0.249642)
							(end 0.2794 0.1778)
						)
						(arc
							(start 0.2794 -0.1778)
							(mid 0.249642 -0.249642)
							(end 0.1778 -0.2794)
						)
					)
					(width 0)
					(fill yes)
				)
			)
		)
	)
	(footprint ""
		(layer "F.Cu")
		(at 208.407 -44.704)
		(property "Reference" "R338"
			(at 0 0 0)
			(layer "F.SilkS")
			(hide yes)
			(effects
				(font
					(size 1.27 1.27)
				)
			)
		)
		(property "Value" "4K7R2J-2-GP"
			(at 0.064008 -3.993896 0)
			(unlocked yes)
			(layer "F.Fab")
			(hide yes)
			(effects
				(font
					(size 1.016 1.016)
					(thickness 0.1524)
				)
			)
		)
		(property "Device Type" "R402H16"
			(at 0.064008 -5.517896 0)
			(unlocked yes)
			(layer "F.Fab")
			(hide yes)
			(effects
				(font
					(size 1.016 1.016)
					(thickness 0.1524)
				)
			)
		)
		(duplicate_pad_numbers_are_jumpers no)
		(fp_line
			(start -0.508 -0.9398)
			(end -0.508 0.9398)
			(stroke
				(width 0.1524)
				(type default)
			)
			(layer "F.SilkS")
		)
		(fp_line
			(start 0.508 -0.9398)
			(end -0.508 -0.9398)
			(stroke
				(width 0.1524)
				(type default)
			)
			(layer "F.SilkS")
		)
		(fp_rect
			(start -0.508 0.9398)
			(end 0.508 -0.9398)
			(stroke
				(width 0)
				(type default)
			)
			(fill no)
			(layer "F.CrtYd")
		)
		(fp_rect
			(start -0.508 0.9398)
			(end 0.508 -0.9398)
			(stroke
				(width 0)
				(type default)
			)
			(fill no)
			(layer "F.Fab")
		)
		(pad "1" smd custom
			(at 0 -0.4445)
			(size 0.1397 0.1397)
			(layers "F.Cu" "F.Mask" "F.Paste")
			(net "I2C_B_TMP3_A0")
			(options
				(clearance outline)
				(anchor circle)
			)
			(primitives
				(gr_poly
					(pts
						(arc
							(start -0.1778 -0.2794)
							(mid -0.249642 -0.249642)
							(end -0.2794 -0.1778)
						)
						(arc
							(start -0.2794 0.1778)
							(mid -0.249642 0.249642)
							(end -0.1778 0.2794)
						)
						(arc
							(start 0.1778 0.2794)
							(mid 0.249642 0.249642)
							(end 0.2794 0.1778)
						)
						(arc
							(start 0.2794 -0.1778)
							(mid 0.249642 -0.249642)
							(end 0.1778 -0.2794)
						)
					)
					(width 0)
					(fill yes)
				)
			)
		)
		(pad "2" smd custom
			(at 0 0.4445)
			(size 0.1397 0.1397)
			(layers "F.Cu" "F.Mask" "F.Paste")
			(net "GND")
			(options
				(clearance outline)
				(anchor circle)
			)
			(primitives
				(gr_poly
					(pts
						(arc
							(start -0.1778 -0.2794)
							(mid -0.249642 -0.249642)
							(end -0.2794 -0.1778)
						)
						(arc
							(start -0.2794 0.1778)
							(mid -0.249642 0.249642)
							(end -0.1778 0.2794)
						)
						(arc
							(start 0.1778 0.2794)
							(mid 0.249642 0.249642)
							(end 0.2794 0.1778)
						)
						(arc
							(start 0.2794 -0.1778)
							(mid 0.249642 -0.249642)
							(end 0.1778 -0.2794)
						)
					)
					(width 0)
					(fill yes)
				)
			)
		)
	)
	(footprint ""
		(layer "F.Cu")
		(at 97.155 -224.282)
		(property "Reference" "R9603"
			(at 0 0 0)
			(layer "F.SilkS")
			(hide yes)
			(effects
				(font
					(size 1.27 1.27)
				)
			)
		)
		(property "Value" "10R2F-L-GP"
			(at 0.064008 -3.993896 0)
			(unlocked yes)
			(layer "F.Fab")
			(hide yes)
			(effects
				(font
					(size 1.016 1.016)
					(thickness 0.1524)
				)
			)
		)
		(property "Device Type" "R402H14"
			(at 0.064008 -5.517896 0)
			(unlocked yes)
			(layer "F.Fab")
			(hide yes)
			(effects
				(font
					(size 1.016 1.016)
					(thickness 0.1524)
				)
			)
		)
		(duplicate_pad_numbers_are_jumpers no)
		(fp_line
			(start -0.508 -0.9398)
			(end -0.508 0.9398)
			(stroke
				(width 0.1524)
				(type default)
			)
			(layer "F.SilkS")
		)
		(fp_line
			(start 0.508 -0.9398)
			(end -0.508 -0.9398)
			(stroke
				(width 0.1524)
				(type default)
			)
			(layer "F.SilkS")
		)
		(fp_rect
			(start -0.508 0.9398)
			(end 0.508 -0.9398)
			(stroke
				(width 0)
				(type default)
			)
			(fill no)
			(layer "F.CrtYd")
		)
		(fp_rect
			(start -0.508 0.9398)
			(end 0.508 -0.9398)
			(stroke
				(width 0)
				(type default)
			)
			(fill no)
			(layer "F.Fab")
		)
		(pad "1" smd custom
			(at 0 -0.4445)
			(size 0.1397 0.1397)
			(layers "F.Cu" "F.Mask" "F.Paste")
			(net "SSD7_CLK0_OE_N")
			(options
				(clearance outline)
				(anchor circle)
			)
			(primitives
				(gr_poly
					(pts
						(arc
							(start -0.1778 -0.2794)
							(mid -0.249642 -0.249642)
							(end -0.2794 -0.1778)
						)
						(arc
							(start -0.2794 0.1778)
							(mid -0.249642 0.249642)
							(end -0.1778 0.2794)
						)
						(arc
							(start 0.1778 0.2794)
							(mid 0.249642 0.249642)
							(end 0.2794 0.1778)
						)
						(arc
							(start 0.2794 -0.1778)
							(mid 0.249642 -0.249642)
							(end 0.1778 -0.2794)
						)
					)
					(width 0)
					(fill yes)
				)
			)
		)
		(pad "2" smd custom
			(at 0 0.4445)
			(size 0.1397 0.1397)
			(layers "F.Cu" "F.Mask" "F.Paste")
			(net "SSD7_CLK0_OE_R_N")
			(options
				(clearance outline)
				(anchor circle)
			)
			(primitives
				(gr_poly
					(pts
						(arc
							(start -0.1778 -0.2794)
							(mid -0.249642 -0.249642)
							(end -0.2794 -0.1778)
						)
						(arc
							(start -0.2794 0.1778)
							(mid -0.249642 0.249642)
							(end -0.1778 0.2794)
						)
						(arc
							(start 0.1778 0.2794)
							(mid 0.249642 0.249642)
							(end 0.2794 0.1778)
						)
						(arc
							(start 0.2794 -0.1778)
							(mid 0.249642 -0.249642)
							(end 0.1778 -0.2794)
						)
					)
					(width 0)
					(fill yes)
				)
			)
		)
	)
	(footprint ""
		(layer "F.Cu")
		(at 27.5844 -414.274)
		(property "Reference" "PC1182"
			(at 0 0 0)
			(layer "F.SilkS")
			(hide yes)
			(effects
				(font
					(size 1.27 1.27)
				)
			)
		)
		(property "Value" "SCD1U50V3KX-GP"
			(at 0 -2.8194 0)
			(unlocked yes)
			(layer "F.Fab")
			(hide yes)
			(effects
				(font
					(size 1.016 1.016)
					(thickness 0.1524)
				)
			)
		)
		(property "Device Type" "C603H36"
			(at 0 -4.3434 0)
			(unlocked yes)
			(layer "F.Fab")
			(hide yes)
			(effects
				(font
					(size 1.016 1.016)
					(thickness 0.1524)
				)
			)
		)
		(duplicate_pad_numbers_are_jumpers no)
		(fp_line
			(start 0.508 0)
			(end -0.508 0)
			(stroke
				(width 0.2032)
				(type default)
			)
			(layer "F.SilkS")
		)
		(fp_rect
			(start -0.5842 1.3335)
			(end 0.5842 -1.3335)
			(stroke
				(width 0)
				(type default)
			)
			(fill no)
			(layer "F.CrtYd")
		)
		(fp_rect
			(start -0.5842 1.3335)
			(end 0.5842 -1.3335)
			(stroke
				(width 0)
				(type default)
			)
			(fill no)
			(layer "F.Fab")
		)
		(pad "1" smd custom
			(at 0 -0.762)
			(size 0.2159 0.2159)
			(layers "F.Cu" "F.Mask" "F.Paste")
			(net "P12V_SSD10")
			(options
				(clearance outline)
				(anchor circle)
			)
			(primitives
				(gr_poly
					(pts
						(arc
							(start -0.3302 -0.4318)
							(mid -0.402042 -0.402042)
							(end -0.4318 -0.3302)
						)
						(arc
							(start -0.4318 0.3302)
							(mid -0.402042 0.402042)
							(end -0.3302 0.4318)
						)
						(arc
							(start 0.3302 0.4318)
							(mid 0.402042 0.402042)
							(end 0.4318 0.3302)
						)
						(arc
							(start 0.4318 -0.3302)
							(mid 0.402042 -0.402042)
							(end 0.3302 -0.4318)
						)
					)
					(width 0)
					(fill yes)
				)
			)
		)
		(pad "2" smd custom
			(at 0 0.762)
			(size 0.2159 0.2159)
			(layers "F.Cu" "F.Mask" "F.Paste")
			(net "GND")
			(options
				(clearance outline)
				(anchor circle)
			)
			(primitives
				(gr_poly
					(pts
						(arc
							(start -0.3302 -0.4318)
							(mid -0.402042 -0.402042)
							(end -0.4318 -0.3302)
						)
						(arc
							(start -0.4318 0.3302)
							(mid -0.402042 0.402042)
							(end -0.3302 0.4318)
						)
						(arc
							(start 0.3302 0.4318)
							(mid 0.402042 0.402042)
							(end 0.4318 0.3302)
						)
						(arc
							(start 0.4318 -0.3302)
							(mid 0.402042 -0.402042)
							(end 0.3302 -0.4318)
						)
					)
					(width 0)
					(fill yes)
				)
			)
		)
	)
	(footprint ""
		(layer "F.Cu")
		(at 202.752706 -498.959378 -90)
		(property "Reference" "Q24"
			(at 0 0 270)
			(layer "F.SilkS")
			(hide yes)
			(effects
				(font
					(size 1.27 1.27)
				)
			)
		)
		(property "Value" "2N7002A-7-GP"
			(at 0.127 -8.9662 270)
			(unlocked yes)
			(layer "F.Fab")
			(hide yes)
			(effects
				(font
					(size 1.016 1.016)
					(thickness 0.1524)
				)
			)
		)
		(property "Device Type" "SOT23DGS2D4H48"
			(at 0.127 -10.4902 270)
			(unlocked yes)
			(layer "F.Fab")
			(hide yes)
			(effects
				(font
					(size 1.016 1.016)
					(thickness 0.1524)
				)
			)
		)
		(duplicate_pad_numbers_are_jumpers no)
		(fp_line
			(start -1.651 1.778)
			(end 1.651 1.778)
			(stroke
				(width 0.1524)
				(type default)
			)
			(layer "F.SilkS")
		)
		(fp_line
			(start 1.651 1.778)
			(end 1.651 -1.778)
			(stroke
				(width 0.1524)
				(type default)
			)
			(layer "F.SilkS")
		)
		(fp_line
			(start -1.651 -1.778)
			(end -1.651 1.778)
			(stroke
				(width 0.1524)
				(type default)
			)
			(layer "F.SilkS")
		)
		(fp_line
			(start 1.651 -1.778)
			(end -1.651 -1.778)
			(stroke
				(width 0.1524)
				(type default)
			)
			(layer "F.SilkS")
		)
		(fp_poly
			(pts
				(xy -1.778 1.8796) (xy -1.778 -1.8796) (xy 1.778 -1.8796) (xy 1.778 1.8796)
			)
			(stroke
				(width 0)
				(type default)
			)
			(fill no)
			(layer "F.CrtYd")
		)
		(fp_poly
			(pts
				(xy -1.778 1.8796) (xy -1.778 -1.8796) (xy 1.778 -1.8796) (xy 1.778 1.8796)
			)
			(stroke
				(width 0)
				(type default)
			)
			(fill no)
			(layer "F.Fab")
		)
		(pad "D" smd custom
			(at 0 -0.9525 270)
			(size 0.1905 0.1905)
			(layers "F.Cu" "F.Mask" "F.Paste")
			(net "P12V_MOST0_GATE_D")
			(options
				(clearance outline)
				(anchor circle)
			)
			(primitives
				(gr_poly
					(pts
						(arc
							(start -0.1778 0.5715)
							(mid -0.321484 0.511984)
							(end -0.381 0.3683)
						)
						(arc
							(start -0.381 -0.3683)
							(mid -0.321484 -0.511984)
							(end -0.1778 -0.5715)
						)
						(arc
							(start 0.1778 -0.5715)
							(mid 0.321484 -0.511984)
							(end 0.381 -0.3683)
						)
						(arc
							(start 0.381 0.3683)
							(mid 0.321484 0.511984)
							(end 0.1778 0.5715)
						)
					)
					(width 0)
					(fill yes)
				)
			)
		)
		(pad "G" smd custom
			(at -0.98425 0.9525 270)
			(size 0.1905 0.1905)
			(layers "F.Cu" "F.Mask" "F.Paste")
			(net "P12V_MOST0_GATE")
			(options
				(clearance outline)
				(anchor circle)
			)
			(primitives
				(gr_poly
					(pts
						(arc
							(start -0.1778 0.5715)
							(mid -0.321484 0.511984)
							(end -0.381 0.3683)
						)
						(arc
							(start -0.381 -0.3683)
							(mid -0.321484 -0.511984)
							(end -0.1778 -0.5715)
						)
						(arc
							(start 0.1778 -0.5715)
							(mid 0.321484 -0.511984)
							(end 0.381 -0.3683)
						)
						(arc
							(start 0.381 0.3683)
							(mid 0.321484 0.511984)
							(end 0.1778 0.5715)
						)
					)
					(width 0)
					(fill yes)
				)
			)
		)
		(pad "S" smd custom
			(at 0.98425 0.9525 270)
			(size 0.1905 0.1905)
			(layers "F.Cu" "F.Mask" "F.Paste")
			(net "GND")
			(options
				(clearance outline)
				(anchor circle)
			)
			(primitives
				(gr_poly
					(pts
						(arc
							(start -0.1778 0.5715)
							(mid -0.321484 0.511984)
							(end -0.381 0.3683)
						)
						(arc
							(start -0.381 -0.3683)
							(mid -0.321484 -0.511984)
							(end -0.1778 -0.5715)
						)
						(arc
							(start 0.1778 -0.5715)
							(mid 0.321484 -0.511984)
							(end 0.381 -0.3683)
						)
						(arc
							(start 0.381 0.3683)
							(mid 0.321484 0.511984)
							(end 0.1778 0.5715)
						)
					)
					(width 0)
					(fill yes)
				)
			)
		)
	)
	(footprint ""
		(layer "F.Cu")
		(at 209.296 -297.18 180)
		(property "Reference" "Q10"
			(at 0 0 180)
			(layer "F.SilkS")
			(hide yes)
			(effects
				(font
					(size 1.27 1.27)
				)
			)
		)
		(property "Value" "2N7002A-7-GP"
			(at 0.127 -8.9662 180)
			(unlocked yes)
			(layer "F.Fab")
			(hide yes)
			(effects
				(font
					(size 1.016 1.016)
					(thickness 0.1524)
				)
			)
		)
		(property "Device Type" "SOT23DGS2D4H48"
			(at 0.127 -10.4902 180)
			(unlocked yes)
			(layer "F.Fab")
			(hide yes)
			(effects
				(font
					(size 1.016 1.016)
					(thickness 0.1524)
				)
			)
		)
		(duplicate_pad_numbers_are_jumpers no)
		(fp_line
			(start 1.651 1.778)
			(end 1.651 -1.778)
			(stroke
				(width 0.1524)
				(type default)
			)
			(layer "F.SilkS")
		)
		(fp_line
			(start 1.651 -1.778)
			(end -1.651 -1.778)
			(stroke
				(width 0.1524)
				(type default)
			)
			(layer "F.SilkS")
		)
		(fp_line
			(start -1.651 1.778)
			(end 1.651 1.778)
			(stroke
				(width 0.1524)
				(type default)
			)
			(layer "F.SilkS")
		)
		(fp_line
			(start -1.651 -1.778)
			(end -1.651 1.778)
			(stroke
				(width 0.1524)
				(type default)
			)
			(layer "F.SilkS")
		)
		(fp_poly
			(pts
				(xy -1.778 1.8796) (xy -1.778 -1.8796) (xy 1.778 -1.8796) (xy 1.778 1.8796)
			)
			(stroke
				(width 0)
				(type default)
			)
			(fill no)
			(layer "F.CrtYd")
		)
		(fp_poly
			(pts
				(xy -1.778 1.8796) (xy -1.778 -1.8796) (xy 1.778 -1.8796) (xy 1.778 1.8796)
			)
			(stroke
				(width 0)
				(type default)
			)
			(fill no)
			(layer "F.Fab")
		)
		(pad "D" smd custom
			(at 0 -0.9525 180)
			(size 0.1905 0.1905)
			(layers "F.Cu" "F.Mask" "F.Paste")
			(net "SW_SSD2_R")
			(options
				(clearance outline)
				(anchor circle)
			)
			(primitives
				(gr_poly
					(pts
						(arc
							(start -0.1778 0.5715)
							(mid -0.321484 0.511984)
							(end -0.381 0.3683)
						)
						(arc
							(start -0.381 -0.3683)
							(mid -0.321484 -0.511984)
							(end -0.1778 -0.5715)
						)
						(arc
							(start 0.1778 -0.5715)
							(mid 0.321484 -0.511984)
							(end 0.381 -0.3683)
						)
						(arc
							(start 0.381 0.3683)
							(mid 0.321484 0.511984)
							(end 0.1778 0.5715)
						)
					)
					(width 0)
					(fill yes)
				)
			)
		)
		(pad "G" smd custom
			(at -0.98425 0.9525 180)
			(size 0.1905 0.1905)
			(layers "F.Cu" "F.Mask" "F.Paste")
			(net "SSD2_PWREN")
			(options
				(clearance outline)
				(anchor circle)
			)
			(primitives
				(gr_poly
					(pts
						(arc
							(start -0.1778 0.5715)
							(mid -0.321484 0.511984)
							(end -0.381 0.3683)
						)
						(arc
							(start -0.381 -0.3683)
							(mid -0.321484 -0.511984)
							(end -0.1778 -0.5715)
						)
						(arc
							(start 0.1778 -0.5715)
							(mid 0.321484 -0.511984)
							(end 0.381 -0.3683)
						)
						(arc
							(start 0.381 0.3683)
							(mid 0.321484 0.511984)
							(end 0.1778 0.5715)
						)
					)
					(width 0)
					(fill yes)
				)
			)
		)
		(pad "S" smd custom
			(at 0.98425 0.9525 180)
			(size 0.1905 0.1905)
			(layers "F.Cu" "F.Mask" "F.Paste")
			(net "GND")
			(options
				(clearance outline)
				(anchor circle)
			)
			(primitives
				(gr_poly
					(pts
						(arc
							(start -0.1778 0.5715)
							(mid -0.321484 0.511984)
							(end -0.381 0.3683)
						)
						(arc
							(start -0.381 -0.3683)
							(mid -0.321484 -0.511984)
							(end -0.1778 -0.5715)
						)
						(arc
							(start 0.1778 -0.5715)
							(mid 0.321484 -0.511984)
							(end 0.381 -0.3683)
						)
						(arc
							(start 0.381 0.3683)
							(mid 0.321484 0.511984)
							(end 0.1778 0.5715)
						)
					)
					(width 0)
					(fill yes)
				)
			)
		)
	)
	(footprint ""
		(layer "F.Cu")
		(at 72.3646 -352.679 180)
		(property "Reference" "R375"
			(at 0 0 180)
			(layer "F.SilkS")
			(hide yes)
			(effects
				(font
					(size 1.27 1.27)
				)
			)
		)
		(property "Value" "4K7R2J-2-GP"
			(at 0.064008 -3.993896 180)
			(unlocked yes)
			(layer "F.Fab")
			(hide yes)
			(effects
				(font
					(size 1.016 1.016)
					(thickness 0.1524)
				)
			)
		)
		(property "Device Type" "R402H16"
			(at 0.064008 -5.517896 180)
			(unlocked yes)
			(layer "F.Fab")
			(hide yes)
			(effects
				(font
					(size 1.016 1.016)
					(thickness 0.1524)
				)
			)
		)
		(duplicate_pad_numbers_are_jumpers no)
		(fp_line
			(start 0.508 -0.9398)
			(end -0.508 -0.9398)
			(stroke
				(width 0.1524)
				(type default)
			)
			(layer "F.SilkS")
		)
		(fp_line
			(start -0.508 -0.9398)
			(end -0.508 0.9398)
			(stroke
				(width 0.1524)
				(type default)
			)
			(layer "F.SilkS")
		)
		(fp_rect
			(start -0.508 0.9398)
			(end 0.508 -0.9398)
			(stroke
				(width 0)
				(type default)
			)
			(fill no)
			(layer "F.CrtYd")
		)
		(fp_rect
			(start -0.508 0.9398)
			(end 0.508 -0.9398)
			(stroke
				(width 0)
				(type default)
			)
			(fill no)
			(layer "F.Fab")
		)
		(pad "1" smd custom
			(at 0 -0.4445 180)
			(size 0.1397 0.1397)
			(layers "F.Cu" "F.Mask" "F.Paste")
			(net "P3V3")
			(options
				(clearance outline)
				(anchor circle)
			)
			(primitives
				(gr_poly
					(pts
						(arc
							(start -0.1778 -0.2794)
							(mid -0.249642 -0.249642)
							(end -0.2794 -0.1778)
						)
						(arc
							(start -0.2794 0.1778)
							(mid -0.249642 0.249642)
							(end -0.1778 0.2794)
						)
						(arc
							(start 0.1778 0.2794)
							(mid 0.249642 0.249642)
							(end 0.2794 0.1778)
						)
						(arc
							(start 0.2794 -0.1778)
							(mid 0.249642 -0.249642)
							(end 0.1778 -0.2794)
						)
					)
					(width 0)
					(fill yes)
				)
			)
		)
		(pad "2" smd custom
			(at 0 0.4445 180)
			(size 0.1397 0.1397)
			(layers "F.Cu" "F.Mask" "F.Paste")
			(net "BMC_I2C_SCL_BUF_9")
			(options
				(clearance outline)
				(anchor circle)
			)
			(primitives
				(gr_poly
					(pts
						(arc
							(start -0.1778 -0.2794)
							(mid -0.249642 -0.249642)
							(end -0.2794 -0.1778)
						)
						(arc
							(start -0.2794 0.1778)
							(mid -0.249642 0.249642)
							(end -0.1778 0.2794)
						)
						(arc
							(start 0.1778 0.2794)
							(mid 0.249642 0.249642)
							(end 0.2794 0.1778)
						)
						(arc
							(start 0.2794 -0.1778)
							(mid 0.249642 -0.249642)
							(end 0.1778 -0.2794)
						)
					)
					(width 0)
					(fill yes)
				)
			)
		)
	)
	(footprint ""
		(layer "F.Cu")
		(at 26.416 -94.9706 -90)
		(property "Reference" "Q71"
			(at 0 0 270)
			(layer "F.SilkS")
			(hide yes)
			(effects
				(font
					(size 1.27 1.27)
				)
			)
		)
		(property "Value" "2N7002A-7-GP"
			(at 0.127 -8.9662 270)
			(unlocked yes)
			(layer "F.Fab")
			(hide yes)
			(effects
				(font
					(size 1.016 1.016)
					(thickness 0.1524)
				)
			)
		)
		(property "Device Type" "SOT23DGS2D4H48"
			(at 0.127 -10.4902 270)
			(unlocked yes)
			(layer "F.Fab")
			(hide yes)
			(effects
				(font
					(size 1.016 1.016)
					(thickness 0.1524)
				)
			)
		)
		(duplicate_pad_numbers_are_jumpers no)
		(fp_line
			(start -1.651 1.778)
			(end 1.651 1.778)
			(stroke
				(width 0.1524)
				(type default)
			)
			(layer "F.SilkS")
		)
		(fp_line
			(start 1.651 1.778)
			(end 1.651 -1.778)
			(stroke
				(width 0.1524)
				(type default)
			)
			(layer "F.SilkS")
		)
		(fp_line
			(start -1.651 -1.778)
			(end -1.651 1.778)
			(stroke
				(width 0.1524)
				(type default)
			)
			(layer "F.SilkS")
		)
		(fp_line
			(start 1.651 -1.778)
			(end -1.651 -1.778)
			(stroke
				(width 0.1524)
				(type default)
			)
			(layer "F.SilkS")
		)
		(fp_poly
			(pts
				(xy -1.778 1.8796) (xy -1.778 -1.8796) (xy 1.778 -1.8796) (xy 1.778 1.8796)
			)
			(stroke
				(width 0)
				(type default)
			)
			(fill no)
			(layer "F.CrtYd")
		)
		(fp_poly
			(pts
				(xy -1.778 1.8796) (xy -1.778 -1.8796) (xy 1.778 -1.8796) (xy 1.778 1.8796)
			)
			(stroke
				(width 0)
				(type default)
			)
			(fill no)
			(layer "F.Fab")
		)
		(pad "D" smd custom
			(at 0 -0.9525 270)
			(size 0.1905 0.1905)
			(layers "F.Cu" "F.Mask" "F.Paste")
			(net "P12V_MOST9_GATE")
			(options
				(clearance outline)
				(anchor circle)
			)
			(primitives
				(gr_poly
					(pts
						(arc
							(start -0.1778 0.5715)
							(mid -0.321484 0.511984)
							(end -0.381 0.3683)
						)
						(arc
							(start -0.381 -0.3683)
							(mid -0.321484 -0.511984)
							(end -0.1778 -0.5715)
						)
						(arc
							(start 0.1778 -0.5715)
							(mid 0.321484 -0.511984)
							(end 0.381 -0.3683)
						)
						(arc
							(start 0.381 0.3683)
							(mid 0.321484 0.511984)
							(end 0.1778 0.5715)
						)
					)
					(width 0)
					(fill yes)
				)
			)
		)
		(pad "G" smd custom
			(at -0.98425 0.9525 270)
			(size 0.1905 0.1905)
			(layers "F.Cu" "F.Mask" "F.Paste")
			(net "SSD9_PWREN_R")
			(options
				(clearance outline)
				(anchor circle)
			)
			(primitives
				(gr_poly
					(pts
						(arc
							(start -0.1778 0.5715)
							(mid -0.321484 0.511984)
							(end -0.381 0.3683)
						)
						(arc
							(start -0.381 -0.3683)
							(mid -0.321484 -0.511984)
							(end -0.1778 -0.5715)
						)
						(arc
							(start 0.1778 -0.5715)
							(mid 0.321484 -0.511984)
							(end 0.381 -0.3683)
						)
						(arc
							(start 0.381 0.3683)
							(mid 0.321484 0.511984)
							(end 0.1778 0.5715)
						)
					)
					(width 0)
					(fill yes)
				)
			)
		)
		(pad "S" smd custom
			(at 0.98425 0.9525 270)
			(size 0.1905 0.1905)
			(layers "F.Cu" "F.Mask" "F.Paste")
			(net "GND")
			(options
				(clearance outline)
				(anchor circle)
			)
			(primitives
				(gr_poly
					(pts
						(arc
							(start -0.1778 0.5715)
							(mid -0.321484 0.511984)
							(end -0.381 0.3683)
						)
						(arc
							(start -0.381 -0.3683)
							(mid -0.321484 -0.511984)
							(end -0.1778 -0.5715)
						)
						(arc
							(start 0.1778 -0.5715)
							(mid 0.321484 -0.511984)
							(end 0.381 -0.3683)
						)
						(arc
							(start 0.381 0.3683)
							(mid 0.321484 0.511984)
							(end 0.1778 0.5715)
						)
					)
					(width 0)
					(fill yes)
				)
			)
		)
	)
	(footprint ""
		(layer "F.Cu")
		(at 26.3144 -467.3346 -90)
		(property "Reference" "R9849"
			(at 0 0 270)
			(layer "F.SilkS")
			(hide yes)
			(effects
				(font
					(size 1.27 1.27)
				)
			)
		)
		(property "Value" "0R2J-2-GP"
			(at 0.064008 -3.993896 270)
			(unlocked yes)
			(layer "F.Fab")
			(hide yes)
			(effects
				(font
					(size 1.016 1.016)
					(thickness 0.1524)
				)
			)
		)
		(property "Device Type" "R402H16"
			(at 0.064008 -5.517896 270)
			(unlocked yes)
			(layer "F.Fab")
			(hide yes)
			(effects
				(font
					(size 1.016 1.016)
					(thickness 0.1524)
				)
			)
		)
		(duplicate_pad_numbers_are_jumpers no)
		(fp_line
			(start -0.508 -0.9398)
			(end -0.508 0.9398)
			(stroke
				(width 0.1524)
				(type default)
			)
			(layer "F.SilkS")
		)
		(fp_line
			(start 0.508 -0.9398)
			(end -0.508 -0.9398)
			(stroke
				(width 0.1524)
				(type default)
			)
			(layer "F.SilkS")
		)
		(fp_rect
			(start -0.508 0.9398)
			(end 0.508 -0.9398)
			(stroke
				(width 0)
				(type default)
			)
			(fill no)
			(layer "F.CrtYd")
		)
		(fp_rect
			(start -0.508 0.9398)
			(end 0.508 -0.9398)
			(stroke
				(width 0)
				(type default)
			)
			(fill no)
			(layer "F.Fab")
		)
		(pad "1" smd custom
			(at 0 -0.4445 270)
			(size 0.1397 0.1397)
			(layers "F.Cu" "F.Mask" "F.Paste")
			(net "SSD_ACT_DR10_R")
			(options
				(clearance outline)
				(anchor circle)
			)
			(primitives
				(gr_poly
					(pts
						(arc
							(start -0.1778 -0.2794)
							(mid -0.249642 -0.249642)
							(end -0.2794 -0.1778)
						)
						(arc
							(start -0.2794 0.1778)
							(mid -0.249642 0.249642)
							(end -0.1778 0.2794)
						)
						(arc
							(start 0.1778 0.2794)
							(mid 0.249642 0.249642)
							(end 0.2794 0.1778)
						)
						(arc
							(start 0.2794 -0.1778)
							(mid 0.249642 -0.249642)
							(end 0.1778 -0.2794)
						)
					)
					(width 0)
					(fill yes)
				)
			)
		)
		(pad "2" smd custom
			(at 0 0.4445 270)
			(size 0.1397 0.1397)
			(layers "F.Cu" "F.Mask" "F.Paste")
			(net "SSD_ACT_DR10")
			(options
				(clearance outline)
				(anchor circle)
			)
			(primitives
				(gr_poly
					(pts
						(arc
							(start -0.1778 -0.2794)
							(mid -0.249642 -0.249642)
							(end -0.2794 -0.1778)
						)
						(arc
							(start -0.2794 0.1778)
							(mid -0.249642 0.249642)
							(end -0.1778 0.2794)
						)
						(arc
							(start 0.1778 0.2794)
							(mid 0.249642 0.249642)
							(end 0.2794 0.1778)
						)
						(arc
							(start 0.2794 -0.1778)
							(mid 0.249642 -0.249642)
							(end 0.1778 -0.2794)
						)
					)
					(width 0)
					(fill yes)
				)
			)
		)
	)
	(footprint ""
		(layer "F.Cu")
		(at 47.879 -351.028 -90)
		(property "Reference" "R9470"
			(at 0 0 270)
			(layer "F.SilkS")
			(hide yes)
			(effects
				(font
					(size 1.27 1.27)
				)
			)
		)
		(property "Value" "330R2F-GP"
			(at 0.064008 -3.993896 270)
			(unlocked yes)
			(layer "F.Fab")
			(hide yes)
			(effects
				(font
					(size 1.016 1.016)
					(thickness 0.1524)
				)
			)
		)
		(property "Device Type" "R402H16"
			(at 0.064008 -5.517896 270)
			(unlocked yes)
			(layer "F.Fab")
			(hide yes)
			(effects
				(font
					(size 1.016 1.016)
					(thickness 0.1524)
				)
			)
		)
		(duplicate_pad_numbers_are_jumpers no)
		(fp_line
			(start -0.508 -0.9398)
			(end -0.508 0.9398)
			(stroke
				(width 0.1524)
				(type default)
			)
			(layer "F.SilkS")
		)
		(fp_line
			(start 0.508 -0.9398)
			(end -0.508 -0.9398)
			(stroke
				(width 0.1524)
				(type default)
			)
			(layer "F.SilkS")
		)
		(fp_rect
			(start -0.508 0.9398)
			(end 0.508 -0.9398)
			(stroke
				(width 0)
				(type default)
			)
			(fill no)
			(layer "F.CrtYd")
		)
		(fp_rect
			(start -0.508 0.9398)
			(end 0.508 -0.9398)
			(stroke
				(width 0)
				(type default)
			)
			(fill no)
			(layer "F.Fab")
		)
		(pad "1" smd custom
			(at 0 -0.4445 270)
			(size 0.1397 0.1397)
			(layers "F.Cu" "F.Mask" "F.Paste")
			(net "P3V3")
			(options
				(clearance outline)
				(anchor circle)
			)
			(primitives
				(gr_poly
					(pts
						(arc
							(start -0.1778 -0.2794)
							(mid -0.249642 -0.249642)
							(end -0.2794 -0.1778)
						)
						(arc
							(start -0.2794 0.1778)
							(mid -0.249642 0.249642)
							(end -0.1778 0.2794)
						)
						(arc
							(start 0.1778 0.2794)
							(mid 0.249642 0.249642)
							(end 0.2794 0.1778)
						)
						(arc
							(start 0.2794 -0.1778)
							(mid 0.249642 -0.249642)
							(end 0.1778 -0.2794)
						)
					)
					(width 0)
					(fill yes)
				)
			)
		)
		(pad "2" smd custom
			(at 0 0.4445 270)
			(size 0.1397 0.1397)
			(layers "F.Cu" "F.Mask" "F.Paste")
			(net "DRV_ATTN_6")
			(options
				(clearance outline)
				(anchor circle)
			)
			(primitives
				(gr_poly
					(pts
						(arc
							(start -0.1778 -0.2794)
							(mid -0.249642 -0.249642)
							(end -0.2794 -0.1778)
						)
						(arc
							(start -0.2794 0.1778)
							(mid -0.249642 0.249642)
							(end -0.1778 0.2794)
						)
						(arc
							(start 0.1778 0.2794)
							(mid 0.249642 0.249642)
							(end 0.2794 0.1778)
						)
						(arc
							(start 0.2794 -0.1778)
							(mid 0.249642 -0.249642)
							(end 0.1778 -0.2794)
						)
					)
					(width 0)
					(fill yes)
				)
			)
		)
	)
	(footprint ""
		(layer "F.Cu")
		(at 70.739 -360.553 90)
		(property "Reference" "SR978"
			(at 0 0 90)
			(layer "F.SilkS")
			(hide yes)
			(effects
				(font
					(size 1.27 1.27)
				)
			)
		)
		(property "Value" "2KR2F-3-GP"
			(at 0.064008 -3.993896 90)
			(unlocked yes)
			(layer "F.Fab")
			(hide yes)
			(effects
				(font
					(size 1.016 1.016)
					(thickness 0.1524)
				)
			)
		)
		(property "Device Type" "R402H16"
			(at 0.064008 -5.517896 90)
			(unlocked yes)
			(layer "F.Fab")
			(hide yes)
			(effects
				(font
					(size 1.016 1.016)
					(thickness 0.1524)
				)
			)
		)
		(duplicate_pad_numbers_are_jumpers no)
		(fp_line
			(start 0.508 -0.9398)
			(end -0.508 -0.9398)
			(stroke
				(width 0.1524)
				(type default)
			)
			(layer "F.SilkS")
		)
		(fp_line
			(start -0.508 -0.9398)
			(end -0.508 0.9398)
			(stroke
				(width 0.1524)
				(type default)
			)
			(layer "F.SilkS")
		)
		(fp_rect
			(start -0.508 0.9398)
			(end 0.508 -0.9398)
			(stroke
				(width 0)
				(type default)
			)
			(fill no)
			(layer "F.CrtYd")
		)
		(fp_rect
			(start -0.508 0.9398)
			(end 0.508 -0.9398)
			(stroke
				(width 0)
				(type default)
			)
			(fill no)
			(layer "F.Fab")
		)
		(pad "1" smd custom
			(at 0 -0.4445 90)
			(size 0.1397 0.1397)
			(layers "F.Cu" "F.Mask" "F.Paste")
			(net "P3V3")
			(options
				(clearance outline)
				(anchor circle)
			)
			(primitives
				(gr_poly
					(pts
						(arc
							(start -0.1778 -0.2794)
							(mid -0.249642 -0.249642)
							(end -0.2794 -0.1778)
						)
						(arc
							(start -0.2794 0.1778)
							(mid -0.249642 0.249642)
							(end -0.1778 0.2794)
						)
						(arc
							(start 0.1778 0.2794)
							(mid 0.249642 0.249642)
							(end 0.2794 0.1778)
						)
						(arc
							(start 0.2794 -0.1778)
							(mid 0.249642 -0.249642)
							(end 0.1778 -0.2794)
						)
					)
					(width 0)
					(fill yes)
				)
			)
		)
		(pad "2" smd custom
			(at 0 0.4445 90)
			(size 0.1397 0.1397)
			(layers "F.Cu" "F.Mask" "F.Paste")
			(net "SDA_DR7")
			(options
				(clearance outline)
				(anchor circle)
			)
			(primitives
				(gr_poly
					(pts
						(arc
							(start -0.1778 -0.2794)
							(mid -0.249642 -0.249642)
							(end -0.2794 -0.1778)
						)
						(arc
							(start -0.2794 0.1778)
							(mid -0.249642 0.249642)
							(end -0.1778 0.2794)
						)
						(arc
							(start 0.1778 0.2794)
							(mid 0.249642 0.249642)
							(end 0.2794 0.1778)
						)
						(arc
							(start 0.2794 -0.1778)
							(mid 0.249642 -0.249642)
							(end 0.1778 -0.2794)
						)
					)
					(width 0)
					(fill yes)
				)
			)
		)
	)
	(footprint ""
		(layer "F.Cu")
		(at 91.313 -92.964)
		(property "Reference" "R9123"
			(at 0 0 0)
			(layer "F.SilkS")
			(hide yes)
			(effects
				(font
					(size 1.27 1.27)
				)
			)
		)
		(property "Value" "27R2F-GP"
			(at 0.064008 -3.993896 0)
			(unlocked yes)
			(layer "F.Fab")
			(hide yes)
			(effects
				(font
					(size 1.016 1.016)
					(thickness 0.1524)
				)
			)
		)
		(property "Device Type" "R402H16"
			(at 0.064008 -5.517896 0)
			(unlocked yes)
			(layer "F.Fab")
			(hide yes)
			(effects
				(font
					(size 1.016 1.016)
					(thickness 0.1524)
				)
			)
		)
		(duplicate_pad_numbers_are_jumpers no)
		(fp_line
			(start -0.508 -0.9398)
			(end -0.508 0.9398)
			(stroke
				(width 0.1524)
				(type default)
			)
			(layer "F.SilkS")
		)
		(fp_line
			(start 0.508 -0.9398)
			(end -0.508 -0.9398)
			(stroke
				(width 0.1524)
				(type default)
			)
			(layer "F.SilkS")
		)
		(fp_rect
			(start -0.508 0.9398)
			(end 0.508 -0.9398)
			(stroke
				(width 0)
				(type default)
			)
			(fill no)
			(layer "F.CrtYd")
		)
		(fp_rect
			(start -0.508 0.9398)
			(end 0.508 -0.9398)
			(stroke
				(width 0)
				(type default)
			)
			(fill no)
			(layer "F.Fab")
		)
		(pad "1" smd custom
			(at 0 -0.4445)
			(size 0.1397 0.1397)
			(layers "F.Cu" "F.Mask" "F.Paste")
			(net "PE_CLK_100M_DR9_1_R_N")
			(options
				(clearance outline)
				(anchor circle)
			)
			(primitives
				(gr_poly
					(pts
						(arc
							(start -0.1778 -0.2794)
							(mid -0.249642 -0.249642)
							(end -0.2794 -0.1778)
						)
						(arc
							(start -0.2794 0.1778)
							(mid -0.249642 0.249642)
							(end -0.1778 0.2794)
						)
						(arc
							(start 0.1778 0.2794)
							(mid 0.249642 0.249642)
							(end 0.2794 0.1778)
						)
						(arc
							(start 0.2794 -0.1778)
							(mid 0.249642 -0.249642)
							(end 0.1778 -0.2794)
						)
					)
					(width 0)
					(fill yes)
				)
			)
		)
		(pad "2" smd custom
			(at 0 0.4445)
			(size 0.1397 0.1397)
			(layers "F.Cu" "F.Mask" "F.Paste")
			(net "PE_CLK100M_DR9_1_N")
			(options
				(clearance outline)
				(anchor circle)
			)
			(primitives
				(gr_poly
					(pts
						(arc
							(start -0.1778 -0.2794)
							(mid -0.249642 -0.249642)
							(end -0.2794 -0.1778)
						)
						(arc
							(start -0.2794 0.1778)
							(mid -0.249642 0.249642)
							(end -0.1778 0.2794)
						)
						(arc
							(start 0.1778 0.2794)
							(mid 0.249642 0.249642)
							(end 0.2794 0.1778)
						)
						(arc
							(start 0.2794 -0.1778)
							(mid 0.249642 -0.249642)
							(end 0.1778 -0.2794)
						)
					)
					(width 0)
					(fill yes)
				)
			)
		)
	)
	(footprint ""
		(layer "F.Cu")
		(at 88.011 -309.88)
		(property "Reference" "C8910"
			(at 0 0 0)
			(layer "F.SilkS")
			(hide yes)
			(effects
				(font
					(size 1.27 1.27)
				)
			)
		)
		(property "Value" "SCD1U16V2KX-3GP"
			(at 1.1811 -2.7051 0)
			(unlocked yes)
			(layer "F.Fab")
			(hide yes)
			(effects
				(font
					(size 1.016 1.016)
					(thickness 0.1524)
				)
			)
		)
		(property "Device Type" "C402H22"
			(at 1.1811 -4.2291 0)
			(unlocked yes)
			(layer "F.Fab")
			(hide yes)
			(effects
				(font
					(size 1.016 1.016)
					(thickness 0.1524)
				)
			)
		)
		(duplicate_pad_numbers_are_jumpers no)
		(fp_rect
			(start -0.4318 0.9525)
			(end 0.4318 -0.9525)
			(stroke
				(width 0)
				(type default)
			)
			(fill no)
			(layer "F.CrtYd")
		)
		(fp_rect
			(start -0.4318 0.9525)
			(end 0.4318 -0.9525)
			(stroke
				(width 0)
				(type default)
			)
			(fill no)
			(layer "F.Fab")
		)
		(pad "1" smd custom
			(at 0 -0.4445)
			(size 0.1524 0.1524)
			(layers "F.Cu" "F.Mask" "F.Paste")
			(net "VDDA_2")
			(options
				(clearance outline)
				(anchor circle)
			)
			(primitives
				(gr_poly
					(pts
						(arc
							(start 0.3048 -0.2032)
							(mid 0.275042 -0.275042)
							(end 0.2032 -0.3048)
						)
						(arc
							(start -0.2032 -0.3048)
							(mid -0.275042 -0.275042)
							(end -0.3048 -0.2032)
						)
						(arc
							(start -0.3048 0.2032)
							(mid -0.275042 0.275042)
							(end -0.2032 0.3048)
						)
						(arc
							(start 0.2032 0.3048)
							(mid 0.275042 0.275042)
							(end 0.3048 0.2032)
						)
					)
					(width 0)
					(fill yes)
				)
			)
		)
		(pad "2" smd custom
			(at 0 0.4445)
			(size 0.1524 0.1524)
			(layers "F.Cu" "F.Mask" "F.Paste")
			(net "GND")
			(options
				(clearance outline)
				(anchor circle)
			)
			(primitives
				(gr_poly
					(pts
						(arc
							(start 0.3048 -0.2032)
							(mid 0.275042 -0.275042)
							(end 0.2032 -0.3048)
						)
						(arc
							(start -0.2032 -0.3048)
							(mid -0.275042 -0.275042)
							(end -0.3048 -0.2032)
						)
						(arc
							(start -0.3048 0.2032)
							(mid -0.275042 0.275042)
							(end -0.2032 0.3048)
						)
						(arc
							(start 0.2032 0.3048)
							(mid 0.275042 0.275042)
							(end 0.3048 0.2032)
						)
					)
					(width 0)
					(fill yes)
				)
			)
		)
	)
	(footprint ""
		(layer "F.Cu")
		(at 38.8366 -109.8804 180)
		(property "Reference" "R564"
			(at 0 0 180)
			(layer "F.SilkS")
			(hide yes)
			(effects
				(font
					(size 1.27 1.27)
				)
			)
		)
		(property "Value" "200KR2F-L-GP"
			(at 0.064008 -3.993896 180)
			(unlocked yes)
			(layer "F.Fab")
			(hide yes)
			(effects
				(font
					(size 1.016 1.016)
					(thickness 0.1524)
				)
			)
		)
		(property "Device Type" "R402H16"
			(at 0.064008 -5.517896 180)
			(unlocked yes)
			(layer "F.Fab")
			(hide yes)
			(effects
				(font
					(size 1.016 1.016)
					(thickness 0.1524)
				)
			)
		)
		(duplicate_pad_numbers_are_jumpers no)
		(fp_line
			(start 0.508 -0.9398)
			(end -0.508 -0.9398)
			(stroke
				(width 0.1524)
				(type default)
			)
			(layer "F.SilkS")
		)
		(fp_line
			(start -0.508 -0.9398)
			(end -0.508 0.9398)
			(stroke
				(width 0.1524)
				(type default)
			)
			(layer "F.SilkS")
		)
		(fp_rect
			(start -0.508 0.9398)
			(end 0.508 -0.9398)
			(stroke
				(width 0)
				(type default)
			)
			(fill no)
			(layer "F.CrtYd")
		)
		(fp_rect
			(start -0.508 0.9398)
			(end 0.508 -0.9398)
			(stroke
				(width 0)
				(type default)
			)
			(fill no)
			(layer "F.Fab")
		)
		(pad "1" smd custom
			(at 0 -0.4445 180)
			(size 0.1397 0.1397)
			(layers "F.Cu" "F.Mask" "F.Paste")
			(net "SW_SSD13_R")
			(options
				(clearance outline)
				(anchor circle)
			)
			(primitives
				(gr_poly
					(pts
						(arc
							(start -0.1778 -0.2794)
							(mid -0.249642 -0.249642)
							(end -0.2794 -0.1778)
						)
						(arc
							(start -0.2794 0.1778)
							(mid -0.249642 0.249642)
							(end -0.1778 0.2794)
						)
						(arc
							(start 0.1778 0.2794)
							(mid 0.249642 0.249642)
							(end 0.2794 0.1778)
						)
						(arc
							(start 0.2794 -0.1778)
							(mid 0.249642 -0.249642)
							(end 0.1778 -0.2794)
						)
					)
					(width 0)
					(fill yes)
				)
			)
		)
		(pad "2" smd custom
			(at 0 0.4445 180)
			(size 0.1397 0.1397)
			(layers "F.Cu" "F.Mask" "F.Paste")
			(net "SW_SSD13_N")
			(options
				(clearance outline)
				(anchor circle)
			)
			(primitives
				(gr_poly
					(pts
						(arc
							(start -0.1778 -0.2794)
							(mid -0.249642 -0.249642)
							(end -0.2794 -0.1778)
						)
						(arc
							(start -0.2794 0.1778)
							(mid -0.249642 0.249642)
							(end -0.1778 0.2794)
						)
						(arc
							(start 0.1778 0.2794)
							(mid 0.249642 0.249642)
							(end 0.2794 0.1778)
						)
						(arc
							(start 0.2794 -0.1778)
							(mid 0.249642 -0.249642)
							(end 0.1778 -0.2794)
						)
					)
					(width 0)
					(fill yes)
				)
			)
		)
	)
	(footprint ""
		(layer "F.Cu")
		(at 90.297 -440.436 180)
		(property "Reference" "R9066"
			(at 0 0 180)
			(layer "F.SilkS")
			(hide yes)
			(effects
				(font
					(size 1.27 1.27)
				)
			)
		)
		(property "Value" "27R2F-GP"
			(at 0.064008 -3.993896 180)
			(unlocked yes)
			(layer "F.Fab")
			(hide yes)
			(effects
				(font
					(size 1.016 1.016)
					(thickness 0.1524)
				)
			)
		)
		(property "Device Type" "R402H16"
			(at 0.064008 -5.517896 180)
			(unlocked yes)
			(layer "F.Fab")
			(hide yes)
			(effects
				(font
					(size 1.016 1.016)
					(thickness 0.1524)
				)
			)
		)
		(duplicate_pad_numbers_are_jumpers no)
		(fp_line
			(start 0.508 -0.9398)
			(end -0.508 -0.9398)
			(stroke
				(width 0.1524)
				(type default)
			)
			(layer "F.SilkS")
		)
		(fp_line
			(start -0.508 -0.9398)
			(end -0.508 0.9398)
			(stroke
				(width 0.1524)
				(type default)
			)
			(layer "F.SilkS")
		)
		(fp_rect
			(start -0.508 0.9398)
			(end 0.508 -0.9398)
			(stroke
				(width 0)
				(type default)
			)
			(fill no)
			(layer "F.CrtYd")
		)
		(fp_rect
			(start -0.508 0.9398)
			(end 0.508 -0.9398)
			(stroke
				(width 0)
				(type default)
			)
			(fill no)
			(layer "F.Fab")
		)
		(pad "1" smd custom
			(at 0 -0.4445 180)
			(size 0.1397 0.1397)
			(layers "F.Cu" "F.Mask" "F.Paste")
			(net "PE_CLK_100M_DR5_2_R_N")
			(options
				(clearance outline)
				(anchor circle)
			)
			(primitives
				(gr_poly
					(pts
						(arc
							(start -0.1778 -0.2794)
							(mid -0.249642 -0.249642)
							(end -0.2794 -0.1778)
						)
						(arc
							(start -0.2794 0.1778)
							(mid -0.249642 0.249642)
							(end -0.1778 0.2794)
						)
						(arc
							(start 0.1778 0.2794)
							(mid 0.249642 0.249642)
							(end 0.2794 0.1778)
						)
						(arc
							(start 0.2794 -0.1778)
							(mid 0.249642 -0.249642)
							(end 0.1778 -0.2794)
						)
					)
					(width 0)
					(fill yes)
				)
			)
		)
		(pad "2" smd custom
			(at 0 0.4445 180)
			(size 0.1397 0.1397)
			(layers "F.Cu" "F.Mask" "F.Paste")
			(net "PE_CLK100M_DR5_2_N")
			(options
				(clearance outline)
				(anchor circle)
			)
			(primitives
				(gr_poly
					(pts
						(arc
							(start -0.1778 -0.2794)
							(mid -0.249642 -0.249642)
							(end -0.2794 -0.1778)
						)
						(arc
							(start -0.2794 0.1778)
							(mid -0.249642 0.249642)
							(end -0.1778 0.2794)
						)
						(arc
							(start 0.1778 0.2794)
							(mid 0.249642 0.249642)
							(end 0.2794 0.1778)
						)
						(arc
							(start 0.2794 -0.1778)
							(mid 0.249642 -0.249642)
							(end 0.1778 -0.2794)
						)
					)
					(width 0)
					(fill yes)
				)
			)
		)
	)
	(footprint ""
		(layer "F.Cu")
		(at 246.126 -416.941)
		(property "Reference" "TP3"
			(at 0 0 0)
			(layer "F.SilkS")
			(hide yes)
			(effects
				(font
					(size 1.27 1.27)
				)
			)
		)
		(property "Value" "TPAD28-2-GP"
			(at -0.0127 -1.6637 0)
			(unlocked yes)
			(layer "F.Fab")
			(hide yes)
			(effects
				(font
					(size 1.016 1.016)
					(thickness 0.1524)
				)
			)
		)
		(property "Device Type" "TPAD28"
			(at -0.0127 -3.1877 0)
			(unlocked yes)
			(layer "F.Fab")
			(hide yes)
			(effects
				(font
					(size 1.016 1.016)
					(thickness 0.1524)
				)
			)
		)
		(duplicate_pad_numbers_are_jumpers no)
		(fp_poly
			(pts
				(arc
					(start 0.3556 0)
					(mid -0.3556 0)
					(end 0.3556 0)
				)
			)
			(stroke
				(width 0)
				(type default)
			)
			(fill no)
			(layer "F.CrtYd")
		)
		(fp_poly
			(pts
				(arc
					(start 0.6096 0)
					(mid -0.6096 0)
					(end 0.6096 0)
				)
			)
			(stroke
				(width 0)
				(type default)
			)
			(fill no)
			(layer "F.Fab")
		)
		(pad "1" smd circle
			(at 0 0)
			(size 0.7112 0.7112)
			(layers "F.Cu" "F.Mask" "F.Paste")
			(net "N70914768")
		)
	)
	(footprint ""
		(layer "F.Cu")
		(at 107.442 -434.467 -90)
		(property "Reference" "R9590"
			(at 0 0 270)
			(layer "F.SilkS")
			(hide yes)
			(effects
				(font
					(size 1.27 1.27)
				)
			)
		)
		(property "Value" "10R2F-L-GP"
			(at 0.064008 -3.993896 270)
			(unlocked yes)
			(layer "F.Fab")
			(hide yes)
			(effects
				(font
					(size 1.016 1.016)
					(thickness 0.1524)
				)
			)
		)
		(property "Device Type" "R402H14"
			(at 0.064008 -5.517896 270)
			(unlocked yes)
			(layer "F.Fab")
			(hide yes)
			(effects
				(font
					(size 1.016 1.016)
					(thickness 0.1524)
				)
			)
		)
		(duplicate_pad_numbers_are_jumpers no)
		(fp_line
			(start -0.508 -0.9398)
			(end -0.508 0.9398)
			(stroke
				(width 0.1524)
				(type default)
			)
			(layer "F.SilkS")
		)
		(fp_line
			(start 0.508 -0.9398)
			(end -0.508 -0.9398)
			(stroke
				(width 0.1524)
				(type default)
			)
			(layer "F.SilkS")
		)
		(fp_rect
			(start -0.508 0.9398)
			(end 0.508 -0.9398)
			(stroke
				(width 0)
				(type default)
			)
			(fill no)
			(layer "F.CrtYd")
		)
		(fp_rect
			(start -0.508 0.9398)
			(end 0.508 -0.9398)
			(stroke
				(width 0)
				(type default)
			)
			(fill no)
			(layer "F.Fab")
		)
		(pad "1" smd custom
			(at 0 -0.4445 270)
			(size 0.1397 0.1397)
			(layers "F.Cu" "F.Mask" "F.Paste")
			(net "SSD_PRSNT_NET0")
			(options
				(clearance outline)
				(anchor circle)
			)
			(primitives
				(gr_poly
					(pts
						(arc
							(start -0.1778 -0.2794)
							(mid -0.249642 -0.249642)
							(end -0.2794 -0.1778)
						)
						(arc
							(start -0.2794 0.1778)
							(mid -0.249642 0.249642)
							(end -0.1778 0.2794)
						)
						(arc
							(start 0.1778 0.2794)
							(mid 0.249642 0.249642)
							(end 0.2794 0.1778)
						)
						(arc
							(start 0.2794 -0.1778)
							(mid 0.249642 -0.249642)
							(end 0.1778 -0.2794)
						)
					)
					(width 0)
					(fill yes)
				)
			)
		)
		(pad "2" smd custom
			(at 0 0.4445 270)
			(size 0.1397 0.1397)
			(layers "F.Cu" "F.Mask" "F.Paste")
			(net "SSD_PRSNT0")
			(options
				(clearance outline)
				(anchor circle)
			)
			(primitives
				(gr_poly
					(pts
						(arc
							(start -0.1778 -0.2794)
							(mid -0.249642 -0.249642)
							(end -0.2794 -0.1778)
						)
						(arc
							(start -0.2794 0.1778)
							(mid -0.249642 0.249642)
							(end -0.1778 0.2794)
						)
						(arc
							(start 0.1778 0.2794)
							(mid 0.249642 0.249642)
							(end 0.2794 0.1778)
						)
						(arc
							(start 0.2794 -0.1778)
							(mid 0.249642 -0.249642)
							(end 0.1778 -0.2794)
						)
					)
					(width 0)
					(fill yes)
				)
			)
		)
	)
	(footprint ""
		(layer "F.Cu")
		(at 35.0012 -86.3346)
		(property "Reference" "PC1196"
			(at 0 0 0)
			(layer "F.SilkS")
			(hide yes)
			(effects
				(font
					(size 1.27 1.27)
				)
			)
		)
		(property "Value" "SC22U25V6KX-GP-U"
			(at -2.860802 -5.279644 0)
			(unlocked yes)
			(layer "F.Fab")
			(hide yes)
			(effects
				(font
					(size 1.016 1.016)
					(thickness 0.1524)
				)
			)
		)
		(property "Device Type" "C1206-TO0D3H75"
			(at -2.860802 -6.803644 0)
			(unlocked yes)
			(layer "F.Fab")
			(hide yes)
			(effects
				(font
					(size 1.016 1.016)
					(thickness 0.1524)
				)
			)
		)
		(duplicate_pad_numbers_are_jumpers no)
		(fp_line
			(start -1.3081 -2.3749)
			(end 1.3081 -2.3749)
			(stroke
				(width 0.1524)
				(type default)
			)
			(layer "F.SilkS")
		)
		(fp_line
			(start -1.3081 2.3749)
			(end -1.3081 -2.3749)
			(stroke
				(width 0.1524)
				(type default)
			)
			(layer "F.SilkS")
		)
		(fp_line
			(start 1.3081 -2.3749)
			(end 1.3081 2.3749)
			(stroke
				(width 0.1524)
				(type default)
			)
			(layer "F.SilkS")
		)
		(fp_line
			(start 1.3081 2.3749)
			(end -1.3081 2.3749)
			(stroke
				(width 0.1524)
				(type default)
			)
			(layer "F.SilkS")
		)
		(fp_rect
			(start -0.8001 1.6002)
			(end 0.8001 -1.6002)
			(stroke
				(width 0)
				(type default)
			)
			(fill no)
			(layer "F.CrtYd")
		)
		(fp_poly
			(pts
				(xy -1.5621 2.4511) (xy -1.5621 1.6002) (xy 0.8001 1.6002) (xy 0.8001 -1.6002) (xy -0.8001 -1.6002)
				(xy -0.8001 1.5875) (xy -1.5621 1.5875) (xy -1.5621 -2.4511) (xy 1.5621 -2.4511) (xy 1.5621 2.4511)
			)
			(stroke
				(width 0)
				(type default)
			)
			(fill no)
			(layer "F.CrtYd")
		)
		(fp_rect
			(start -1.5621 2.4511)
			(end 1.5621 -2.4511)
			(stroke
				(width 0)
				(type default)
			)
			(fill no)
			(layer "F.Fab")
		)
		(pad "1" smd rect
			(at 0 -1.392936)
			(size 2.1082 1.4478)
			(layers "F.Cu" "F.Mask" "F.Paste")
			(net "P12V_SSD9")
		)
		(pad "2" smd rect
			(at 0 1.392936)
			(size 2.1082 1.4478)
			(layers "F.Cu" "F.Mask" "F.Paste")
			(net "GND")
		)
	)
	(footprint ""
		(layer "F.Cu")
		(at 107.442 -207.645 -90)
		(property "Reference" "R9595"
			(at 0 0 270)
			(layer "F.SilkS")
			(hide yes)
			(effects
				(font
					(size 1.27 1.27)
				)
			)
		)
		(property "Value" "10R2F-L-GP"
			(at 0.064008 -3.993896 270)
			(unlocked yes)
			(layer "F.Fab")
			(hide yes)
			(effects
				(font
					(size 1.016 1.016)
					(thickness 0.1524)
				)
			)
		)
		(property "Device Type" "R402H14"
			(at 0.064008 -5.517896 270)
			(unlocked yes)
			(layer "F.Fab")
			(hide yes)
			(effects
				(font
					(size 1.016 1.016)
					(thickness 0.1524)
				)
			)
		)
		(duplicate_pad_numbers_are_jumpers no)
		(fp_line
			(start -0.508 -0.9398)
			(end -0.508 0.9398)
			(stroke
				(width 0.1524)
				(type default)
			)
			(layer "F.SilkS")
		)
		(fp_line
			(start 0.508 -0.9398)
			(end -0.508 -0.9398)
			(stroke
				(width 0.1524)
				(type default)
			)
			(layer "F.SilkS")
		)
		(fp_rect
			(start -0.508 0.9398)
			(end 0.508 -0.9398)
			(stroke
				(width 0)
				(type default)
			)
			(fill no)
			(layer "F.CrtYd")
		)
		(fp_rect
			(start -0.508 0.9398)
			(end 0.508 -0.9398)
			(stroke
				(width 0)
				(type default)
			)
			(fill no)
			(layer "F.Fab")
		)
		(pad "1" smd custom
			(at 0 -0.4445 270)
			(size 0.1397 0.1397)
			(layers "F.Cu" "F.Mask" "F.Paste")
			(net "SSD3_CLK0_OE_N")
			(options
				(clearance outline)
				(anchor circle)
			)
			(primitives
				(gr_poly
					(pts
						(arc
							(start -0.1778 -0.2794)
							(mid -0.249642 -0.249642)
							(end -0.2794 -0.1778)
						)
						(arc
							(start -0.2794 0.1778)
							(mid -0.249642 0.249642)
							(end -0.1778 0.2794)
						)
						(arc
							(start 0.1778 0.2794)
							(mid 0.249642 0.249642)
							(end 0.2794 0.1778)
						)
						(arc
							(start 0.2794 -0.1778)
							(mid 0.249642 -0.249642)
							(end 0.1778 -0.2794)
						)
					)
					(width 0)
					(fill yes)
				)
			)
		)
		(pad "2" smd custom
			(at 0 0.4445 270)
			(size 0.1397 0.1397)
			(layers "F.Cu" "F.Mask" "F.Paste")
			(net "SSD3_CLK0_OE_R_N")
			(options
				(clearance outline)
				(anchor circle)
			)
			(primitives
				(gr_poly
					(pts
						(arc
							(start -0.1778 -0.2794)
							(mid -0.249642 -0.249642)
							(end -0.2794 -0.1778)
						)
						(arc
							(start -0.2794 0.1778)
							(mid -0.249642 0.249642)
							(end -0.1778 0.2794)
						)
						(arc
							(start 0.1778 0.2794)
							(mid 0.249642 0.249642)
							(end 0.2794 0.1778)
						)
						(arc
							(start 0.2794 -0.1778)
							(mid 0.249642 -0.249642)
							(end 0.1778 -0.2794)
						)
					)
					(width 0)
					(fill yes)
				)
			)
		)
	)
	(footprint ""
		(layer "F.Cu")
		(at 82.931 -212.979 90)
		(property "Reference" "SR952"
			(at 0 0 90)
			(layer "F.SilkS")
			(hide yes)
			(effects
				(font
					(size 1.27 1.27)
				)
			)
		)
		(property "Value" "4K7R2F-GP"
			(at 0.064008 -3.993896 90)
			(unlocked yes)
			(layer "F.Fab")
			(hide yes)
			(effects
				(font
					(size 1.016 1.016)
					(thickness 0.1524)
				)
			)
		)
		(property "Device Type" "R402H16"
			(at 0.064008 -5.517896 90)
			(unlocked yes)
			(layer "F.Fab")
			(hide yes)
			(effects
				(font
					(size 1.016 1.016)
					(thickness 0.1524)
				)
			)
		)
		(duplicate_pad_numbers_are_jumpers no)
		(fp_line
			(start 0.508 -0.9398)
			(end -0.508 -0.9398)
			(stroke
				(width 0.1524)
				(type default)
			)
			(layer "F.SilkS")
		)
		(fp_line
			(start -0.508 -0.9398)
			(end -0.508 0.9398)
			(stroke
				(width 0.1524)
				(type default)
			)
			(layer "F.SilkS")
		)
		(fp_rect
			(start -0.508 0.9398)
			(end 0.508 -0.9398)
			(stroke
				(width 0)
				(type default)
			)
			(fill no)
			(layer "F.CrtYd")
		)
		(fp_rect
			(start -0.508 0.9398)
			(end 0.508 -0.9398)
			(stroke
				(width 0)
				(type default)
			)
			(fill no)
			(layer "F.Fab")
		)
		(pad "1" smd custom
			(at 0 -0.4445 90)
			(size 0.1397 0.1397)
			(layers "F.Cu" "F.Mask" "F.Paste")
			(net "VDD_DIFF_3")
			(options
				(clearance outline)
				(anchor circle)
			)
			(primitives
				(gr_poly
					(pts
						(arc
							(start -0.1778 -0.2794)
							(mid -0.249642 -0.249642)
							(end -0.2794 -0.1778)
						)
						(arc
							(start -0.2794 0.1778)
							(mid -0.249642 0.249642)
							(end -0.1778 0.2794)
						)
						(arc
							(start 0.1778 0.2794)
							(mid 0.249642 0.249642)
							(end 0.2794 0.1778)
						)
						(arc
							(start 0.2794 -0.1778)
							(mid 0.249642 -0.249642)
							(end 0.1778 -0.2794)
						)
					)
					(width 0)
					(fill yes)
				)
			)
		)
		(pad "2" smd custom
			(at 0 0.4445 90)
			(size 0.1397 0.1397)
			(layers "F.Cu" "F.Mask" "F.Paste")
			(net "P3V3_PG")
			(options
				(clearance outline)
				(anchor circle)
			)
			(primitives
				(gr_poly
					(pts
						(arc
							(start -0.1778 -0.2794)
							(mid -0.249642 -0.249642)
							(end -0.2794 -0.1778)
						)
						(arc
							(start -0.2794 0.1778)
							(mid -0.249642 0.249642)
							(end -0.1778 0.2794)
						)
						(arc
							(start 0.1778 0.2794)
							(mid 0.249642 0.249642)
							(end 0.2794 0.1778)
						)
						(arc
							(start 0.2794 -0.1778)
							(mid 0.249642 -0.249642)
							(end 0.1778 -0.2794)
						)
					)
					(width 0)
					(fill yes)
				)
			)
		)
	)
	(footprint ""
		(layer "F.Cu")
		(at 84.455 -426.974 90)
		(property "Reference" "R419"
			(at 0 0 90)
			(layer "F.SilkS")
			(hide yes)
			(effects
				(font
					(size 1.27 1.27)
				)
			)
		)
		(property "Value" "0R2J-2-GP"
			(at 0.064008 -3.993896 90)
			(unlocked yes)
			(layer "F.Fab")
			(hide yes)
			(effects
				(font
					(size 1.016 1.016)
					(thickness 0.1524)
				)
			)
		)
		(property "Device Type" "R402H16"
			(at 0.064008 -5.517896 90)
			(unlocked yes)
			(layer "F.Fab")
			(hide yes)
			(effects
				(font
					(size 1.016 1.016)
					(thickness 0.1524)
				)
			)
		)
		(duplicate_pad_numbers_are_jumpers no)
		(fp_line
			(start 0.508 -0.9398)
			(end -0.508 -0.9398)
			(stroke
				(width 0.1524)
				(type default)
			)
			(layer "F.SilkS")
		)
		(fp_line
			(start -0.508 -0.9398)
			(end -0.508 0.9398)
			(stroke
				(width 0.1524)
				(type default)
			)
			(layer "F.SilkS")
		)
		(fp_rect
			(start -0.508 0.9398)
			(end 0.508 -0.9398)
			(stroke
				(width 0)
				(type default)
			)
			(fill no)
			(layer "F.CrtYd")
		)
		(fp_rect
			(start -0.508 0.9398)
			(end 0.508 -0.9398)
			(stroke
				(width 0)
				(type default)
			)
			(fill no)
			(layer "F.Fab")
		)
		(pad "1" smd custom
			(at 0 -0.4445 90)
			(size 0.1397 0.1397)
			(layers "F.Cu" "F.Mask" "F.Paste")
			(net "BMC_I2C_SCL_BUF_9")
			(options
				(clearance outline)
				(anchor circle)
			)
			(primitives
				(gr_poly
					(pts
						(arc
							(start -0.1778 -0.2794)
							(mid -0.249642 -0.249642)
							(end -0.2794 -0.1778)
						)
						(arc
							(start -0.2794 0.1778)
							(mid -0.249642 0.249642)
							(end -0.1778 0.2794)
						)
						(arc
							(start 0.1778 0.2794)
							(mid 0.249642 0.249642)
							(end 0.2794 0.1778)
						)
						(arc
							(start 0.2794 -0.1778)
							(mid 0.249642 -0.249642)
							(end 0.1778 -0.2794)
						)
					)
					(width 0)
					(fill yes)
				)
			)
		)
		(pad "2" smd custom
			(at 0 0.4445 90)
			(size 0.1397 0.1397)
			(layers "F.Cu" "F.Mask" "F.Paste")
			(net "I2C_SCL_BUF_9_EU1_R")
			(options
				(clearance outline)
				(anchor circle)
			)
			(primitives
				(gr_poly
					(pts
						(arc
							(start -0.1778 -0.2794)
							(mid -0.249642 -0.249642)
							(end -0.2794 -0.1778)
						)
						(arc
							(start -0.2794 0.1778)
							(mid -0.249642 0.249642)
							(end -0.1778 0.2794)
						)
						(arc
							(start 0.1778 0.2794)
							(mid 0.249642 0.249642)
							(end 0.2794 0.1778)
						)
						(arc
							(start 0.2794 -0.1778)
							(mid 0.249642 -0.249642)
							(end 0.1778 -0.2794)
						)
					)
					(width 0)
					(fill yes)
				)
			)
		)
	)
	(footprint ""
		(layer "F.Cu")
		(at 34.671 -38.735)
		(property "Reference" "Q75"
			(at 0 0 0)
			(layer "F.SilkS")
			(hide yes)
			(effects
				(font
					(size 1.27 1.27)
				)
			)
		)
		(property "Value" "2N7002A-7-GP"
			(at 0.127 -8.9662 0)
			(unlocked yes)
			(layer "F.Fab")
			(hide yes)
			(effects
				(font
					(size 1.016 1.016)
					(thickness 0.1524)
				)
			)
		)
		(property "Device Type" "SOT23DGS2D4H48"
			(at 0.127 -10.4902 0)
			(unlocked yes)
			(layer "F.Fab")
			(hide yes)
			(effects
				(font
					(size 1.016 1.016)
					(thickness 0.1524)
				)
			)
		)
		(duplicate_pad_numbers_are_jumpers no)
		(fp_line
			(start -1.651 -1.778)
			(end -1.651 1.778)
			(stroke
				(width 0.1524)
				(type default)
			)
			(layer "F.SilkS")
		)
		(fp_line
			(start -1.651 1.778)
			(end 1.651 1.778)
			(stroke
				(width 0.1524)
				(type default)
			)
			(layer "F.SilkS")
		)
		(fp_line
			(start 1.651 -1.778)
			(end -1.651 -1.778)
			(stroke
				(width 0.1524)
				(type default)
			)
			(layer "F.SilkS")
		)
		(fp_line
			(start 1.651 1.778)
			(end 1.651 -1.778)
			(stroke
				(width 0.1524)
				(type default)
			)
			(layer "F.SilkS")
		)
		(fp_poly
			(pts
				(xy -1.778 1.8796) (xy -1.778 -1.8796) (xy 1.778 -1.8796) (xy 1.778 1.8796)
			)
			(stroke
				(width 0)
				(type default)
			)
			(fill no)
			(layer "F.CrtYd")
		)
		(fp_poly
			(pts
				(xy -1.778 1.8796) (xy -1.778 -1.8796) (xy 1.778 -1.8796) (xy 1.778 1.8796)
			)
			(stroke
				(width 0)
				(type default)
			)
			(fill no)
			(layer "F.Fab")
		)
		(pad "D" smd custom
			(at 0 -0.9525)
			(size 0.1905 0.1905)
			(layers "F.Cu" "F.Mask" "F.Paste")
			(net "ATTN_LED_DR9_MOS_N")
			(options
				(clearance outline)
				(anchor circle)
			)
			(primitives
				(gr_poly
					(pts
						(arc
							(start -0.1778 0.5715)
							(mid -0.321484 0.511984)
							(end -0.381 0.3683)
						)
						(arc
							(start -0.381 -0.3683)
							(mid -0.321484 -0.511984)
							(end -0.1778 -0.5715)
						)
						(arc
							(start 0.1778 -0.5715)
							(mid 0.321484 -0.511984)
							(end 0.381 -0.3683)
						)
						(arc
							(start 0.381 0.3683)
							(mid 0.321484 0.511984)
							(end 0.1778 0.5715)
						)
					)
					(width 0)
					(fill yes)
				)
			)
		)
		(pad "G" smd custom
			(at -0.98425 0.9525)
			(size 0.1905 0.1905)
			(layers "F.Cu" "F.Mask" "F.Paste")
			(net "SSD9_CLK0_OE_MOS_N")
			(options
				(clearance outline)
				(anchor circle)
			)
			(primitives
				(gr_poly
					(pts
						(arc
							(start -0.1778 0.5715)
							(mid -0.321484 0.511984)
							(end -0.381 0.3683)
						)
						(arc
							(start -0.381 -0.3683)
							(mid -0.321484 -0.511984)
							(end -0.1778 -0.5715)
						)
						(arc
							(start 0.1778 -0.5715)
							(mid 0.321484 -0.511984)
							(end 0.381 -0.3683)
						)
						(arc
							(start 0.381 0.3683)
							(mid 0.321484 0.511984)
							(end 0.1778 0.5715)
						)
					)
					(width 0)
					(fill yes)
				)
			)
		)
		(pad "S" smd custom
			(at 0.98425 0.9525)
			(size 0.1905 0.1905)
			(layers "F.Cu" "F.Mask" "F.Paste")
			(net "ATTN_LED_DR9_R")
			(options
				(clearance outline)
				(anchor circle)
			)
			(primitives
				(gr_poly
					(pts
						(arc
							(start -0.1778 0.5715)
							(mid -0.321484 0.511984)
							(end -0.381 0.3683)
						)
						(arc
							(start -0.381 -0.3683)
							(mid -0.321484 -0.511984)
							(end -0.1778 -0.5715)
						)
						(arc
							(start 0.1778 -0.5715)
							(mid 0.321484 -0.511984)
							(end 0.381 -0.3683)
						)
						(arc
							(start 0.381 0.3683)
							(mid 0.321484 0.511984)
							(end 0.1778 0.5715)
						)
					)
					(width 0)
					(fill yes)
				)
			)
		)
	)
	(footprint ""
		(layer "F.Cu")
		(at 9.4742 -498.4242 180)
		(property "Reference" "R9508"
			(at 0 0 180)
			(layer "F.SilkS")
			(hide yes)
			(effects
				(font
					(size 1.27 1.27)
				)
			)
		)
		(property "Value" "4K7R2J-2-GP"
			(at 0.064008 -3.993896 180)
			(unlocked yes)
			(layer "F.Fab")
			(hide yes)
			(effects
				(font
					(size 1.016 1.016)
					(thickness 0.1524)
				)
			)
		)
		(property "Device Type" "R402H16"
			(at 0.064008 -5.517896 180)
			(unlocked yes)
			(layer "F.Fab")
			(hide yes)
			(effects
				(font
					(size 1.016 1.016)
					(thickness 0.1524)
				)
			)
		)
		(duplicate_pad_numbers_are_jumpers no)
		(fp_line
			(start 0.508 -0.9398)
			(end -0.508 -0.9398)
			(stroke
				(width 0.1524)
				(type default)
			)
			(layer "F.SilkS")
		)
		(fp_line
			(start -0.508 -0.9398)
			(end -0.508 0.9398)
			(stroke
				(width 0.1524)
				(type default)
			)
			(layer "F.SilkS")
		)
		(fp_rect
			(start -0.508 0.9398)
			(end 0.508 -0.9398)
			(stroke
				(width 0)
				(type default)
			)
			(fill no)
			(layer "F.CrtYd")
		)
		(fp_rect
			(start -0.508 0.9398)
			(end 0.508 -0.9398)
			(stroke
				(width 0)
				(type default)
			)
			(fill no)
			(layer "F.Fab")
		)
		(pad "1" smd custom
			(at 0 -0.4445 180)
			(size 0.1397 0.1397)
			(layers "F.Cu" "F.Mask" "F.Paste")
			(net "P3V3")
			(options
				(clearance outline)
				(anchor circle)
			)
			(primitives
				(gr_poly
					(pts
						(arc
							(start -0.1778 -0.2794)
							(mid -0.249642 -0.249642)
							(end -0.2794 -0.1778)
						)
						(arc
							(start -0.2794 0.1778)
							(mid -0.249642 0.249642)
							(end -0.1778 0.2794)
						)
						(arc
							(start 0.1778 0.2794)
							(mid 0.249642 0.249642)
							(end 0.2794 0.1778)
						)
						(arc
							(start 0.2794 -0.1778)
							(mid 0.249642 -0.249642)
							(end 0.1778 -0.2794)
						)
					)
					(width 0)
					(fill yes)
				)
			)
		)
		(pad "2" smd custom
			(at 0 0.4445 180)
			(size 0.1397 0.1397)
			(layers "F.Cu" "F.Mask" "F.Paste")
			(net "SSD5_PWREN")
			(options
				(clearance outline)
				(anchor circle)
			)
			(primitives
				(gr_poly
					(pts
						(arc
							(start -0.1778 -0.2794)
							(mid -0.249642 -0.249642)
							(end -0.2794 -0.1778)
						)
						(arc
							(start -0.2794 0.1778)
							(mid -0.249642 0.249642)
							(end -0.1778 0.2794)
						)
						(arc
							(start 0.1778 0.2794)
							(mid 0.249642 0.249642)
							(end 0.2794 0.1778)
						)
						(arc
							(start 0.2794 -0.1778)
							(mid 0.249642 -0.249642)
							(end 0.1778 -0.2794)
						)
					)
					(width 0)
					(fill yes)
				)
			)
		)
	)
	(footprint ""
		(layer "F.Cu")
		(at 232.791 -438.023 180)
		(property "Reference" "PG3"
			(at 0 0 180)
			(layer "F.SilkS")
			(hide yes)
			(effects
				(font
					(size 1.27 1.27)
				)
			)
		)
		(property "Value" "COPPER-CLOSE-GP-U"
			(at 0.0762 -2.8702 180)
			(unlocked yes)
			(layer "F.Fab")
			(hide yes)
			(effects
				(font
					(size 1.016 1.016)
					(thickness 0.1524)
				)
			)
		)
		(property "Device Type" "CON2C-U"
			(at 0.0762 -4.3942 180)
			(unlocked yes)
			(layer "F.Fab")
			(hide yes)
			(effects
				(font
					(size 1.016 1.016)
					(thickness 0.1524)
				)
			)
		)
		(duplicate_pad_numbers_are_jumpers no)
		(fp_rect
			(start -0.9398 0.9652)
			(end 0.9398 -0.9652)
			(stroke
				(width 0)
				(type default)
			)
			(fill no)
			(layer "F.CrtYd")
		)
		(fp_rect
			(start -0.9398 0.9652)
			(end 0.9398 -0.9652)
			(stroke
				(width 0)
				(type default)
			)
			(fill no)
			(layer "F.Fab")
		)
		(pad "1" smd custom
			(at 0 -0.5334 180)
			(size 0.17145 0.17145)
			(layers "F.Cu" "F.Mask" "F.Paste")
			(net "AGND_P3V3")
			(options
				(clearance outline)
				(anchor circle)
			)
			(primitives
				(gr_poly
					(pts
						(xy -0.127 0.3429) (xy -0.127 0.1651) (xy -0.635 -0.3429) (xy 0.635 -0.3429) (xy 0.127 0.1651)
						(xy 0.127 0.3429)
					)
					(width 0)
					(fill yes)
				)
			)
		)
		(pad "2" smd custom
			(at 0 0.5334 180)
			(size 0.17145 0.17145)
			(layers "F.Cu" "F.Mask" "F.Paste")
			(net "GND")
			(options
				(clearance outline)
				(anchor circle)
			)
			(primitives
				(gr_poly
					(pts
						(xy -0.635 0.3429) (xy -0.127 -0.1651) (xy -0.127 -0.3429) (xy 0.127 -0.3429) (xy 0.127 -0.1651)
						(xy 0.635 0.3429)
					)
					(width 0)
					(fill yes)
				)
			)
		)
	)
	(footprint ""
		(layer "F.Cu")
		(at 209.804 -397.637 -90)
		(property "Reference" "R138"
			(at 0 0 270)
			(layer "F.SilkS")
			(hide yes)
			(effects
				(font
					(size 1.27 1.27)
				)
			)
		)
		(property "Value" "4K7R2J-2-GP"
			(at 0.064008 -3.993896 270)
			(unlocked yes)
			(layer "F.Fab")
			(hide yes)
			(effects
				(font
					(size 1.016 1.016)
					(thickness 0.1524)
				)
			)
		)
		(property "Device Type" "R402H16"
			(at 0.064008 -5.517896 270)
			(unlocked yes)
			(layer "F.Fab")
			(hide yes)
			(effects
				(font
					(size 1.016 1.016)
					(thickness 0.1524)
				)
			)
		)
		(duplicate_pad_numbers_are_jumpers no)
		(fp_line
			(start -0.508 -0.9398)
			(end -0.508 0.9398)
			(stroke
				(width 0.1524)
				(type default)
			)
			(layer "F.SilkS")
		)
		(fp_line
			(start 0.508 -0.9398)
			(end -0.508 -0.9398)
			(stroke
				(width 0.1524)
				(type default)
			)
			(layer "F.SilkS")
		)
		(fp_rect
			(start -0.508 0.9398)
			(end 0.508 -0.9398)
			(stroke
				(width 0)
				(type default)
			)
			(fill no)
			(layer "F.CrtYd")
		)
		(fp_rect
			(start -0.508 0.9398)
			(end 0.508 -0.9398)
			(stroke
				(width 0)
				(type default)
			)
			(fill no)
			(layer "F.Fab")
		)
		(pad "1" smd custom
			(at 0 -0.4445 270)
			(size 0.1397 0.1397)
			(layers "F.Cu" "F.Mask" "F.Paste")
			(net "P12V")
			(options
				(clearance outline)
				(anchor circle)
			)
			(primitives
				(gr_poly
					(pts
						(arc
							(start -0.1778 -0.2794)
							(mid -0.249642 -0.249642)
							(end -0.2794 -0.1778)
						)
						(arc
							(start -0.2794 0.1778)
							(mid -0.249642 0.249642)
							(end -0.1778 0.2794)
						)
						(arc
							(start 0.1778 0.2794)
							(mid 0.249642 0.249642)
							(end 0.2794 0.1778)
						)
						(arc
							(start 0.2794 -0.1778)
							(mid 0.249642 -0.249642)
							(end 0.1778 -0.2794)
						)
					)
					(width 0)
					(fill yes)
				)
			)
		)
		(pad "2" smd custom
			(at 0 0.4445 270)
			(size 0.1397 0.1397)
			(layers "F.Cu" "F.Mask" "F.Paste")
			(net "SW_SSD1_R")
			(options
				(clearance outline)
				(anchor circle)
			)
			(primitives
				(gr_poly
					(pts
						(arc
							(start -0.1778 -0.2794)
							(mid -0.249642 -0.249642)
							(end -0.2794 -0.1778)
						)
						(arc
							(start -0.2794 0.1778)
							(mid -0.249642 0.249642)
							(end -0.1778 0.2794)
						)
						(arc
							(start 0.1778 0.2794)
							(mid 0.249642 0.249642)
							(end 0.2794 0.1778)
						)
						(arc
							(start 0.2794 -0.1778)
							(mid 0.249642 -0.249642)
							(end 0.1778 -0.2794)
						)
					)
					(width 0)
					(fill yes)
				)
			)
		)
	)
	(footprint ""
		(layer "F.Cu")
		(at 79.248 -435.7878 -90)
		(property "Reference" "C8897"
			(at 0 0 270)
			(layer "F.SilkS")
			(hide yes)
			(effects
				(font
					(size 1.27 1.27)
				)
			)
		)
		(property "Value" "SC10U25V3MX-GP"
			(at 0 -2.8194 270)
			(unlocked yes)
			(layer "F.Fab")
			(hide yes)
			(effects
				(font
					(size 1.016 1.016)
					(thickness 0.1524)
				)
			)
		)
		(property "Device Type" "C603H40"
			(at 0 -4.3434 270)
			(unlocked yes)
			(layer "F.Fab")
			(hide yes)
			(effects
				(font
					(size 1.016 1.016)
					(thickness 0.1524)
				)
			)
		)
		(duplicate_pad_numbers_are_jumpers no)
		(fp_line
			(start 0.508 0)
			(end -0.508 0)
			(stroke
				(width 0.2032)
				(type default)
			)
			(layer "F.SilkS")
		)
		(fp_rect
			(start -0.5842 1.3335)
			(end 0.5842 -1.3335)
			(stroke
				(width 0)
				(type default)
			)
			(fill no)
			(layer "F.CrtYd")
		)
		(fp_rect
			(start -0.5842 1.3335)
			(end 0.5842 -1.3335)
			(stroke
				(width 0)
				(type default)
			)
			(fill no)
			(layer "F.Fab")
		)
		(pad "1" smd custom
			(at 0 -0.762 270)
			(size 0.2159 0.2159)
			(layers "F.Cu" "F.Mask" "F.Paste")
			(net "VDD_DIFF_1")
			(options
				(clearance outline)
				(anchor circle)
			)
			(primitives
				(gr_poly
					(pts
						(arc
							(start -0.3302 -0.4318)
							(mid -0.402042 -0.402042)
							(end -0.4318 -0.3302)
						)
						(arc
							(start -0.4318 0.3302)
							(mid -0.402042 0.402042)
							(end -0.3302 0.4318)
						)
						(arc
							(start 0.3302 0.4318)
							(mid 0.402042 0.402042)
							(end 0.4318 0.3302)
						)
						(arc
							(start 0.4318 -0.3302)
							(mid 0.402042 -0.402042)
							(end 0.3302 -0.4318)
						)
					)
					(width 0)
					(fill yes)
				)
			)
		)
		(pad "2" smd custom
			(at 0 0.762 270)
			(size 0.2159 0.2159)
			(layers "F.Cu" "F.Mask" "F.Paste")
			(net "GND")
			(options
				(clearance outline)
				(anchor circle)
			)
			(primitives
				(gr_poly
					(pts
						(arc
							(start -0.3302 -0.4318)
							(mid -0.402042 -0.402042)
							(end -0.4318 -0.3302)
						)
						(arc
							(start -0.4318 0.3302)
							(mid -0.402042 0.402042)
							(end -0.3302 0.4318)
						)
						(arc
							(start 0.3302 0.4318)
							(mid 0.402042 0.402042)
							(end 0.4318 0.3302)
						)
						(arc
							(start 0.4318 -0.3302)
							(mid 0.402042 -0.402042)
							(end 0.3302 -0.4318)
						)
					)
					(width 0)
					(fill yes)
				)
			)
		)
	)
	(footprint ""
		(layer "F.Cu")
		(at 217.17 -431.673 180)
		(property "Reference" "PC1273"
			(at 0 0 180)
			(layer "F.SilkS")
			(hide yes)
			(effects
				(font
					(size 1.27 1.27)
				)
			)
		)
		(property "Value" "SCD1U50V3KX-GP"
			(at 0 -2.8194 180)
			(unlocked yes)
			(layer "F.Fab")
			(hide yes)
			(effects
				(font
					(size 1.016 1.016)
					(thickness 0.1524)
				)
			)
		)
		(property "Device Type" "C603H36"
			(at 0 -4.3434 180)
			(unlocked yes)
			(layer "F.Fab")
			(hide yes)
			(effects
				(font
					(size 1.016 1.016)
					(thickness 0.1524)
				)
			)
		)
		(duplicate_pad_numbers_are_jumpers no)
		(fp_line
			(start 0.508 0)
			(end -0.508 0)
			(stroke
				(width 0.2032)
				(type default)
			)
			(layer "F.SilkS")
		)
		(fp_rect
			(start -0.5842 1.3335)
			(end 0.5842 -1.3335)
			(stroke
				(width 0)
				(type default)
			)
			(fill no)
			(layer "F.CrtYd")
		)
		(fp_rect
			(start -0.5842 1.3335)
			(end 0.5842 -1.3335)
			(stroke
				(width 0)
				(type default)
			)
			(fill no)
			(layer "F.Fab")
		)
		(pad "1" smd custom
			(at 0 -0.762 180)
			(size 0.2159 0.2159)
			(layers "F.Cu" "F.Mask" "F.Paste")
			(net "P3V3_VFB_R")
			(options
				(clearance outline)
				(anchor circle)
			)
			(primitives
				(gr_poly
					(pts
						(arc
							(start -0.3302 -0.4318)
							(mid -0.402042 -0.402042)
							(end -0.4318 -0.3302)
						)
						(arc
							(start -0.4318 0.3302)
							(mid -0.402042 0.402042)
							(end -0.3302 0.4318)
						)
						(arc
							(start 0.3302 0.4318)
							(mid 0.402042 0.402042)
							(end 0.4318 0.3302)
						)
						(arc
							(start 0.4318 -0.3302)
							(mid 0.402042 -0.402042)
							(end 0.3302 -0.4318)
						)
					)
					(width 0)
					(fill yes)
				)
			)
		)
		(pad "2" smd custom
			(at 0 0.762 180)
			(size 0.2159 0.2159)
			(layers "F.Cu" "F.Mask" "F.Paste")
			(net "P3V3_OUT")
			(options
				(clearance outline)
				(anchor circle)
			)
			(primitives
				(gr_poly
					(pts
						(arc
							(start -0.3302 -0.4318)
							(mid -0.402042 -0.402042)
							(end -0.4318 -0.3302)
						)
						(arc
							(start -0.4318 0.3302)
							(mid -0.402042 0.402042)
							(end -0.3302 0.4318)
						)
						(arc
							(start 0.3302 0.4318)
							(mid 0.402042 0.402042)
							(end 0.4318 0.3302)
						)
						(arc
							(start 0.4318 -0.3302)
							(mid 0.402042 -0.402042)
							(end 0.3302 -0.4318)
						)
					)
					(width 0)
					(fill yes)
				)
			)
		)
	)
	(footprint ""
		(layer "F.Cu")
		(at 88.138 -224.282)
		(property "Reference" "R9612"
			(at 0 0 0)
			(layer "F.SilkS")
			(hide yes)
			(effects
				(font
					(size 1.27 1.27)
				)
			)
		)
		(property "Value" "10R2F-L-GP"
			(at 0.064008 -3.993896 0)
			(unlocked yes)
			(layer "F.Fab")
			(hide yes)
			(effects
				(font
					(size 1.016 1.016)
					(thickness 0.1524)
				)
			)
		)
		(property "Device Type" "R402H14"
			(at 0.064008 -5.517896 0)
			(unlocked yes)
			(layer "F.Fab")
			(hide yes)
			(effects
				(font
					(size 1.016 1.016)
					(thickness 0.1524)
				)
			)
		)
		(duplicate_pad_numbers_are_jumpers no)
		(fp_line
			(start -0.508 -0.9398)
			(end -0.508 0.9398)
			(stroke
				(width 0.1524)
				(type default)
			)
			(layer "F.SilkS")
		)
		(fp_line
			(start 0.508 -0.9398)
			(end -0.508 -0.9398)
			(stroke
				(width 0.1524)
				(type default)
			)
			(layer "F.SilkS")
		)
		(fp_rect
			(start -0.508 0.9398)
			(end 0.508 -0.9398)
			(stroke
				(width 0)
				(type default)
			)
			(fill no)
			(layer "F.CrtYd")
		)
		(fp_rect
			(start -0.508 0.9398)
			(end 0.508 -0.9398)
			(stroke
				(width 0)
				(type default)
			)
			(fill no)
			(layer "F.Fab")
		)
		(pad "1" smd custom
			(at 0 -0.4445)
			(size 0.1397 0.1397)
			(layers "F.Cu" "F.Mask" "F.Paste")
			(net "SSD12_CLK0_OE_N")
			(options
				(clearance outline)
				(anchor circle)
			)
			(primitives
				(gr_poly
					(pts
						(arc
							(start -0.1778 -0.2794)
							(mid -0.249642 -0.249642)
							(end -0.2794 -0.1778)
						)
						(arc
							(start -0.2794 0.1778)
							(mid -0.249642 0.249642)
							(end -0.1778 0.2794)
						)
						(arc
							(start 0.1778 0.2794)
							(mid 0.249642 0.249642)
							(end 0.2794 0.1778)
						)
						(arc
							(start 0.2794 -0.1778)
							(mid 0.249642 -0.249642)
							(end 0.1778 -0.2794)
						)
					)
					(width 0)
					(fill yes)
				)
			)
		)
		(pad "2" smd custom
			(at 0 0.4445)
			(size 0.1397 0.1397)
			(layers "F.Cu" "F.Mask" "F.Paste")
			(net "SSD12_CLK0_OE_R_N")
			(options
				(clearance outline)
				(anchor circle)
			)
			(primitives
				(gr_poly
					(pts
						(arc
							(start -0.1778 -0.2794)
							(mid -0.249642 -0.249642)
							(end -0.2794 -0.1778)
						)
						(arc
							(start -0.2794 0.1778)
							(mid -0.249642 0.249642)
							(end -0.1778 0.2794)
						)
						(arc
							(start 0.1778 0.2794)
							(mid 0.249642 0.249642)
							(end 0.2794 0.1778)
						)
						(arc
							(start 0.2794 -0.1778)
							(mid 0.249642 -0.249642)
							(end 0.1778 -0.2794)
						)
					)
					(width 0)
					(fill yes)
				)
			)
		)
	)
	(footprint ""
		(layer "F.Cu")
		(at 86.487 -313.817 180)
		(property "Reference" "R9103"
			(at 0 0 180)
			(layer "F.SilkS")
			(hide yes)
			(effects
				(font
					(size 1.27 1.27)
				)
			)
		)
		(property "Value" "27R2F-GP"
			(at 0.064008 -3.993896 180)
			(unlocked yes)
			(layer "F.Fab")
			(hide yes)
			(effects
				(font
					(size 1.016 1.016)
					(thickness 0.1524)
				)
			)
		)
		(property "Device Type" "R402H16"
			(at 0.064008 -5.517896 180)
			(unlocked yes)
			(layer "F.Fab")
			(hide yes)
			(effects
				(font
					(size 1.016 1.016)
					(thickness 0.1524)
				)
			)
		)
		(duplicate_pad_numbers_are_jumpers no)
		(fp_line
			(start 0.508 -0.9398)
			(end -0.508 -0.9398)
			(stroke
				(width 0.1524)
				(type default)
			)
			(layer "F.SilkS")
		)
		(fp_line
			(start -0.508 -0.9398)
			(end -0.508 0.9398)
			(stroke
				(width 0.1524)
				(type default)
			)
			(layer "F.SilkS")
		)
		(fp_rect
			(start -0.508 0.9398)
			(end 0.508 -0.9398)
			(stroke
				(width 0)
				(type default)
			)
			(fill no)
			(layer "F.CrtYd")
		)
		(fp_rect
			(start -0.508 0.9398)
			(end 0.508 -0.9398)
			(stroke
				(width 0)
				(type default)
			)
			(fill no)
			(layer "F.Fab")
		)
		(pad "1" smd custom
			(at 0 -0.4445 180)
			(size 0.1397 0.1397)
			(layers "F.Cu" "F.Mask" "F.Paste")
			(net "PE_CLK_100M_DR11_1_R_N")
			(options
				(clearance outline)
				(anchor circle)
			)
			(primitives
				(gr_poly
					(pts
						(arc
							(start -0.1778 -0.2794)
							(mid -0.249642 -0.249642)
							(end -0.2794 -0.1778)
						)
						(arc
							(start -0.2794 0.1778)
							(mid -0.249642 0.249642)
							(end -0.1778 0.2794)
						)
						(arc
							(start 0.1778 0.2794)
							(mid 0.249642 0.249642)
							(end 0.2794 0.1778)
						)
						(arc
							(start 0.2794 -0.1778)
							(mid 0.249642 -0.249642)
							(end 0.1778 -0.2794)
						)
					)
					(width 0)
					(fill yes)
				)
			)
		)
		(pad "2" smd custom
			(at 0 0.4445 180)
			(size 0.1397 0.1397)
			(layers "F.Cu" "F.Mask" "F.Paste")
			(net "PE_CLK100M_DR11_1_N")
			(options
				(clearance outline)
				(anchor circle)
			)
			(primitives
				(gr_poly
					(pts
						(arc
							(start -0.1778 -0.2794)
							(mid -0.249642 -0.249642)
							(end -0.2794 -0.1778)
						)
						(arc
							(start -0.2794 0.1778)
							(mid -0.249642 0.249642)
							(end -0.1778 0.2794)
						)
						(arc
							(start 0.1778 0.2794)
							(mid 0.249642 0.249642)
							(end 0.2794 0.1778)
						)
						(arc
							(start 0.2794 -0.1778)
							(mid 0.249642 -0.249642)
							(end 0.1778 -0.2794)
						)
					)
					(width 0)
					(fill yes)
				)
			)
		)
	)
	(footprint ""
		(layer "F.Cu")
		(at 95.504 -110.236 180)
		(property "Reference" "R9132"
			(at 0 0 180)
			(layer "F.SilkS")
			(hide yes)
			(effects
				(font
					(size 1.27 1.27)
				)
			)
		)
		(property "Value" "27R2F-GP"
			(at 0.064008 -3.993896 180)
			(unlocked yes)
			(layer "F.Fab")
			(hide yes)
			(effects
				(font
					(size 1.016 1.016)
					(thickness 0.1524)
				)
			)
		)
		(property "Device Type" "R402H16"
			(at 0.064008 -5.517896 180)
			(unlocked yes)
			(layer "F.Fab")
			(hide yes)
			(effects
				(font
					(size 1.016 1.016)
					(thickness 0.1524)
				)
			)
		)
		(duplicate_pad_numbers_are_jumpers no)
		(fp_line
			(start 0.508 -0.9398)
			(end -0.508 -0.9398)
			(stroke
				(width 0.1524)
				(type default)
			)
			(layer "F.SilkS")
		)
		(fp_line
			(start -0.508 -0.9398)
			(end -0.508 0.9398)
			(stroke
				(width 0.1524)
				(type default)
			)
			(layer "F.SilkS")
		)
		(fp_rect
			(start -0.508 0.9398)
			(end 0.508 -0.9398)
			(stroke
				(width 0)
				(type default)
			)
			(fill no)
			(layer "F.CrtYd")
		)
		(fp_rect
			(start -0.508 0.9398)
			(end 0.508 -0.9398)
			(stroke
				(width 0)
				(type default)
			)
			(fill no)
			(layer "F.Fab")
		)
		(pad "1" smd custom
			(at 0 -0.4445 180)
			(size 0.1397 0.1397)
			(layers "F.Cu" "F.Mask" "F.Paste")
			(net "PE_CLK_100M_DR8_1_R_N")
			(options
				(clearance outline)
				(anchor circle)
			)
			(primitives
				(gr_poly
					(pts
						(arc
							(start -0.1778 -0.2794)
							(mid -0.249642 -0.249642)
							(end -0.2794 -0.1778)
						)
						(arc
							(start -0.2794 0.1778)
							(mid -0.249642 0.249642)
							(end -0.1778 0.2794)
						)
						(arc
							(start 0.1778 0.2794)
							(mid 0.249642 0.249642)
							(end 0.2794 0.1778)
						)
						(arc
							(start 0.2794 -0.1778)
							(mid 0.249642 -0.249642)
							(end 0.1778 -0.2794)
						)
					)
					(width 0)
					(fill yes)
				)
			)
		)
		(pad "2" smd custom
			(at 0 0.4445 180)
			(size 0.1397 0.1397)
			(layers "F.Cu" "F.Mask" "F.Paste")
			(net "PE_CLK100M_DR8_1_N")
			(options
				(clearance outline)
				(anchor circle)
			)
			(primitives
				(gr_poly
					(pts
						(arc
							(start -0.1778 -0.2794)
							(mid -0.249642 -0.249642)
							(end -0.2794 -0.1778)
						)
						(arc
							(start -0.2794 0.1778)
							(mid -0.249642 0.249642)
							(end -0.1778 0.2794)
						)
						(arc
							(start 0.1778 0.2794)
							(mid 0.249642 0.249642)
							(end 0.2794 0.1778)
						)
						(arc
							(start 0.2794 -0.1778)
							(mid 0.249642 -0.249642)
							(end 0.1778 -0.2794)
						)
					)
					(width 0)
					(fill yes)
				)
			)
		)
	)
	(footprint ""
		(layer "F.Cu")
		(at 26.416 -376.428)
		(property "Reference" "TP7"
			(at 0 0 0)
			(layer "F.SilkS")
			(hide yes)
			(effects
				(font
					(size 1.27 1.27)
				)
			)
		)
		(property "Value" "TPAD32-GP"
			(at -0.0508 -1.6764 0)
			(unlocked yes)
			(layer "F.Fab")
			(hide yes)
			(effects
				(font
					(size 1.016 1.016)
					(thickness 0.1524)
				)
			)
		)
		(property "Device Type" "TPAD32"
			(at -0.0508 -3.2004 0)
			(unlocked yes)
			(layer "F.Fab")
			(hide yes)
			(effects
				(font
					(size 1.016 1.016)
					(thickness 0.1524)
				)
			)
		)
		(duplicate_pad_numbers_are_jumpers no)
		(fp_poly
			(pts
				(arc
					(start 0.4064 0)
					(mid -0.4064 0)
					(end 0.4064 0)
				)
			)
			(stroke
				(width 0)
				(type default)
			)
			(fill no)
			(layer "F.CrtYd")
		)
		(fp_poly
			(pts
				(arc
					(start 0.7112 0)
					(mid -0.7112 0)
					(end 0.7112 0)
				)
			)
			(stroke
				(width 0)
				(type default)
			)
			(fill no)
			(layer "F.Fab")
		)
		(pad "1" smd circle
			(at 0 0)
			(size 0.8128 0.8128)
			(layers "F.Cu" "F.Mask" "F.Paste")
			(net "I2C_B_TMP4_ALERT")
		)
	)
	(footprint ""
		(layer "F.Cu")
		(at 206.67345 -404.94585 90)
		(property "Reference" "R9785"
			(at 0 0 90)
			(layer "F.SilkS")
			(hide yes)
			(effects
				(font
					(size 1.27 1.27)
				)
			)
		)
		(property "Value" "1KR2J-1-GP"
			(at 0.064008 -3.993896 90)
			(unlocked yes)
			(layer "F.Fab")
			(hide yes)
			(effects
				(font
					(size 1.016 1.016)
					(thickness 0.1524)
				)
			)
		)
		(property "Device Type" "R402H16"
			(at 0.064008 -5.517896 90)
			(unlocked yes)
			(layer "F.Fab")
			(hide yes)
			(effects
				(font
					(size 1.016 1.016)
					(thickness 0.1524)
				)
			)
		)
		(duplicate_pad_numbers_are_jumpers no)
		(fp_line
			(start 0.508 -0.9398)
			(end -0.508 -0.9398)
			(stroke
				(width 0.1524)
				(type default)
			)
			(layer "F.SilkS")
		)
		(fp_line
			(start -0.508 -0.9398)
			(end -0.508 0.9398)
			(stroke
				(width 0.1524)
				(type default)
			)
			(layer "F.SilkS")
		)
		(fp_rect
			(start -0.508 0.9398)
			(end 0.508 -0.9398)
			(stroke
				(width 0)
				(type default)
			)
			(fill no)
			(layer "F.CrtYd")
		)
		(fp_rect
			(start -0.508 0.9398)
			(end 0.508 -0.9398)
			(stroke
				(width 0)
				(type default)
			)
			(fill no)
			(layer "F.Fab")
		)
		(pad "1" smd custom
			(at 0 -0.4445 90)
			(size 0.1397 0.1397)
			(layers "F.Cu" "F.Mask" "F.Paste")
			(net "SSD1_PWREN")
			(options
				(clearance outline)
				(anchor circle)
			)
			(primitives
				(gr_poly
					(pts
						(arc
							(start -0.1778 -0.2794)
							(mid -0.249642 -0.249642)
							(end -0.2794 -0.1778)
						)
						(arc
							(start -0.2794 0.1778)
							(mid -0.249642 0.249642)
							(end -0.1778 0.2794)
						)
						(arc
							(start 0.1778 0.2794)
							(mid 0.249642 0.249642)
							(end 0.2794 0.1778)
						)
						(arc
							(start 0.2794 -0.1778)
							(mid 0.249642 -0.249642)
							(end 0.1778 -0.2794)
						)
					)
					(width 0)
					(fill yes)
				)
			)
		)
		(pad "2" smd custom
			(at 0 0.4445 90)
			(size 0.1397 0.1397)
			(layers "F.Cu" "F.Mask" "F.Paste")
			(net "SSD1_PWREN_R")
			(options
				(clearance outline)
				(anchor circle)
			)
			(primitives
				(gr_poly
					(pts
						(arc
							(start -0.1778 -0.2794)
							(mid -0.249642 -0.249642)
							(end -0.2794 -0.1778)
						)
						(arc
							(start -0.2794 0.1778)
							(mid -0.249642 0.249642)
							(end -0.1778 0.2794)
						)
						(arc
							(start 0.1778 0.2794)
							(mid 0.249642 0.249642)
							(end 0.2794 0.1778)
						)
						(arc
							(start 0.2794 -0.1778)
							(mid 0.249642 -0.249642)
							(end 0.1778 -0.2794)
						)
					)
					(width 0)
					(fill yes)
				)
			)
		)
	)
	(footprint ""
		(layer "F.Cu")
		(at 41.150032 -273.670014 90)
		(property "Reference" "J7"
			(at 0 0 90)
			(layer "F.SilkS")
			(hide yes)
			(effects
				(font
					(size 1.27 1.27)
				)
			)
		)
		(property "Value" "PCISLT68-14-GP-U1"
			(at -22.225 12.7508 90)
			(unlocked yes)
			(layer "F.Fab")
			(hide yes)
			(effects
				(font
					(size 1.016 1.016)
					(thickness 0.1524)
				)
			)
		)
		(property "Device Type" "SD-78827-0001"
			(at -22.225 11.2268 90)
			(unlocked yes)
			(layer "F.Fab")
			(hide yes)
			(effects
				(font
					(size 1.016 1.016)
					(thickness 0.1524)
				)
			)
		)
		(duplicate_pad_numbers_are_jumpers no)
		(fp_line
			(start 20.4724 -3.4036)
			(end 20.4724 0.0254)
			(stroke
				(width 0.1524)
				(type default)
			)
			(layer "F.SilkS")
		)
		(fp_line
			(start -20.4724 -3.4036)
			(end 20.4724 -3.4036)
			(stroke
				(width 0.1524)
				(type default)
			)
			(layer "F.SilkS")
		)
		(fp_line
			(start 23.749 0.0254)
			(end 23.749 4.6736)
			(stroke
				(width 0.1524)
				(type default)
			)
			(layer "F.SilkS")
		)
		(fp_line
			(start 20.4724 0.0254)
			(end 23.749 0.0254)
			(stroke
				(width 0.1524)
				(type default)
			)
			(layer "F.SilkS")
		)
		(fp_line
			(start -20.4724 0.0254)
			(end -20.4724 -3.4036)
			(stroke
				(width 0.1524)
				(type default)
			)
			(layer "F.SilkS")
		)
		(fp_line
			(start -23.749 0.0254)
			(end -20.4724 0.0254)
			(stroke
				(width 0.1524)
				(type default)
			)
			(layer "F.SilkS")
		)
		(fp_line
			(start 23.117556 1.803908)
			(end 23.117556 2.896108)
			(stroke
				(width 0.3048)
				(type default)
			)
			(layer "F.SilkS")
		)
		(fp_line
			(start -20.882356 1.803908)
			(end -20.882356 2.896108)
			(stroke
				(width 0.3048)
				(type default)
			)
			(layer "F.SilkS")
		)
		(fp_line
			(start 20.882356 2.896108)
			(end 20.882356 1.803908)
			(stroke
				(width 0.3048)
				(type default)
			)
			(layer "F.SilkS")
		)
		(fp_line
			(start -23.117556 2.896108)
			(end -23.117556 1.803908)
			(stroke
				(width 0.3048)
				(type default)
			)
			(layer "F.SilkS")
		)
		(fp_line
			(start 23.749 4.6736)
			(end 20.4724 4.6736)
			(stroke
				(width 0.1524)
				(type default)
			)
			(layer "F.SilkS")
		)
		(fp_line
			(start 20.4724 4.6736)
			(end 20.4724 12.0142)
			(stroke
				(width 0.1524)
				(type default)
			)
			(layer "F.SilkS")
		)
		(fp_line
			(start -20.4724 4.6736)
			(end -23.749 4.6736)
			(stroke
				(width 0.1524)
				(type default)
			)
			(layer "F.SilkS")
		)
		(fp_line
			(start -23.749 4.6736)
			(end -23.749 0.0254)
			(stroke
				(width 0.1524)
				(type default)
			)
			(layer "F.SilkS")
		)
		(fp_line
			(start 17.8435 10.3124)
			(end -17.8435 10.3124)
			(stroke
				(width 0.1524)
				(type default)
			)
			(layer "F.SilkS")
		)
		(fp_line
			(start -17.8435 10.3124)
			(end -17.8435 12.0142)
			(stroke
				(width 0.1524)
				(type default)
			)
			(layer "F.SilkS")
		)
		(fp_line
			(start 20.4724 12.0142)
			(end 17.8435 12.0142)
			(stroke
				(width 0.1524)
				(type default)
			)
			(layer "F.SilkS")
		)
		(fp_line
			(start 17.8435 12.0142)
			(end 17.8435 10.3124)
			(stroke
				(width 0.1524)
				(type default)
			)
			(layer "F.SilkS")
		)
		(fp_line
			(start -17.8435 12.0142)
			(end -20.4724 12.0142)
			(stroke
				(width 0.1524)
				(type default)
			)
			(layer "F.SilkS")
		)
		(fp_line
			(start -20.4724 12.0142)
			(end -20.4724 4.6736)
			(stroke
				(width 0.1524)
				(type default)
			)
			(layer "F.SilkS")
		)
		(fp_arc
			(start 20.882356 1.803908)
			(mid 21.999956 0.686308)
			(end 23.117556 1.803908)
			(stroke
				(width 0.3048)
				(type default)
			)
			(layer "F.SilkS")
		)
		(fp_arc
			(start -23.117556 1.803908)
			(mid -21.999956 0.686308)
			(end -20.882356 1.803908)
			(stroke
				(width 0.3048)
				(type default)
			)
			(layer "F.SilkS")
		)
		(fp_arc
			(start 23.117556 2.896108)
			(mid 21.999956 4.013708)
			(end 20.882356 2.896108)
			(stroke
				(width 0.3048)
				(type default)
			)
			(layer "F.SilkS")
		)
		(fp_arc
			(start -20.882356 2.896108)
			(mid -21.999956 4.013708)
			(end -23.117556 2.896108)
			(stroke
				(width 0.3048)
				(type default)
			)
			(layer "F.SilkS")
		)
		(fp_poly
			(pts
				(xy -20.2184 11.7602) (xy -20.2184 4.4196) (xy -23.495 4.4196) (xy -23.495 0.2794) (xy -20.2184 0.2794)
				(xy -20.2184 -3.1496) (xy 20.2184 -3.1496) (xy 20.2184 0.2794) (xy 23.495 0.2794) (xy 23.495 4.4196)
				(xy 20.2184 4.4196) (xy 20.2184 11.7602) (xy 18.0975 11.7602) (xy 18.0975 10.0584) (xy -18.0975 10.0584)
				(xy -18.0975 11.7602)
			)
			(stroke
				(width 0)
				(type default)
			)
			(fill no)
			(layer "F.CrtYd")
		)
		(fp_poly
			(pts
				(xy -21.2471 16.256) (xy -21.2471 4.9276) (xy -24.003 4.9276) (xy -24.003 -0.2286) (xy -20.7264 -0.2286)
				(xy -20.7264 -3.6576) (xy 20.7264 -3.6576) (xy 20.7264 -0.2286) (xy 24.003 -0.2286) (xy 24.003 -0.00635)
				(xy 20.2184 -0.00635) (xy 20.2184 -3.1496) (xy -20.2184 -3.1496) (xy -20.2184 0.2794) (xy -23.495 0.2794)
				(xy -23.495 4.4196) (xy -20.2184 4.4196) (xy -20.2184 11.7602) (xy -18.0975 11.7602) (xy -18.0975 10.0584)
				(xy 18.0975 10.0584) (xy 18.0975 11.7602) (xy 20.2184 11.7602) (xy 20.2184 4.4196) (xy 23.495 4.4196)
				(xy 23.495 0.2794) (xy 20.2184 0.2794) (xy 20.2184 0.00635) (xy 24.003 0.00635) (xy 24.003 4.9276)
				(xy 21.2471 4.9276) (xy 21.2471 16.256)
			)
			(stroke
				(width 0)
				(type default)
			)
			(fill no)
			(layer "F.CrtYd")
		)
		(fp_poly
			(pts
				(xy -21.2471 16.256) (xy -21.2471 4.9276) (xy -24.003 4.9276) (xy -24.003 -0.2286) (xy -20.7264 -0.2286)
				(xy -20.7264 -3.6576) (xy 20.7264 -3.6576) (xy 20.7264 -0.2286) (xy 24.003 -0.2286) (xy 24.003 4.9276)
				(xy 21.2471 4.9276) (xy 21.2471 16.256)
			)
			(stroke
				(width 0)
				(type default)
			)
			(fill no)
			(layer "F.Fab")
		)
		(pad "" np_thru_hole circle
			(at -18.999962 0 90)
			(size 0.254 0.254)
			(drill 1.8542)
			(layers "*.Cu" "*.Mask")
			(clearance 1.1557)
			(thermal_gap 1.1557)
		)
		(pad "" np_thru_hole circle
			(at 18.999962 0 90)
			(size 0.254 0.254)
			(drill 1.8542)
			(layers "*.Cu" "*.Mask")
			(clearance 1.1557)
			(thermal_gap 1.1557)
		)
		(pad "E1" smd rect
			(at -7.079996 1.240028 90)
			(size 0.508 2.0066)
			(layers "F.Cu" "F.Mask" "F.Paste")
			(net "PE_CLK100M_DR7_2_P")
		)
		(pad "E2" smd rect
			(at -6.279896 1.240028 90)
			(size 0.508 2.0066)
			(layers "F.Cu" "F.Mask" "F.Paste")
			(net "PE_CLK100M_DR7_2_N")
		)
		(pad "E3" smd rect
			(at -5.48005 1.240028 90)
			(size 0.508 2.0066)
			(layers "F.Cu" "F.Mask" "F.Paste")
			(net "P3V3")
		)
		(pad "E4" smd rect
			(at -4.67995 1.240028 90)
			(size 0.508 2.0066)
			(layers "F.Cu" "F.Mask" "F.Paste")
			(net "SSD7_PERST_N")
		)
		(pad "E5" smd rect
			(at -3.880104 1.240028 90)
			(size 0.508 2.0066)
			(layers "F.Cu" "F.Mask" "F.Paste")
			(net "SSD7_PERST_N")
		)
		(pad "E6" smd rect
			(at -3.080004 1.240028 90)
			(size 0.508 2.0066)
			(layers "F.Cu" "F.Mask" "F.Paste")
			(net "Net_1107")
		)
		(pad "E7" smd rect
			(at -15.48003 -1.949958 90)
			(size 0.508 2.0066)
			(layers "F.Cu" "F.Mask" "F.Paste")
			(net "PE_CLK100M_DR7_1_P")
		)
		(pad "E8" smd rect
			(at -14.67993 -1.949958 90)
			(size 0.508 2.0066)
			(layers "F.Cu" "F.Mask" "F.Paste")
			(net "PE_CLK100M_DR7_1_N")
		)
		(pad "E9" smd rect
			(at -13.880084 -1.949958 90)
			(size 0.508 2.0066)
			(layers "F.Cu" "F.Mask" "F.Paste")
			(net "GND")
		)
		(pad "E10" smd rect
			(at -13.079984 -1.949958 90)
			(size 0.508 2.0066)
			(layers "F.Cu" "F.Mask" "F.Paste")
			(net "PE_TX1_DR7_N")
		)
		(pad "E11" smd rect
			(at -12.279884 -1.949958 90)
			(size 0.508 2.0066)
			(layers "F.Cu" "F.Mask" "F.Paste")
			(net "PE_TX1_DR7_P")
		)
		(pad "E12" smd rect
			(at -11.480038 -1.949958 90)
			(size 0.508 2.0066)
			(layers "F.Cu" "F.Mask" "F.Paste")
			(net "GND")
		)
		(pad "E13" smd rect
			(at -10.679938 -1.949958 90)
			(size 0.508 2.0066)
			(layers "F.Cu" "F.Mask" "F.Paste")
			(net "PE_RX1_DR7_N")
		)
		(pad "E14" smd rect
			(at -9.880092 -1.949958 90)
			(size 0.508 2.0066)
			(layers "F.Cu" "F.Mask" "F.Paste")
			(net "PE_RX1_DR7_P")
		)
		(pad "E15" smd rect
			(at -9.079992 -1.949958 90)
			(size 0.508 2.0066)
			(layers "F.Cu" "F.Mask" "F.Paste")
			(net "GND")
		)
		(pad "E16" smd rect
			(at -8.279892 -1.949958 90)
			(size 0.508 2.0066)
			(layers "F.Cu" "F.Mask" "F.Paste")
			(net "Net_1114")
		)
		(pad "E17" smd rect
			(at 9.320022 -1.949958 90)
			(size 0.508 2.0066)
			(layers "F.Cu" "F.Mask" "F.Paste")
			(net "PE_TX4_DR7_N")
		)
		(pad "E18" smd rect
			(at 10.120122 -1.949958 90)
			(size 0.508 2.0066)
			(layers "F.Cu" "F.Mask" "F.Paste")
			(net "PE_TX4_DR7_P")
		)
		(pad "E19" smd rect
			(at 10.919968 -1.949958 90)
			(size 0.508 2.0066)
			(layers "F.Cu" "F.Mask" "F.Paste")
			(net "GND")
		)
		(pad "E20" smd rect
			(at 11.720068 -1.949958 90)
			(size 0.508 2.0066)
			(layers "F.Cu" "F.Mask" "F.Paste")
			(net "PE_RX4_DR7_N")
		)
		(pad "E21" smd rect
			(at 12.519914 -1.949958 90)
			(size 0.508 2.0066)
			(layers "F.Cu" "F.Mask" "F.Paste")
			(net "PE_RX4_DR7_P")
		)
		(pad "E22" smd rect
			(at 13.320014 -1.949958 90)
			(size 0.508 2.0066)
			(layers "F.Cu" "F.Mask" "F.Paste")
			(net "GND")
		)
		(pad "E23" smd rect
			(at 14.120114 -1.949958 90)
			(size 0.508 2.0066)
			(layers "F.Cu" "F.Mask" "F.Paste")
			(net "SCL_DR7_R")
		)
		(pad "E24" smd rect
			(at 14.91996 -1.949958 90)
			(size 0.508 2.0066)
			(layers "F.Cu" "F.Mask" "F.Paste")
			(net "SDA_DR7_R")
		)
		(pad "E25" smd rect
			(at 15.72006 -1.949958 90)
			(size 0.508 2.0066)
			(layers "F.Cu" "F.Mask" "F.Paste")
			(net "DUALPORTEN#7")
		)
		(pad "P1" smd rect
			(at -1.905 0.824992 90)
			(size 0.6604 2.0574)
			(layers "F.Cu" "F.Mask" "F.Paste")
			(net "Net_1110")
		)
		(pad "P2" smd rect
			(at -0.635 0.824992 90)
			(size 0.6604 2.0574)
			(layers "F.Cu" "F.Mask" "F.Paste")
			(net "Net_1109")
		)
		(pad "P3" smd rect
			(at 0.635 0.824992 90)
			(size 0.6604 2.0574)
			(layers "F.Cu" "F.Mask" "F.Paste")
			(net "Net_1108")
		)
		(pad "P4" smd rect
			(at 1.905 0.824992 90)
			(size 0.6604 2.0574)
			(layers "F.Cu" "F.Mask" "F.Paste")
			(net "SSD7_CLK0_OE_N")
		)
		(pad "P5" smd rect
			(at 3.175 0.824992 90)
			(size 0.6604 2.0574)
			(layers "F.Cu" "F.Mask" "F.Paste")
			(net "GND")
		)
		(pad "P6" smd rect
			(at 4.445 0.824992 90)
			(size 0.6604 2.0574)
			(layers "F.Cu" "F.Mask" "F.Paste")
			(net "GND")
		)
		(pad "P7" smd rect
			(at 5.715 0.824992 90)
			(size 0.6604 2.0574)
			(layers "F.Cu" "F.Mask" "F.Paste")
			(net "Net_101")
		)
		(pad "P8" smd rect
			(at 6.985 0.824992 90)
			(size 0.6604 2.0574)
			(layers "F.Cu" "F.Mask" "F.Paste")
			(net "Net_71")
		)
		(pad "P9" smd rect
			(at 8.255 0.824992 90)
			(size 0.6604 2.0574)
			(layers "F.Cu" "F.Mask" "F.Paste")
			(net "Net_85")
		)
		(pad "P10" smd rect
			(at 9.525 0.824992 90)
			(size 0.6604 2.0574)
			(layers "F.Cu" "F.Mask" "F.Paste")
			(net "SSD_PRSNT_NET7")
		)
		(pad "P11" smd rect
			(at 10.795 0.824992 90)
			(size 0.6604 2.0574)
			(layers "F.Cu" "F.Mask" "F.Paste")
			(net "SSD_ACT_DR7")
		)
		(pad "P12" smd rect
			(at 12.065 0.824992 90)
			(size 0.6604 2.0574)
			(layers "F.Cu" "F.Mask" "F.Paste")
			(net "GND")
		)
		(pad "P13" smd rect
			(at 13.335 0.824992 90)
			(size 0.6604 2.0574)
			(layers "F.Cu" "F.Mask" "F.Paste")
			(net "12V_PRECH_SSD7")
		)
		(pad "P14" smd rect
			(at 14.605 0.824992 90)
			(size 0.6604 2.0574)
			(layers "F.Cu" "F.Mask" "F.Paste")
			(net "P12V_SSD7")
		)
		(pad "P15" smd rect
			(at 15.875 0.824992 90)
			(size 0.6604 2.0574)
			(layers "F.Cu" "F.Mask" "F.Paste")
			(net "P12V_SSD7")
		)
		(pad "PTH1" thru_hole oval
			(at -21.999956 2.350008 90)
			(size 1.524 2.6162)
			(drill oval 0.8128 1.905)
			(layers "*.Cu" "*.Mask")
			(remove_unused_layers no)
			(net "Net_1119")
			(clearance 0.1524)
			(thermal_gap 0.1524)
		)
		(pad "PTH2" thru_hole oval
			(at 21.999956 2.350008 90)
			(size 1.524 2.6162)
			(drill oval 0.8128 1.905)
			(layers "*.Cu" "*.Mask")
			(remove_unused_layers no)
			(net "Net_1103")
			(clearance 0.1524)
			(thermal_gap 0.1524)
		)
		(pad "S1" smd rect
			(at -15.875 0.824992 90)
			(size 0.6604 2.0574)
			(layers "F.Cu" "F.Mask" "F.Paste")
			(net "GND")
		)
		(pad "S2" smd rect
			(at -14.605 0.824992 90)
			(size 0.6604 2.0574)
			(layers "F.Cu" "F.Mask" "F.Paste")
			(net "Net_1118")
		)
		(pad "S3" smd rect
			(at -13.335 0.824992 90)
			(size 0.6604 2.0574)
			(layers "F.Cu" "F.Mask" "F.Paste")
			(net "Net_1117")
		)
		(pad "S4" smd rect
			(at -12.065 0.824992 90)
			(size 0.6604 2.0574)
			(layers "F.Cu" "F.Mask" "F.Paste")
			(net "GND")
		)
		(pad "S5" smd rect
			(at -10.795 0.824992 90)
			(size 0.6604 2.0574)
			(layers "F.Cu" "F.Mask" "F.Paste")
			(net "Net_1116")
		)
		(pad "S6" smd rect
			(at -9.525 0.824992 90)
			(size 0.6604 2.0574)
			(layers "F.Cu" "F.Mask" "F.Paste")
			(net "Net_1115")
		)
		(pad "S7" smd rect
			(at -8.255 0.824992 90)
			(size 0.6604 2.0574)
			(layers "F.Cu" "F.Mask" "F.Paste")
			(net "GND")
		)
		(pad "S8" smd rect
			(at -7.480046 -1.949958 90)
			(size 0.508 2.0066)
			(layers "F.Cu" "F.Mask" "F.Paste")
			(net "GND")
		)
		(pad "S9" smd rect
			(at -6.679946 -1.949958 90)
			(size 0.508 2.0066)
			(layers "F.Cu" "F.Mask" "F.Paste")
			(net "Net_1113")
		)
		(pad "S10" smd rect
			(at -5.8801 -1.949958 90)
			(size 0.508 2.0066)
			(layers "F.Cu" "F.Mask" "F.Paste")
			(net "Net_1112")
		)
		(pad "S11" smd rect
			(at -5.08 -1.949958 90)
			(size 0.508 2.0066)
			(layers "F.Cu" "F.Mask" "F.Paste")
			(net "GND")
		)
		(pad "S12" smd rect
			(at -4.2799 -1.949958 90)
			(size 0.508 2.0066)
			(layers "F.Cu" "F.Mask" "F.Paste")
			(net "Net_1111")
		)
		(pad "S13" smd rect
			(at -3.480054 -1.949958 90)
			(size 0.508 2.0066)
			(layers "F.Cu" "F.Mask" "F.Paste")
			(net "Net_1106")
		)
		(pad "S14" smd rect
			(at -2.679954 -1.949958 90)
			(size 0.508 2.0066)
			(layers "F.Cu" "F.Mask" "F.Paste")
			(net "GND")
		)
		(pad "S15" smd rect
			(at -1.880108 -1.949958 90)
			(size 0.508 2.0066)
			(layers "F.Cu" "F.Mask" "F.Paste")
			(net "Net_1105")
		)
		(pad "S16" smd rect
			(at -1.080008 -1.949958 90)
			(size 0.508 2.0066)
			(layers "F.Cu" "F.Mask" "F.Paste")
			(net "GND")
		)
		(pad "S17" smd rect
			(at -0.279908 -1.949958 90)
			(size 0.508 2.0066)
			(layers "F.Cu" "F.Mask" "F.Paste")
			(net "PE_TX2_DR7_N")
		)
		(pad "S18" smd rect
			(at 0.519938 -1.949958 90)
			(size 0.508 2.0066)
			(layers "F.Cu" "F.Mask" "F.Paste")
			(net "PE_TX2_DR7_P")
		)
		(pad "S19" smd rect
			(at 1.320038 -1.949958 90)
			(size 0.508 2.0066)
			(layers "F.Cu" "F.Mask" "F.Paste")
			(net "GND")
		)
		(pad "S20" smd rect
			(at 2.119884 -1.949958 90)
			(size 0.508 2.0066)
			(layers "F.Cu" "F.Mask" "F.Paste")
			(net "PE_RX2_DR7_N")
		)
		(pad "S21" smd rect
			(at 2.919984 -1.949958 90)
			(size 0.508 2.0066)
			(layers "F.Cu" "F.Mask" "F.Paste")
			(net "PE_RX2_DR7_P")
		)
		(pad "S22" smd rect
			(at 3.720084 -1.949958 90)
			(size 0.508 2.0066)
			(layers "F.Cu" "F.Mask" "F.Paste")
			(net "GND")
		)
		(pad "S23" smd rect
			(at 4.51993 -1.949958 90)
			(size 0.508 2.0066)
			(layers "F.Cu" "F.Mask" "F.Paste")
			(net "PE_TX3_DR7_N")
		)
		(pad "S24" smd rect
			(at 5.32003 -1.949958 90)
			(size 0.508 2.0066)
			(layers "F.Cu" "F.Mask" "F.Paste")
			(net "PE_TX3_DR7_P")
		)
		(pad "S25" smd rect
			(at 6.119876 -1.949958 90)
			(size 0.508 2.0066)
			(layers "F.Cu" "F.Mask" "F.Paste")
			(net "GND")
		)
		(pad "S26" smd rect
			(at 6.919976 -1.949958 90)
			(size 0.508 2.0066)
			(layers "F.Cu" "F.Mask" "F.Paste")
			(net "PE_RX3_DR7_N")
		)
		(pad "S27" smd rect
			(at 7.720076 -1.949958 90)
			(size 0.508 2.0066)
			(layers "F.Cu" "F.Mask" "F.Paste")
			(net "PE_RX3_DR7_P")
		)
		(pad "S28" smd rect
			(at 8.519922 -1.949958 90)
			(size 0.508 2.0066)
			(layers "F.Cu" "F.Mask" "F.Paste")
			(net "GND")
		)
		(zone
			(layers "F.Cu" "B.Cu" "In1.Cu" "In2.Cu" "In3.Cu" "In4.Cu" "In5.Cu" "In6.Cu")
			(hatch none 0.5)
			(connect_pads
				(clearance 0)
			)
			(min_thickness 0.25)
			(keepout
				(tracks not_allowed)
				(vias allowed)
				(pads allowed)
				(copperpour not_allowed)
				(footprints allowed)
			)
			(placement
				(enabled no)
				(sheetname "")
			)
			(fill
				(thermal_gap 0.5)
				(thermal_bridge_width 0.5)
				(island_removal_mode 0)
			)
			(polygon
				(pts
					(arc
						(start 42.381932 -292.669976)
						(mid 39.918132 -292.669976)
						(end 42.381932 -292.669976)
					)
				)
			)
		)
		(zone
			(layers "F.Cu" "B.Cu" "In1.Cu" "In2.Cu" "In3.Cu" "In4.Cu" "In5.Cu" "In6.Cu")
			(hatch none 0.5)
			(connect_pads
				(clearance 0)
			)
			(min_thickness 0.25)
			(keepout
				(tracks not_allowed)
				(vias allowed)
				(pads allowed)
				(copperpour not_allowed)
				(footprints allowed)
			)
			(placement
				(enabled no)
				(sheetname "")
			)
			(fill
				(thermal_gap 0.5)
				(thermal_bridge_width 0.5)
				(island_removal_mode 0)
			)
			(polygon
				(pts
					(arc
						(start 42.381932 -254.670052)
						(mid 39.918132 -254.670052)
						(end 42.381932 -254.670052)
					)
				)
			)
		)
	)
	(footprint ""
		(layer "F.Cu")
		(at 206.67345 -198.95185 90)
		(property "Reference" "R9799"
			(at 0 0 90)
			(layer "F.SilkS")
			(hide yes)
			(effects
				(font
					(size 1.27 1.27)
				)
			)
		)
		(property "Value" "1KR2J-1-GP"
			(at 0.064008 -3.993896 90)
			(unlocked yes)
			(layer "F.Fab")
			(hide yes)
			(effects
				(font
					(size 1.016 1.016)
					(thickness 0.1524)
				)
			)
		)
		(property "Device Type" "R402H16"
			(at 0.064008 -5.517896 90)
			(unlocked yes)
			(layer "F.Fab")
			(hide yes)
			(effects
				(font
					(size 1.016 1.016)
					(thickness 0.1524)
				)
			)
		)
		(duplicate_pad_numbers_are_jumpers no)
		(fp_line
			(start 0.508 -0.9398)
			(end -0.508 -0.9398)
			(stroke
				(width 0.1524)
				(type default)
			)
			(layer "F.SilkS")
		)
		(fp_line
			(start -0.508 -0.9398)
			(end -0.508 0.9398)
			(stroke
				(width 0.1524)
				(type default)
			)
			(layer "F.SilkS")
		)
		(fp_rect
			(start -0.508 0.9398)
			(end 0.508 -0.9398)
			(stroke
				(width 0)
				(type default)
			)
			(fill no)
			(layer "F.CrtYd")
		)
		(fp_rect
			(start -0.508 0.9398)
			(end 0.508 -0.9398)
			(stroke
				(width 0)
				(type default)
			)
			(fill no)
			(layer "F.Fab")
		)
		(pad "1" smd custom
			(at 0 -0.4445 90)
			(size 0.1397 0.1397)
			(layers "F.Cu" "F.Mask" "F.Paste")
			(net "SSD3_PWREN")
			(options
				(clearance outline)
				(anchor circle)
			)
			(primitives
				(gr_poly
					(pts
						(arc
							(start -0.1778 -0.2794)
							(mid -0.249642 -0.249642)
							(end -0.2794 -0.1778)
						)
						(arc
							(start -0.2794 0.1778)
							(mid -0.249642 0.249642)
							(end -0.1778 0.2794)
						)
						(arc
							(start 0.1778 0.2794)
							(mid 0.249642 0.249642)
							(end 0.2794 0.1778)
						)
						(arc
							(start 0.2794 -0.1778)
							(mid 0.249642 -0.249642)
							(end 0.1778 -0.2794)
						)
					)
					(width 0)
					(fill yes)
				)
			)
		)
		(pad "2" smd custom
			(at 0 0.4445 90)
			(size 0.1397 0.1397)
			(layers "F.Cu" "F.Mask" "F.Paste")
			(net "SSD3_PWREN_R")
			(options
				(clearance outline)
				(anchor circle)
			)
			(primitives
				(gr_poly
					(pts
						(arc
							(start -0.1778 -0.2794)
							(mid -0.249642 -0.249642)
							(end -0.2794 -0.1778)
						)
						(arc
							(start -0.2794 0.1778)
							(mid -0.249642 0.249642)
							(end -0.1778 0.2794)
						)
						(arc
							(start 0.1778 0.2794)
							(mid 0.249642 0.249642)
							(end 0.2794 0.1778)
						)
						(arc
							(start 0.2794 -0.1778)
							(mid 0.249642 -0.249642)
							(end 0.1778 -0.2794)
						)
					)
					(width 0)
					(fill yes)
				)
			)
		)
	)
	(footprint ""
		(layer "F.Cu")
		(at 234.061 -453.771 -90)
		(property "Reference" "R111"
			(at 0 0 270)
			(layer "F.SilkS")
			(hide yes)
			(effects
				(font
					(size 1.27 1.27)
				)
			)
		)
		(property "Value" "330R2F-GP"
			(at 0.064008 -3.993896 270)
			(unlocked yes)
			(layer "F.Fab")
			(hide yes)
			(effects
				(font
					(size 1.016 1.016)
					(thickness 0.1524)
				)
			)
		)
		(property "Device Type" "R402H16"
			(at 0.064008 -5.517896 270)
			(unlocked yes)
			(layer "F.Fab")
			(hide yes)
			(effects
				(font
					(size 1.016 1.016)
					(thickness 0.1524)
				)
			)
		)
		(duplicate_pad_numbers_are_jumpers no)
		(fp_line
			(start -0.508 -0.9398)
			(end -0.508 0.9398)
			(stroke
				(width 0.1524)
				(type default)
			)
			(layer "F.SilkS")
		)
		(fp_line
			(start 0.508 -0.9398)
			(end -0.508 -0.9398)
			(stroke
				(width 0.1524)
				(type default)
			)
			(layer "F.SilkS")
		)
		(fp_rect
			(start -0.508 0.9398)
			(end 0.508 -0.9398)
			(stroke
				(width 0)
				(type default)
			)
			(fill no)
			(layer "F.CrtYd")
		)
		(fp_rect
			(start -0.508 0.9398)
			(end 0.508 -0.9398)
			(stroke
				(width 0)
				(type default)
			)
			(fill no)
			(layer "F.Fab")
		)
		(pad "1" smd custom
			(at 0 -0.4445 270)
			(size 0.1397 0.1397)
			(layers "F.Cu" "F.Mask" "F.Paste")
			(net "P3V3")
			(options
				(clearance outline)
				(anchor circle)
			)
			(primitives
				(gr_poly
					(pts
						(arc
							(start -0.1778 -0.2794)
							(mid -0.249642 -0.249642)
							(end -0.2794 -0.1778)
						)
						(arc
							(start -0.2794 0.1778)
							(mid -0.249642 0.249642)
							(end -0.1778 0.2794)
						)
						(arc
							(start 0.1778 0.2794)
							(mid 0.249642 0.249642)
							(end 0.2794 0.1778)
						)
						(arc
							(start 0.2794 -0.1778)
							(mid 0.249642 -0.249642)
							(end 0.1778 -0.2794)
						)
					)
					(width 0)
					(fill yes)
				)
			)
		)
		(pad "2" smd custom
			(at 0 0.4445 270)
			(size 0.1397 0.1397)
			(layers "F.Cu" "F.Mask" "F.Paste")
			(net "DRV_ATTN_0")
			(options
				(clearance outline)
				(anchor circle)
			)
			(primitives
				(gr_poly
					(pts
						(arc
							(start -0.1778 -0.2794)
							(mid -0.249642 -0.249642)
							(end -0.2794 -0.1778)
						)
						(arc
							(start -0.2794 0.1778)
							(mid -0.249642 0.249642)
							(end -0.1778 0.2794)
						)
						(arc
							(start 0.1778 0.2794)
							(mid 0.249642 0.249642)
							(end 0.2794 0.1778)
						)
						(arc
							(start 0.2794 -0.1778)
							(mid 0.249642 -0.249642)
							(end 0.1778 -0.2794)
						)
					)
					(width 0)
					(fill yes)
				)
			)
		)
	)
	(footprint ""
		(layer "F.Cu")
		(at 32.131 -494.157 180)
		(property "Reference" "SR1102"
			(at 0 0 180)
			(layer "F.SilkS")
			(hide yes)
			(effects
				(font
					(size 1.27 1.27)
				)
			)
		)
		(property "Value" "4K7R2F-GP"
			(at 0.064008 -3.993896 180)
			(unlocked yes)
			(layer "F.Fab")
			(hide yes)
			(effects
				(font
					(size 1.016 1.016)
					(thickness 0.1524)
				)
			)
		)
		(property "Device Type" "R402H16"
			(at 0.064008 -5.517896 180)
			(unlocked yes)
			(layer "F.Fab")
			(hide yes)
			(effects
				(font
					(size 1.016 1.016)
					(thickness 0.1524)
				)
			)
		)
		(duplicate_pad_numbers_are_jumpers no)
		(fp_line
			(start 0.508 -0.9398)
			(end -0.508 -0.9398)
			(stroke
				(width 0.1524)
				(type default)
			)
			(layer "F.SilkS")
		)
		(fp_line
			(start -0.508 -0.9398)
			(end -0.508 0.9398)
			(stroke
				(width 0.1524)
				(type default)
			)
			(layer "F.SilkS")
		)
		(fp_rect
			(start -0.508 0.9398)
			(end 0.508 -0.9398)
			(stroke
				(width 0)
				(type default)
			)
			(fill no)
			(layer "F.CrtYd")
		)
		(fp_rect
			(start -0.508 0.9398)
			(end 0.508 -0.9398)
			(stroke
				(width 0)
				(type default)
			)
			(fill no)
			(layer "F.Fab")
		)
		(pad "1" smd custom
			(at 0 -0.4445 180)
			(size 0.1397 0.1397)
			(layers "F.Cu" "F.Mask" "F.Paste")
			(net "DUALPORTEN#5")
			(options
				(clearance outline)
				(anchor circle)
			)
			(primitives
				(gr_poly
					(pts
						(arc
							(start -0.1778 -0.2794)
							(mid -0.249642 -0.249642)
							(end -0.2794 -0.1778)
						)
						(arc
							(start -0.2794 0.1778)
							(mid -0.249642 0.249642)
							(end -0.1778 0.2794)
						)
						(arc
							(start 0.1778 0.2794)
							(mid 0.249642 0.249642)
							(end 0.2794 0.1778)
						)
						(arc
							(start 0.2794 -0.1778)
							(mid 0.249642 -0.249642)
							(end 0.1778 -0.2794)
						)
					)
					(width 0)
					(fill yes)
				)
			)
		)
		(pad "2" smd custom
			(at 0 0.4445 180)
			(size 0.1397 0.1397)
			(layers "F.Cu" "F.Mask" "F.Paste")
			(net "GND")
			(options
				(clearance outline)
				(anchor circle)
			)
			(primitives
				(gr_poly
					(pts
						(arc
							(start -0.1778 -0.2794)
							(mid -0.249642 -0.249642)
							(end -0.2794 -0.1778)
						)
						(arc
							(start -0.2794 0.1778)
							(mid -0.249642 0.249642)
							(end -0.1778 0.2794)
						)
						(arc
							(start 0.1778 0.2794)
							(mid 0.249642 0.249642)
							(end 0.2794 0.1778)
						)
						(arc
							(start 0.2794 -0.1778)
							(mid 0.249642 -0.249642)
							(end 0.1778 -0.2794)
						)
					)
					(width 0)
					(fill yes)
				)
			)
		)
	)
	(footprint ""
		(layer "F.Cu")
		(at 222.0214 -291.973)
		(property "Reference" "PC1193"
			(at 0 0 0)
			(layer "F.SilkS")
			(hide yes)
			(effects
				(font
					(size 1.27 1.27)
				)
			)
		)
		(property "Value" "SCD01U50V2KX-1GP"
			(at 1.1811 -2.7051 0)
			(unlocked yes)
			(layer "F.Fab")
			(hide yes)
			(effects
				(font
					(size 1.016 1.016)
					(thickness 0.1524)
				)
			)
		)
		(property "Device Type" "C402H22"
			(at 1.1811 -4.2291 0)
			(unlocked yes)
			(layer "F.Fab")
			(hide yes)
			(effects
				(font
					(size 1.016 1.016)
					(thickness 0.1524)
				)
			)
		)
		(duplicate_pad_numbers_are_jumpers no)
		(fp_rect
			(start -0.4318 0.9525)
			(end 0.4318 -0.9525)
			(stroke
				(width 0)
				(type default)
			)
			(fill no)
			(layer "F.CrtYd")
		)
		(fp_rect
			(start -0.4318 0.9525)
			(end 0.4318 -0.9525)
			(stroke
				(width 0)
				(type default)
			)
			(fill no)
			(layer "F.Fab")
		)
		(pad "1" smd custom
			(at 0 -0.4445)
			(size 0.1524 0.1524)
			(layers "F.Cu" "F.Mask" "F.Paste")
			(net "P12V_SSD2")
			(options
				(clearance outline)
				(anchor circle)
			)
			(primitives
				(gr_poly
					(pts
						(arc
							(start 0.3048 -0.2032)
							(mid 0.275042 -0.275042)
							(end 0.2032 -0.3048)
						)
						(arc
							(start -0.2032 -0.3048)
							(mid -0.275042 -0.275042)
							(end -0.3048 -0.2032)
						)
						(arc
							(start -0.3048 0.2032)
							(mid -0.275042 0.275042)
							(end -0.2032 0.3048)
						)
						(arc
							(start 0.2032 0.3048)
							(mid 0.275042 0.275042)
							(end 0.3048 0.2032)
						)
					)
					(width 0)
					(fill yes)
				)
			)
		)
		(pad "2" smd custom
			(at 0 0.4445)
			(size 0.1524 0.1524)
			(layers "F.Cu" "F.Mask" "F.Paste")
			(net "GND")
			(options
				(clearance outline)
				(anchor circle)
			)
			(primitives
				(gr_poly
					(pts
						(arc
							(start 0.3048 -0.2032)
							(mid 0.275042 -0.275042)
							(end 0.2032 -0.3048)
						)
						(arc
							(start -0.2032 -0.3048)
							(mid -0.275042 -0.275042)
							(end -0.3048 -0.2032)
						)
						(arc
							(start -0.3048 0.2032)
							(mid -0.275042 0.275042)
							(end -0.2032 0.3048)
						)
						(arc
							(start 0.2032 0.3048)
							(mid 0.275042 0.275042)
							(end 0.3048 0.2032)
						)
					)
					(width 0)
					(fill yes)
				)
			)
		)
	)
	(footprint ""
		(layer "F.Cu")
		(at 98.806 -225.806 90)
		(property "Reference" "R9465"
			(at 0 0 90)
			(layer "F.SilkS")
			(hide yes)
			(effects
				(font
					(size 1.27 1.27)
				)
			)
		)
		(property "Value" "4K7R2J-2-GP"
			(at 0.064008 -3.993896 90)
			(unlocked yes)
			(layer "F.Fab")
			(hide yes)
			(effects
				(font
					(size 1.016 1.016)
					(thickness 0.1524)
				)
			)
		)
		(property "Device Type" "R402H16"
			(at 0.064008 -5.517896 90)
			(unlocked yes)
			(layer "F.Fab")
			(hide yes)
			(effects
				(font
					(size 1.016 1.016)
					(thickness 0.1524)
				)
			)
		)
		(duplicate_pad_numbers_are_jumpers no)
		(fp_line
			(start 0.508 -0.9398)
			(end -0.508 -0.9398)
			(stroke
				(width 0.1524)
				(type default)
			)
			(layer "F.SilkS")
		)
		(fp_line
			(start -0.508 -0.9398)
			(end -0.508 0.9398)
			(stroke
				(width 0.1524)
				(type default)
			)
			(layer "F.SilkS")
		)
		(fp_rect
			(start -0.508 0.9398)
			(end 0.508 -0.9398)
			(stroke
				(width 0)
				(type default)
			)
			(fill no)
			(layer "F.CrtYd")
		)
		(fp_rect
			(start -0.508 0.9398)
			(end 0.508 -0.9398)
			(stroke
				(width 0)
				(type default)
			)
			(fill no)
			(layer "F.Fab")
		)
		(pad "1" smd custom
			(at 0 -0.4445 90)
			(size 0.1397 0.1397)
			(layers "F.Cu" "F.Mask" "F.Paste")
			(net "P3V3")
			(options
				(clearance outline)
				(anchor circle)
			)
			(primitives
				(gr_poly
					(pts
						(arc
							(start -0.1778 -0.2794)
							(mid -0.249642 -0.249642)
							(end -0.2794 -0.1778)
						)
						(arc
							(start -0.2794 0.1778)
							(mid -0.249642 0.249642)
							(end -0.1778 0.2794)
						)
						(arc
							(start 0.1778 0.2794)
							(mid 0.249642 0.249642)
							(end 0.2794 0.1778)
						)
						(arc
							(start 0.2794 -0.1778)
							(mid 0.249642 -0.249642)
							(end 0.1778 -0.2794)
						)
					)
					(width 0)
					(fill yes)
				)
			)
		)
		(pad "2" smd custom
			(at 0 0.4445 90)
			(size 0.1397 0.1397)
			(layers "F.Cu" "F.Mask" "F.Paste")
			(net "SSD_PRSNT_NET7")
			(options
				(clearance outline)
				(anchor circle)
			)
			(primitives
				(gr_poly
					(pts
						(arc
							(start -0.1778 -0.2794)
							(mid -0.249642 -0.249642)
							(end -0.2794 -0.1778)
						)
						(arc
							(start -0.2794 0.1778)
							(mid -0.249642 0.249642)
							(end -0.1778 0.2794)
						)
						(arc
							(start 0.1778 0.2794)
							(mid 0.249642 0.249642)
							(end 0.2794 0.1778)
						)
						(arc
							(start 0.2794 -0.1778)
							(mid 0.249642 -0.249642)
							(end 0.1778 -0.2794)
						)
					)
					(width 0)
					(fill yes)
				)
			)
		)
	)
	(footprint ""
		(layer "F.Cu")
		(at 37.7698 -315.8744)
		(property "Reference" "R577"
			(at 0 0 0)
			(layer "F.SilkS")
			(hide yes)
			(effects
				(font
					(size 1.27 1.27)
				)
			)
		)
		(property "Value" "300KR2F-GP"
			(at 0.064008 -3.993896 0)
			(unlocked yes)
			(layer "F.Fab")
			(hide yes)
			(effects
				(font
					(size 1.016 1.016)
					(thickness 0.1524)
				)
			)
		)
		(property "Device Type" "R402H16"
			(at 0.064008 -5.517896 0)
			(unlocked yes)
			(layer "F.Fab")
			(hide yes)
			(effects
				(font
					(size 1.016 1.016)
					(thickness 0.1524)
				)
			)
		)
		(duplicate_pad_numbers_are_jumpers no)
		(fp_line
			(start -0.508 -0.9398)
			(end -0.508 0.9398)
			(stroke
				(width 0.1524)
				(type default)
			)
			(layer "F.SilkS")
		)
		(fp_line
			(start 0.508 -0.9398)
			(end -0.508 -0.9398)
			(stroke
				(width 0.1524)
				(type default)
			)
			(layer "F.SilkS")
		)
		(fp_rect
			(start -0.508 0.9398)
			(end 0.508 -0.9398)
			(stroke
				(width 0)
				(type default)
			)
			(fill no)
			(layer "F.CrtYd")
		)
		(fp_rect
			(start -0.508 0.9398)
			(end 0.508 -0.9398)
			(stroke
				(width 0)
				(type default)
			)
			(fill no)
			(layer "F.Fab")
		)
		(pad "1" smd custom
			(at 0 -0.4445)
			(size 0.1397 0.1397)
			(layers "F.Cu" "F.Mask" "F.Paste")
			(net "SW_SSD11_N")
			(options
				(clearance outline)
				(anchor circle)
			)
			(primitives
				(gr_poly
					(pts
						(arc
							(start -0.1778 -0.2794)
							(mid -0.249642 -0.249642)
							(end -0.2794 -0.1778)
						)
						(arc
							(start -0.2794 0.1778)
							(mid -0.249642 0.249642)
							(end -0.1778 0.2794)
						)
						(arc
							(start 0.1778 0.2794)
							(mid 0.249642 0.249642)
							(end 0.2794 0.1778)
						)
						(arc
							(start 0.2794 -0.1778)
							(mid 0.249642 -0.249642)
							(end 0.1778 -0.2794)
						)
					)
					(width 0)
					(fill yes)
				)
			)
		)
		(pad "2" smd custom
			(at 0 0.4445)
			(size 0.1397 0.1397)
			(layers "F.Cu" "F.Mask" "F.Paste")
			(net "P12V")
			(options
				(clearance outline)
				(anchor circle)
			)
			(primitives
				(gr_poly
					(pts
						(arc
							(start -0.1778 -0.2794)
							(mid -0.249642 -0.249642)
							(end -0.2794 -0.1778)
						)
						(arc
							(start -0.2794 0.1778)
							(mid -0.249642 0.249642)
							(end -0.1778 0.2794)
						)
						(arc
							(start 0.1778 0.2794)
							(mid 0.249642 0.249642)
							(end 0.2794 0.1778)
						)
						(arc
							(start 0.2794 -0.1778)
							(mid 0.249642 -0.249642)
							(end 0.1778 -0.2794)
						)
					)
					(width 0)
					(fill yes)
				)
			)
		)
	)
	(footprint ""
		(layer "F.Cu")
		(at 41.184576 -145.67789 180)
		(property "Reference" "R9943"
			(at 0 0 180)
			(layer "F.SilkS")
			(hide yes)
			(effects
				(font
					(size 1.27 1.27)
				)
			)
		)
		(property "Value" "4K7R2J-2-GP"
			(at 0.064008 -3.993896 180)
			(unlocked yes)
			(layer "F.Fab")
			(hide yes)
			(effects
				(font
					(size 1.016 1.016)
					(thickness 0.1524)
				)
			)
		)
		(property "Device Type" "R402H16"
			(at 0.064008 -5.517896 180)
			(unlocked yes)
			(layer "F.Fab")
			(hide yes)
			(effects
				(font
					(size 1.016 1.016)
					(thickness 0.1524)
				)
			)
		)
		(duplicate_pad_numbers_are_jumpers no)
		(fp_line
			(start 0.508 -0.9398)
			(end -0.508 -0.9398)
			(stroke
				(width 0.1524)
				(type default)
			)
			(layer "F.SilkS")
		)
		(fp_line
			(start -0.508 -0.9398)
			(end -0.508 0.9398)
			(stroke
				(width 0.1524)
				(type default)
			)
			(layer "F.SilkS")
		)
		(fp_rect
			(start -0.508 0.9398)
			(end 0.508 -0.9398)
			(stroke
				(width 0)
				(type default)
			)
			(fill no)
			(layer "F.CrtYd")
		)
		(fp_rect
			(start -0.508 0.9398)
			(end 0.508 -0.9398)
			(stroke
				(width 0)
				(type default)
			)
			(fill no)
			(layer "F.Fab")
		)
		(pad "1" smd custom
			(at 0 -0.4445 180)
			(size 0.1397 0.1397)
			(layers "F.Cu" "F.Mask" "F.Paste")
			(net "P3V3")
			(options
				(clearance outline)
				(anchor circle)
			)
			(primitives
				(gr_poly
					(pts
						(arc
							(start -0.1778 -0.2794)
							(mid -0.249642 -0.249642)
							(end -0.2794 -0.1778)
						)
						(arc
							(start -0.2794 0.1778)
							(mid -0.249642 0.249642)
							(end -0.1778 0.2794)
						)
						(arc
							(start 0.1778 0.2794)
							(mid 0.249642 0.249642)
							(end 0.2794 0.1778)
						)
						(arc
							(start 0.2794 -0.1778)
							(mid 0.249642 -0.249642)
							(end 0.1778 -0.2794)
						)
					)
					(width 0)
					(fill yes)
				)
			)
		)
		(pad "2" smd custom
			(at 0 0.4445 180)
			(size 0.1397 0.1397)
			(layers "F.Cu" "F.Mask" "F.Paste")
			(net "ATTN_LED_DR8_MOS_N")
			(options
				(clearance outline)
				(anchor circle)
			)
			(primitives
				(gr_poly
					(pts
						(arc
							(start -0.1778 -0.2794)
							(mid -0.249642 -0.249642)
							(end -0.2794 -0.1778)
						)
						(arc
							(start -0.2794 0.1778)
							(mid -0.249642 0.249642)
							(end -0.1778 0.2794)
						)
						(arc
							(start 0.1778 0.2794)
							(mid 0.249642 0.249642)
							(end 0.2794 0.1778)
						)
						(arc
							(start 0.2794 -0.1778)
							(mid 0.249642 -0.249642)
							(end 0.1778 -0.2794)
						)
					)
					(width 0)
					(fill yes)
				)
			)
		)
	)
	(footprint ""
		(layer "F.Cu")
		(at 43.020996 -351.872042 -90)
		(property "Reference" "R9939"
			(at 0 0 270)
			(layer "F.SilkS")
			(hide yes)
			(effects
				(font
					(size 1.27 1.27)
				)
			)
		)
		(property "Value" "4K7R2J-2-GP"
			(at 0.064008 -3.993896 270)
			(unlocked yes)
			(layer "F.Fab")
			(hide yes)
			(effects
				(font
					(size 1.016 1.016)
					(thickness 0.1524)
				)
			)
		)
		(property "Device Type" "R402H16"
			(at 0.064008 -5.517896 270)
			(unlocked yes)
			(layer "F.Fab")
			(hide yes)
			(effects
				(font
					(size 1.016 1.016)
					(thickness 0.1524)
				)
			)
		)
		(duplicate_pad_numbers_are_jumpers no)
		(fp_line
			(start -0.508 -0.9398)
			(end -0.508 0.9398)
			(stroke
				(width 0.1524)
				(type default)
			)
			(layer "F.SilkS")
		)
		(fp_line
			(start 0.508 -0.9398)
			(end -0.508 -0.9398)
			(stroke
				(width 0.1524)
				(type default)
			)
			(layer "F.SilkS")
		)
		(fp_rect
			(start -0.508 0.9398)
			(end 0.508 -0.9398)
			(stroke
				(width 0)
				(type default)
			)
			(fill no)
			(layer "F.CrtYd")
		)
		(fp_rect
			(start -0.508 0.9398)
			(end 0.508 -0.9398)
			(stroke
				(width 0)
				(type default)
			)
			(fill no)
			(layer "F.Fab")
		)
		(pad "1" smd custom
			(at 0 -0.4445 270)
			(size 0.1397 0.1397)
			(layers "F.Cu" "F.Mask" "F.Paste")
			(net "P3V3")
			(options
				(clearance outline)
				(anchor circle)
			)
			(primitives
				(gr_poly
					(pts
						(arc
							(start -0.1778 -0.2794)
							(mid -0.249642 -0.249642)
							(end -0.2794 -0.1778)
						)
						(arc
							(start -0.2794 0.1778)
							(mid -0.249642 0.249642)
							(end -0.1778 0.2794)
						)
						(arc
							(start 0.1778 0.2794)
							(mid 0.249642 0.249642)
							(end 0.2794 0.1778)
						)
						(arc
							(start 0.2794 -0.1778)
							(mid 0.249642 -0.249642)
							(end 0.1778 -0.2794)
						)
					)
					(width 0)
					(fill yes)
				)
			)
		)
		(pad "2" smd custom
			(at 0 0.4445 270)
			(size 0.1397 0.1397)
			(layers "F.Cu" "F.Mask" "F.Paste")
			(net "ATTN_LED_DR6_MOS_N")
			(options
				(clearance outline)
				(anchor circle)
			)
			(primitives
				(gr_poly
					(pts
						(arc
							(start -0.1778 -0.2794)
							(mid -0.249642 -0.249642)
							(end -0.2794 -0.1778)
						)
						(arc
							(start -0.2794 0.1778)
							(mid -0.249642 0.249642)
							(end -0.1778 0.2794)
						)
						(arc
							(start 0.1778 0.2794)
							(mid 0.249642 0.249642)
							(end 0.2794 0.1778)
						)
						(arc
							(start 0.2794 -0.1778)
							(mid 0.249642 -0.249642)
							(end 0.1778 -0.2794)
						)
					)
					(width 0)
					(fill yes)
				)
			)
		)
	)
	(footprint ""
		(layer "F.Cu")
		(at 36.2966 -198.2724 -90)
		(property "Reference" "R9832"
			(at 0 0 270)
			(layer "F.SilkS")
			(hide yes)
			(effects
				(font
					(size 1.27 1.27)
				)
			)
		)
		(property "Value" "2K2R5F-GP"
			(at 0 -8.9535 270)
			(unlocked yes)
			(layer "F.Fab")
			(hide yes)
			(effects
				(font
					(size 1.27 1.016)
					(thickness 0.1524)
				)
			)
		)
		(property "Device Type" "R805H24"
			(at 0 -10.6299 270)
			(unlocked yes)
			(layer "F.Fab")
			(hide yes)
			(effects
				(font
					(size 1.27 1.016)
					(thickness 0.1524)
				)
			)
		)
		(duplicate_pad_numbers_are_jumpers no)
		(fp_line
			(start -0.889 1.7018)
			(end 0.889 1.7018)
			(stroke
				(width 0.1524)
				(type default)
			)
			(layer "F.SilkS")
		)
		(fp_line
			(start 0.889 1.7018)
			(end 0.889 -0.508)
			(stroke
				(width 0.1524)
				(type default)
			)
			(layer "F.SilkS")
		)
		(fp_line
			(start -0.889 0.0762)
			(end -0.889 1.7018)
			(stroke
				(width 0.1524)
				(type default)
			)
			(layer "F.SilkS")
		)
		(fp_line
			(start -0.889 -1.7018)
			(end -0.889 0.2794)
			(stroke
				(width 0.1524)
				(type default)
			)
			(layer "F.SilkS")
		)
		(fp_line
			(start 0.889 -1.7018)
			(end 0.889 -0.381)
			(stroke
				(width 0.1524)
				(type default)
			)
			(layer "F.SilkS")
		)
		(fp_line
			(start 0.889 -1.7018)
			(end -0.889 -1.7018)
			(stroke
				(width 0.1524)
				(type default)
			)
			(layer "F.SilkS")
		)
		(fp_poly
			(pts
				(xy 0.9652 -1.778) (xy 0.9652 1.778) (xy -0.9652 1.778) (xy -0.9652 -1.778)
			)
			(stroke
				(width 0)
				(type default)
			)
			(fill no)
			(layer "F.CrtYd")
		)
		(fp_rect
			(start -0.9652 1.778)
			(end 0.9652 -1.778)
			(stroke
				(width 0)
				(type default)
			)
			(fill no)
			(layer "F.Fab")
		)
		(pad "1" smd rect
			(at 0 -0.9652 270)
			(size 1.397 1.143)
			(layers "F.Cu" "F.Mask" "F.Paste")
			(net "P12V_SSD8")
		)
		(pad "2" smd rect
			(at 0 0.9652 270)
			(size 1.397 1.143)
			(layers "F.Cu" "F.Mask" "F.Paste")
			(net "P12V_MOST8_GATE_D")
		)
	)
	(footprint ""
		(layer "F.Cu")
		(at 49.276 -41.275 -90)
		(property "Reference" "R9394"
			(at 0 0 270)
			(layer "F.SilkS")
			(hide yes)
			(effects
				(font
					(size 1.27 1.27)
				)
			)
		)
		(property "Value" "100R2J-2-GP"
			(at 0.064008 -3.993896 270)
			(unlocked yes)
			(layer "F.Fab")
			(hide yes)
			(effects
				(font
					(size 1.016 1.016)
					(thickness 0.1524)
				)
			)
		)
		(property "Device Type" "R402H14"
			(at 0.064008 -5.517896 270)
			(unlocked yes)
			(layer "F.Fab")
			(hide yes)
			(effects
				(font
					(size 1.016 1.016)
					(thickness 0.1524)
				)
			)
		)
		(duplicate_pad_numbers_are_jumpers no)
		(fp_line
			(start -0.508 -0.9398)
			(end -0.508 0.9398)
			(stroke
				(width 0.1524)
				(type default)
			)
			(layer "F.SilkS")
		)
		(fp_line
			(start 0.508 -0.9398)
			(end -0.508 -0.9398)
			(stroke
				(width 0.1524)
				(type default)
			)
			(layer "F.SilkS")
		)
		(fp_rect
			(start -0.508 0.9398)
			(end 0.508 -0.9398)
			(stroke
				(width 0)
				(type default)
			)
			(fill no)
			(layer "F.CrtYd")
		)
		(fp_rect
			(start -0.508 0.9398)
			(end 0.508 -0.9398)
			(stroke
				(width 0)
				(type default)
			)
			(fill no)
			(layer "F.Fab")
		)
		(pad "1" smd custom
			(at 0 -0.4445 270)
			(size 0.1397 0.1397)
			(layers "F.Cu" "F.Mask" "F.Paste")
			(net "P3V3")
			(options
				(clearance outline)
				(anchor circle)
			)
			(primitives
				(gr_poly
					(pts
						(arc
							(start -0.1778 -0.2794)
							(mid -0.249642 -0.249642)
							(end -0.2794 -0.1778)
						)
						(arc
							(start -0.2794 0.1778)
							(mid -0.249642 0.249642)
							(end -0.1778 0.2794)
						)
						(arc
							(start 0.1778 0.2794)
							(mid 0.249642 0.249642)
							(end 0.2794 0.1778)
						)
						(arc
							(start 0.2794 -0.1778)
							(mid 0.249642 -0.249642)
							(end 0.1778 -0.2794)
						)
					)
					(width 0)
					(fill yes)
				)
			)
		)
		(pad "2" smd custom
			(at 0 0.4445 270)
			(size 0.1397 0.1397)
			(layers "F.Cu" "F.Mask" "F.Paste")
			(net "DRV_ACT_9")
			(options
				(clearance outline)
				(anchor circle)
			)
			(primitives
				(gr_poly
					(pts
						(arc
							(start -0.1778 -0.2794)
							(mid -0.249642 -0.249642)
							(end -0.2794 -0.1778)
						)
						(arc
							(start -0.2794 0.1778)
							(mid -0.249642 0.249642)
							(end -0.1778 0.2794)
						)
						(arc
							(start 0.1778 0.2794)
							(mid 0.249642 0.249642)
							(end 0.2794 0.1778)
						)
						(arc
							(start 0.2794 -0.1778)
							(mid 0.249642 -0.249642)
							(end 0.1778 -0.2794)
						)
					)
					(width 0)
					(fill yes)
				)
			)
		)
	)
	(footprint ""
		(layer "F.Cu")
		(at 19.6596 -309.5498 180)
		(property "Reference" "R9260"
			(at 0 0 180)
			(layer "F.SilkS")
			(hide yes)
			(effects
				(font
					(size 1.27 1.27)
				)
			)
		)
		(property "Value" "2R2010F-GP"
			(at 0.0762 -4.5466 180)
			(unlocked yes)
			(layer "F.Fab")
			(hide yes)
			(effects
				(font
					(size 1.016 1.016)
					(thickness 0.1524)
				)
			)
		)
		(property "Device Type" "R2010H26"
			(at 0.0762 -6.1468 180)
			(unlocked yes)
			(layer "F.Fab")
			(hide yes)
			(effects
				(font
					(size 1.016 1.016)
					(thickness 0.1524)
				)
			)
		)
		(duplicate_pad_numbers_are_jumpers no)
		(fp_line
			(start 3.302 1.651)
			(end 3.302 -1.651)
			(stroke
				(width 0.1524)
				(type default)
			)
			(layer "F.SilkS")
		)
		(fp_line
			(start 3.302 -1.651)
			(end -3.302 -1.651)
			(stroke
				(width 0.1524)
				(type default)
			)
			(layer "F.SilkS")
		)
		(fp_line
			(start -3.302 1.651)
			(end 3.302 1.651)
			(stroke
				(width 0.1524)
				(type default)
			)
			(layer "F.SilkS")
		)
		(fp_line
			(start -3.302 -1.651)
			(end -3.302 1.651)
			(stroke
				(width 0.1524)
				(type default)
			)
			(layer "F.SilkS")
		)
		(fp_rect
			(start -3.3782 1.7272)
			(end 3.3782 -1.7272)
			(stroke
				(width 0)
				(type default)
			)
			(fill no)
			(layer "F.CrtYd")
		)
		(fp_poly
			(pts
				(xy 3.3782 -1.7272) (xy -3.3782 -1.7272) (xy -3.3782 1.7272) (xy 3.3782 1.7272)
			)
			(stroke
				(width 0)
				(type default)
			)
			(fill no)
			(layer "F.Fab")
		)
		(pad "1" smd rect
			(at -2.3495 0 180)
			(size 1.143 2.794)
			(layers "F.Cu" "F.Mask" "F.Paste")
			(net "P12V_SSD11")
		)
		(pad "2" smd rect
			(at 2.3495 0 180)
			(size 1.143 2.794)
			(layers "F.Cu" "F.Mask" "F.Paste")
			(net "12V_PRECH_SSD11")
		)
	)
	(footprint ""
		(layer "F.Cu")
		(at 100.4824 -101.5746 180)
		(property "Reference" "C9432"
			(at 0 0 180)
			(layer "F.SilkS")
			(hide yes)
			(effects
				(font
					(size 1.27 1.27)
				)
			)
		)
		(property "Value" "SCD1U16V2KX-3GP"
			(at 1.1811 -2.7051 180)
			(unlocked yes)
			(layer "F.Fab")
			(hide yes)
			(effects
				(font
					(size 1.016 1.016)
					(thickness 0.1524)
				)
			)
		)
		(property "Device Type" "C402H22"
			(at 1.1811 -4.2291 180)
			(unlocked yes)
			(layer "F.Fab")
			(hide yes)
			(effects
				(font
					(size 1.016 1.016)
					(thickness 0.1524)
				)
			)
		)
		(duplicate_pad_numbers_are_jumpers no)
		(fp_rect
			(start -0.4318 0.9525)
			(end 0.4318 -0.9525)
			(stroke
				(width 0)
				(type default)
			)
			(fill no)
			(layer "F.CrtYd")
		)
		(fp_rect
			(start -0.4318 0.9525)
			(end 0.4318 -0.9525)
			(stroke
				(width 0)
				(type default)
			)
			(fill no)
			(layer "F.Fab")
		)
		(pad "1" smd custom
			(at 0 -0.4445 180)
			(size 0.1524 0.1524)
			(layers "F.Cu" "F.Mask" "F.Paste")
			(net "VDD_DIFF_4")
			(options
				(clearance outline)
				(anchor circle)
			)
			(primitives
				(gr_poly
					(pts
						(arc
							(start 0.3048 -0.2032)
							(mid 0.275042 -0.275042)
							(end 0.2032 -0.3048)
						)
						(arc
							(start -0.2032 -0.3048)
							(mid -0.275042 -0.275042)
							(end -0.3048 -0.2032)
						)
						(arc
							(start -0.3048 0.2032)
							(mid -0.275042 0.275042)
							(end -0.2032 0.3048)
						)
						(arc
							(start 0.2032 0.3048)
							(mid 0.275042 0.275042)
							(end 0.3048 0.2032)
						)
					)
					(width 0)
					(fill yes)
				)
			)
		)
		(pad "2" smd custom
			(at 0 0.4445 180)
			(size 0.1524 0.1524)
			(layers "F.Cu" "F.Mask" "F.Paste")
			(net "GND")
			(options
				(clearance outline)
				(anchor circle)
			)
			(primitives
				(gr_poly
					(pts
						(arc
							(start 0.3048 -0.2032)
							(mid 0.275042 -0.275042)
							(end 0.2032 -0.3048)
						)
						(arc
							(start -0.2032 -0.3048)
							(mid -0.275042 -0.275042)
							(end -0.3048 -0.2032)
						)
						(arc
							(start -0.3048 0.2032)
							(mid -0.275042 0.275042)
							(end -0.2032 0.3048)
						)
						(arc
							(start 0.2032 0.3048)
							(mid 0.275042 0.275042)
							(end 0.3048 0.2032)
						)
					)
					(width 0)
					(fill yes)
				)
			)
		)
	)
	(footprint ""
		(layer "F.Cu")
		(at 45.632116 -37.453062 -90)
		(property "Reference" "R9843"
			(at 0 0 270)
			(layer "F.SilkS")
			(hide yes)
			(effects
				(font
					(size 1.27 1.27)
				)
			)
		)
		(property "Value" "0R2J-2-GP"
			(at 0.064008 -3.993896 270)
			(unlocked yes)
			(layer "F.Fab")
			(hide yes)
			(effects
				(font
					(size 1.016 1.016)
					(thickness 0.1524)
				)
			)
		)
		(property "Device Type" "R402H16"
			(at 0.064008 -5.517896 270)
			(unlocked yes)
			(layer "F.Fab")
			(hide yes)
			(effects
				(font
					(size 1.016 1.016)
					(thickness 0.1524)
				)
			)
		)
		(duplicate_pad_numbers_are_jumpers no)
		(fp_line
			(start -0.508 -0.9398)
			(end -0.508 0.9398)
			(stroke
				(width 0.1524)
				(type default)
			)
			(layer "F.SilkS")
		)
		(fp_line
			(start 0.508 -0.9398)
			(end -0.508 -0.9398)
			(stroke
				(width 0.1524)
				(type default)
			)
			(layer "F.SilkS")
		)
		(fp_rect
			(start -0.508 0.9398)
			(end 0.508 -0.9398)
			(stroke
				(width 0)
				(type default)
			)
			(fill no)
			(layer "F.CrtYd")
		)
		(fp_rect
			(start -0.508 0.9398)
			(end 0.508 -0.9398)
			(stroke
				(width 0)
				(type default)
			)
			(fill no)
			(layer "F.Fab")
		)
		(pad "1" smd custom
			(at 0 -0.4445 270)
			(size 0.1397 0.1397)
			(layers "F.Cu" "F.Mask" "F.Paste")
			(net "SSD_ACT_DR9_R")
			(options
				(clearance outline)
				(anchor circle)
			)
			(primitives
				(gr_poly
					(pts
						(arc
							(start -0.1778 -0.2794)
							(mid -0.249642 -0.249642)
							(end -0.2794 -0.1778)
						)
						(arc
							(start -0.2794 0.1778)
							(mid -0.249642 0.249642)
							(end -0.1778 0.2794)
						)
						(arc
							(start 0.1778 0.2794)
							(mid 0.249642 0.249642)
							(end 0.2794 0.1778)
						)
						(arc
							(start 0.2794 -0.1778)
							(mid 0.249642 -0.249642)
							(end 0.1778 -0.2794)
						)
					)
					(width 0)
					(fill yes)
				)
			)
		)
		(pad "2" smd custom
			(at 0 0.4445 270)
			(size 0.1397 0.1397)
			(layers "F.Cu" "F.Mask" "F.Paste")
			(net "SSD_ACT_DR9")
			(options
				(clearance outline)
				(anchor circle)
			)
			(primitives
				(gr_poly
					(pts
						(arc
							(start -0.1778 -0.2794)
							(mid -0.249642 -0.249642)
							(end -0.2794 -0.1778)
						)
						(arc
							(start -0.2794 0.1778)
							(mid -0.249642 0.249642)
							(end -0.1778 0.2794)
						)
						(arc
							(start 0.1778 0.2794)
							(mid 0.249642 0.249642)
							(end 0.2794 0.1778)
						)
						(arc
							(start 0.2794 -0.1778)
							(mid 0.249642 -0.249642)
							(end 0.1778 -0.2794)
						)
					)
					(width 0)
					(fill yes)
				)
			)
		)
	)
	(footprint ""
		(layer "F.Cu")
		(at 48.768 -34.29 90)
		(property "Reference" "R9841"
			(at 0 0 90)
			(layer "F.SilkS")
			(hide yes)
			(effects
				(font
					(size 1.27 1.27)
				)
			)
		)
		(property "Value" "0R2J-2-GP"
			(at 0.064008 -3.993896 90)
			(unlocked yes)
			(layer "F.Fab")
			(hide yes)
			(effects
				(font
					(size 1.016 1.016)
					(thickness 0.1524)
				)
			)
		)
		(property "Device Type" "R402H16"
			(at 0.064008 -5.517896 90)
			(unlocked yes)
			(layer "F.Fab")
			(hide yes)
			(effects
				(font
					(size 1.016 1.016)
					(thickness 0.1524)
				)
			)
		)
		(duplicate_pad_numbers_are_jumpers no)
		(fp_line
			(start 0.508 -0.9398)
			(end -0.508 -0.9398)
			(stroke
				(width 0.1524)
				(type default)
			)
			(layer "F.SilkS")
		)
		(fp_line
			(start -0.508 -0.9398)
			(end -0.508 0.9398)
			(stroke
				(width 0.1524)
				(type default)
			)
			(layer "F.SilkS")
		)
		(fp_rect
			(start -0.508 0.9398)
			(end 0.508 -0.9398)
			(stroke
				(width 0)
				(type default)
			)
			(fill no)
			(layer "F.CrtYd")
		)
		(fp_rect
			(start -0.508 0.9398)
			(end 0.508 -0.9398)
			(stroke
				(width 0)
				(type default)
			)
			(fill no)
			(layer "F.Fab")
		)
		(pad "1" smd custom
			(at 0 -0.4445 90)
			(size 0.1397 0.1397)
			(layers "F.Cu" "F.Mask" "F.Paste")
			(net "ATTN_LED_DR9_AND")
			(options
				(clearance outline)
				(anchor circle)
			)
			(primitives
				(gr_poly
					(pts
						(arc
							(start -0.1778 -0.2794)
							(mid -0.249642 -0.249642)
							(end -0.2794 -0.1778)
						)
						(arc
							(start -0.2794 0.1778)
							(mid -0.249642 0.249642)
							(end -0.1778 0.2794)
						)
						(arc
							(start 0.1778 0.2794)
							(mid 0.249642 0.249642)
							(end 0.2794 0.1778)
						)
						(arc
							(start 0.2794 -0.1778)
							(mid 0.249642 -0.249642)
							(end 0.1778 -0.2794)
						)
					)
					(width 0)
					(fill yes)
				)
			)
		)
		(pad "2" smd custom
			(at 0 0.4445 90)
			(size 0.1397 0.1397)
			(layers "F.Cu" "F.Mask" "F.Paste")
			(net "ATTN_LED_DR9_AND_R")
			(options
				(clearance outline)
				(anchor circle)
			)
			(primitives
				(gr_poly
					(pts
						(arc
							(start -0.1778 -0.2794)
							(mid -0.249642 -0.249642)
							(end -0.2794 -0.1778)
						)
						(arc
							(start -0.2794 0.1778)
							(mid -0.249642 0.249642)
							(end -0.1778 0.2794)
						)
						(arc
							(start 0.1778 0.2794)
							(mid 0.249642 0.249642)
							(end 0.2794 0.1778)
						)
						(arc
							(start 0.2794 -0.1778)
							(mid 0.249642 -0.249642)
							(end 0.1778 -0.2794)
						)
					)
					(width 0)
					(fill yes)
				)
			)
		)
	)
	(footprint ""
		(layer "F.Cu")
		(at 229.93096 -35.118802)
		(property "Reference" "C9522"
			(at 0 0 0)
			(layer "F.SilkS")
			(hide yes)
			(effects
				(font
					(size 1.27 1.27)
				)
			)
		)
		(property "Value" "SCD1U16V2KX-3GP"
			(at 1.1811 -2.7051 0)
			(unlocked yes)
			(layer "F.Fab")
			(hide yes)
			(effects
				(font
					(size 1.016 1.016)
					(thickness 0.1524)
				)
			)
		)
		(property "Device Type" "C402H22"
			(at 1.1811 -4.2291 0)
			(unlocked yes)
			(layer "F.Fab")
			(hide yes)
			(effects
				(font
					(size 1.016 1.016)
					(thickness 0.1524)
				)
			)
		)
		(duplicate_pad_numbers_are_jumpers no)
		(fp_rect
			(start -0.4318 0.9525)
			(end 0.4318 -0.9525)
			(stroke
				(width 0)
				(type default)
			)
			(fill no)
			(layer "F.CrtYd")
		)
		(fp_rect
			(start -0.4318 0.9525)
			(end 0.4318 -0.9525)
			(stroke
				(width 0)
				(type default)
			)
			(fill no)
			(layer "F.Fab")
		)
		(pad "1" smd custom
			(at 0 -0.4445)
			(size 0.1524 0.1524)
			(layers "F.Cu" "F.Mask" "F.Paste")
			(net "P3V3")
			(options
				(clearance outline)
				(anchor circle)
			)
			(primitives
				(gr_poly
					(pts
						(arc
							(start 0.3048 -0.2032)
							(mid 0.275042 -0.275042)
							(end 0.2032 -0.3048)
						)
						(arc
							(start -0.2032 -0.3048)
							(mid -0.275042 -0.275042)
							(end -0.3048 -0.2032)
						)
						(arc
							(start -0.3048 0.2032)
							(mid -0.275042 0.275042)
							(end -0.2032 0.3048)
						)
						(arc
							(start 0.2032 0.3048)
							(mid 0.275042 0.275042)
							(end 0.3048 0.2032)
						)
					)
					(width 0)
					(fill yes)
				)
			)
		)
		(pad "2" smd custom
			(at 0 0.4445)
			(size 0.1524 0.1524)
			(layers "F.Cu" "F.Mask" "F.Paste")
			(net "GND")
			(options
				(clearance outline)
				(anchor circle)
			)
			(primitives
				(gr_poly
					(pts
						(arc
							(start 0.3048 -0.2032)
							(mid 0.275042 -0.275042)
							(end 0.2032 -0.3048)
						)
						(arc
							(start -0.2032 -0.3048)
							(mid -0.275042 -0.275042)
							(end -0.3048 -0.2032)
						)
						(arc
							(start -0.3048 0.2032)
							(mid -0.275042 0.275042)
							(end -0.2032 0.3048)
						)
						(arc
							(start 0.2032 0.3048)
							(mid 0.275042 0.275042)
							(end 0.3048 0.2032)
						)
					)
					(width 0)
					(fill yes)
				)
			)
		)
	)
	(footprint ""
		(layer "F.Cu")
		(at 51.308 -144.526 90)
		(property "Reference" "SR1138"
			(at 0 0 90)
			(layer "F.SilkS")
			(hide yes)
			(effects
				(font
					(size 1.27 1.27)
				)
			)
		)
		(property "Value" "4K7R2J-2-GP"
			(at 0.064008 -3.993896 90)
			(unlocked yes)
			(layer "F.Fab")
			(hide yes)
			(effects
				(font
					(size 1.016 1.016)
					(thickness 0.1524)
				)
			)
		)
		(property "Device Type" "R402H16"
			(at 0.064008 -5.517896 90)
			(unlocked yes)
			(layer "F.Fab")
			(hide yes)
			(effects
				(font
					(size 1.016 1.016)
					(thickness 0.1524)
				)
			)
		)
		(duplicate_pad_numbers_are_jumpers no)
		(fp_line
			(start 0.508 -0.9398)
			(end -0.508 -0.9398)
			(stroke
				(width 0.1524)
				(type default)
			)
			(layer "F.SilkS")
		)
		(fp_line
			(start -0.508 -0.9398)
			(end -0.508 0.9398)
			(stroke
				(width 0.1524)
				(type default)
			)
			(layer "F.SilkS")
		)
		(fp_rect
			(start -0.508 0.9398)
			(end 0.508 -0.9398)
			(stroke
				(width 0)
				(type default)
			)
			(fill no)
			(layer "F.CrtYd")
		)
		(fp_rect
			(start -0.508 0.9398)
			(end 0.508 -0.9398)
			(stroke
				(width 0)
				(type default)
			)
			(fill no)
			(layer "F.Fab")
		)
		(pad "1" smd custom
			(at 0 -0.4445 90)
			(size 0.1397 0.1397)
			(layers "F.Cu" "F.Mask" "F.Paste")
			(net "P3V3")
			(options
				(clearance outline)
				(anchor circle)
			)
			(primitives
				(gr_poly
					(pts
						(arc
							(start -0.1778 -0.2794)
							(mid -0.249642 -0.249642)
							(end -0.2794 -0.1778)
						)
						(arc
							(start -0.2794 0.1778)
							(mid -0.249642 0.249642)
							(end -0.1778 0.2794)
						)
						(arc
							(start 0.1778 0.2794)
							(mid 0.249642 0.249642)
							(end 0.2794 0.1778)
						)
						(arc
							(start 0.2794 -0.1778)
							(mid 0.249642 -0.249642)
							(end 0.1778 -0.2794)
						)
					)
					(width 0)
					(fill yes)
				)
			)
		)
		(pad "2" smd custom
			(at 0 0.4445 90)
			(size 0.1397 0.1397)
			(layers "F.Cu" "F.Mask" "F.Paste")
			(net "SSD_ACT_DR8")
			(options
				(clearance outline)
				(anchor circle)
			)
			(primitives
				(gr_poly
					(pts
						(arc
							(start -0.1778 -0.2794)
							(mid -0.249642 -0.249642)
							(end -0.2794 -0.1778)
						)
						(arc
							(start -0.2794 0.1778)
							(mid -0.249642 0.249642)
							(end -0.1778 0.2794)
						)
						(arc
							(start 0.1778 0.2794)
							(mid 0.249642 0.249642)
							(end 0.2794 0.1778)
						)
						(arc
							(start 0.2794 -0.1778)
							(mid 0.249642 -0.249642)
							(end 0.1778 -0.2794)
						)
					)
					(width 0)
					(fill yes)
				)
			)
		)
	)
	(footprint ""
		(layer "F.Cu")
		(at 23.998174 -268.083284 -90)
		(property "Reference" "U209"
			(at 0 0 270)
			(layer "F.SilkS")
			(hide yes)
			(effects
				(font
					(size 1.27 1.27)
				)
			)
		)
		(property "Value" "SN74LVC1G08DCKR-GP"
			(at -2.3368 -8.6868 270)
			(unlocked yes)
			(layer "F.Fab")
			(hide yes)
			(effects
				(font
					(size 1.016 1.016)
					(thickness 0.1524)
				)
			)
		)
		(property "Device Type" "SC70-5H44"
			(at -2.3114 -10.414 270)
			(unlocked yes)
			(layer "F.Fab")
			(hide yes)
			(effects
				(font
					(size 1.016 1.016)
					(thickness 0.1524)
				)
			)
		)
		(duplicate_pad_numbers_are_jumpers no)
		(fp_line
			(start -1.27 1.7018)
			(end -1.27 -1.7018)
			(stroke
				(width 0.1524)
				(type default)
			)
			(layer "F.SilkS")
		)
		(fp_line
			(start 1.27 1.7018)
			(end -1.27 1.7018)
			(stroke
				(width 0.1524)
				(type default)
			)
			(layer "F.SilkS")
		)
		(fp_line
			(start -1.27 -1.7018)
			(end 1.27 -1.7018)
			(stroke
				(width 0.1524)
				(type default)
			)
			(layer "F.SilkS")
		)
		(fp_line
			(start 1.27 -1.7018)
			(end 1.27 1.7018)
			(stroke
				(width 0.1524)
				(type default)
			)
			(layer "F.SilkS")
		)
		(fp_line
			(start 0.6604 -1.8034)
			(end 1.3843 -1.8034)
			(stroke
				(width 0.3302)
				(type default)
			)
			(layer "F.SilkS")
		)
		(fp_line
			(start 1.3843 -1.8034)
			(end 1.3843 -1.1176)
			(stroke
				(width 0.3302)
				(type default)
			)
			(layer "F.SilkS")
		)
		(fp_rect
			(start -1.524 1.9558)
			(end 1.524 -1.9558)
			(stroke
				(width 0)
				(type default)
			)
			(fill no)
			(layer "F.CrtYd")
		)
		(fp_poly
			(pts
				(xy -1.524 -1.9558) (xy 1.524 -1.9558) (xy 1.524 1.9558) (xy -1.524 1.9558)
			)
			(stroke
				(width 0)
				(type default)
			)
			(fill no)
			(layer "F.Fab")
		)
		(pad "1" smd rect
			(at 0.65024 -0.8255 270)
			(size 0.4064 1.2192)
			(layers "F.Cu" "F.Mask" "F.Paste")
			(net "SSD12_CLK0_OE_MOS_N")
		)
		(pad "2" smd rect
			(at 0 -0.8255 270)
			(size 0.4064 1.2192)
			(layers "F.Cu" "F.Mask" "F.Paste")
			(net "ATTN_LED_DR12_N")
		)
		(pad "3" smd rect
			(at -0.65024 -0.8255 270)
			(size 0.4064 1.2192)
			(layers "F.Cu" "F.Mask" "F.Paste")
			(net "GND")
		)
		(pad "4" smd rect
			(at -0.65024 0.8255 270)
			(size 0.4064 1.2192)
			(layers "F.Cu" "F.Mask" "F.Paste")
			(net "ATTN_LED_DR12_AND")
		)
		(pad "5" smd rect
			(at 0.65024 0.8255 270)
			(size 0.4064 1.2192)
			(layers "F.Cu" "F.Mask" "F.Paste")
			(net "P3V3")
		)
	)
	(footprint ""
		(layer "F.Cu")
		(at 70.739 -149.606 90)
		(property "Reference" "SR972"
			(at 0 0 90)
			(layer "F.SilkS")
			(hide yes)
			(effects
				(font
					(size 1.27 1.27)
				)
			)
		)
		(property "Value" "2KR2F-3-GP"
			(at 0.064008 -3.993896 90)
			(unlocked yes)
			(layer "F.Fab")
			(hide yes)
			(effects
				(font
					(size 1.016 1.016)
					(thickness 0.1524)
				)
			)
		)
		(property "Device Type" "R402H16"
			(at 0.064008 -5.517896 90)
			(unlocked yes)
			(layer "F.Fab")
			(hide yes)
			(effects
				(font
					(size 1.016 1.016)
					(thickness 0.1524)
				)
			)
		)
		(duplicate_pad_numbers_are_jumpers no)
		(fp_line
			(start 0.508 -0.9398)
			(end -0.508 -0.9398)
			(stroke
				(width 0.1524)
				(type default)
			)
			(layer "F.SilkS")
		)
		(fp_line
			(start -0.508 -0.9398)
			(end -0.508 0.9398)
			(stroke
				(width 0.1524)
				(type default)
			)
			(layer "F.SilkS")
		)
		(fp_rect
			(start -0.508 0.9398)
			(end 0.508 -0.9398)
			(stroke
				(width 0)
				(type default)
			)
			(fill no)
			(layer "F.CrtYd")
		)
		(fp_rect
			(start -0.508 0.9398)
			(end 0.508 -0.9398)
			(stroke
				(width 0)
				(type default)
			)
			(fill no)
			(layer "F.Fab")
		)
		(pad "1" smd custom
			(at 0 -0.4445 90)
			(size 0.1397 0.1397)
			(layers "F.Cu" "F.Mask" "F.Paste")
			(net "P3V3")
			(options
				(clearance outline)
				(anchor circle)
			)
			(primitives
				(gr_poly
					(pts
						(arc
							(start -0.1778 -0.2794)
							(mid -0.249642 -0.249642)
							(end -0.2794 -0.1778)
						)
						(arc
							(start -0.2794 0.1778)
							(mid -0.249642 0.249642)
							(end -0.1778 0.2794)
						)
						(arc
							(start 0.1778 0.2794)
							(mid 0.249642 0.249642)
							(end 0.2794 0.1778)
						)
						(arc
							(start 0.2794 -0.1778)
							(mid 0.249642 -0.249642)
							(end 0.1778 -0.2794)
						)
					)
					(width 0)
					(fill yes)
				)
			)
		)
		(pad "2" smd custom
			(at 0 0.4445 90)
			(size 0.1397 0.1397)
			(layers "F.Cu" "F.Mask" "F.Paste")
			(net "SCL_DR8")
			(options
				(clearance outline)
				(anchor circle)
			)
			(primitives
				(gr_poly
					(pts
						(arc
							(start -0.1778 -0.2794)
							(mid -0.249642 -0.249642)
							(end -0.2794 -0.1778)
						)
						(arc
							(start -0.2794 0.1778)
							(mid -0.249642 0.249642)
							(end -0.1778 0.2794)
						)
						(arc
							(start 0.1778 0.2794)
							(mid 0.249642 0.249642)
							(end 0.2794 0.1778)
						)
						(arc
							(start 0.2794 -0.1778)
							(mid 0.249642 -0.249642)
							(end 0.1778 -0.2794)
						)
					)
					(width 0)
					(fill yes)
				)
			)
		)
	)
	(footprint ""
		(layer "F.Cu")
		(at 37.1856 -211.3534 90)
		(property "Reference" "R150"
			(at 0 0 90)
			(layer "F.SilkS")
			(hide yes)
			(effects
				(font
					(size 1.27 1.27)
				)
			)
		)
		(property "Value" "4K7R2J-2-GP"
			(at 0.064008 -3.993896 90)
			(unlocked yes)
			(layer "F.Fab")
			(hide yes)
			(effects
				(font
					(size 1.016 1.016)
					(thickness 0.1524)
				)
			)
		)
		(property "Device Type" "R402H16"
			(at 0.064008 -5.517896 90)
			(unlocked yes)
			(layer "F.Fab")
			(hide yes)
			(effects
				(font
					(size 1.016 1.016)
					(thickness 0.1524)
				)
			)
		)
		(duplicate_pad_numbers_are_jumpers no)
		(fp_line
			(start 0.508 -0.9398)
			(end -0.508 -0.9398)
			(stroke
				(width 0.1524)
				(type default)
			)
			(layer "F.SilkS")
		)
		(fp_line
			(start -0.508 -0.9398)
			(end -0.508 0.9398)
			(stroke
				(width 0.1524)
				(type default)
			)
			(layer "F.SilkS")
		)
		(fp_rect
			(start -0.508 0.9398)
			(end 0.508 -0.9398)
			(stroke
				(width 0)
				(type default)
			)
			(fill no)
			(layer "F.CrtYd")
		)
		(fp_rect
			(start -0.508 0.9398)
			(end 0.508 -0.9398)
			(stroke
				(width 0)
				(type default)
			)
			(fill no)
			(layer "F.Fab")
		)
		(pad "1" smd custom
			(at 0 -0.4445 90)
			(size 0.1397 0.1397)
			(layers "F.Cu" "F.Mask" "F.Paste")
			(net "P12V")
			(options
				(clearance outline)
				(anchor circle)
			)
			(primitives
				(gr_poly
					(pts
						(arc
							(start -0.1778 -0.2794)
							(mid -0.249642 -0.249642)
							(end -0.2794 -0.1778)
						)
						(arc
							(start -0.2794 0.1778)
							(mid -0.249642 0.249642)
							(end -0.1778 0.2794)
						)
						(arc
							(start 0.1778 0.2794)
							(mid 0.249642 0.249642)
							(end 0.2794 0.1778)
						)
						(arc
							(start 0.2794 -0.1778)
							(mid 0.249642 -0.249642)
							(end 0.1778 -0.2794)
						)
					)
					(width 0)
					(fill yes)
				)
			)
		)
		(pad "2" smd custom
			(at 0 0.4445 90)
			(size 0.1397 0.1397)
			(layers "F.Cu" "F.Mask" "F.Paste")
			(net "SW_SSD12_R")
			(options
				(clearance outline)
				(anchor circle)
			)
			(primitives
				(gr_poly
					(pts
						(arc
							(start -0.1778 -0.2794)
							(mid -0.249642 -0.249642)
							(end -0.2794 -0.1778)
						)
						(arc
							(start -0.2794 0.1778)
							(mid -0.249642 0.249642)
							(end -0.1778 0.2794)
						)
						(arc
							(start 0.1778 0.2794)
							(mid 0.249642 0.249642)
							(end 0.2794 0.1778)
						)
						(arc
							(start 0.2794 -0.1778)
							(mid 0.249642 -0.249642)
							(end 0.1778 -0.2794)
						)
					)
					(width 0)
					(fill yes)
				)
			)
		)
	)
	(footprint ""
		(layer "F.Cu")
		(at 82.931 -432.8922 90)
		(property "Reference" "R9349"
			(at 0 0 90)
			(layer "F.SilkS")
			(hide yes)
			(effects
				(font
					(size 1.27 1.27)
				)
			)
		)
		(property "Value" "2D2R2F-GP"
			(at 0.064008 -3.993896 90)
			(unlocked yes)
			(layer "F.Fab")
			(hide yes)
			(effects
				(font
					(size 1.016 1.016)
					(thickness 0.1524)
				)
			)
		)
		(property "Device Type" "R402H16"
			(at 0.064008 -5.517896 90)
			(unlocked yes)
			(layer "F.Fab")
			(hide yes)
			(effects
				(font
					(size 1.016 1.016)
					(thickness 0.1524)
				)
			)
		)
		(duplicate_pad_numbers_are_jumpers no)
		(fp_line
			(start 0.508 -0.9398)
			(end -0.508 -0.9398)
			(stroke
				(width 0.1524)
				(type default)
			)
			(layer "F.SilkS")
		)
		(fp_line
			(start -0.508 -0.9398)
			(end -0.508 0.9398)
			(stroke
				(width 0.1524)
				(type default)
			)
			(layer "F.SilkS")
		)
		(fp_rect
			(start -0.508 0.9398)
			(end 0.508 -0.9398)
			(stroke
				(width 0)
				(type default)
			)
			(fill no)
			(layer "F.CrtYd")
		)
		(fp_rect
			(start -0.508 0.9398)
			(end 0.508 -0.9398)
			(stroke
				(width 0)
				(type default)
			)
			(fill no)
			(layer "F.Fab")
		)
		(pad "1" smd custom
			(at 0 -0.4445 90)
			(size 0.1397 0.1397)
			(layers "F.Cu" "F.Mask" "F.Paste")
			(net "VDD_DIFF_1")
			(options
				(clearance outline)
				(anchor circle)
			)
			(primitives
				(gr_poly
					(pts
						(arc
							(start -0.1778 -0.2794)
							(mid -0.249642 -0.249642)
							(end -0.2794 -0.1778)
						)
						(arc
							(start -0.2794 0.1778)
							(mid -0.249642 0.249642)
							(end -0.1778 0.2794)
						)
						(arc
							(start 0.1778 0.2794)
							(mid 0.249642 0.249642)
							(end 0.2794 0.1778)
						)
						(arc
							(start 0.2794 -0.1778)
							(mid 0.249642 -0.249642)
							(end 0.1778 -0.2794)
						)
					)
					(width 0)
					(fill yes)
				)
			)
		)
		(pad "2" smd custom
			(at 0 0.4445 90)
			(size 0.1397 0.1397)
			(layers "F.Cu" "F.Mask" "F.Paste")
			(net "VDDR_1")
			(options
				(clearance outline)
				(anchor circle)
			)
			(primitives
				(gr_poly
					(pts
						(arc
							(start -0.1778 -0.2794)
							(mid -0.249642 -0.249642)
							(end -0.2794 -0.1778)
						)
						(arc
							(start -0.2794 0.1778)
							(mid -0.249642 0.249642)
							(end -0.1778 0.2794)
						)
						(arc
							(start 0.1778 0.2794)
							(mid 0.249642 0.249642)
							(end 0.2794 0.1778)
						)
						(arc
							(start 0.2794 -0.1778)
							(mid 0.249642 -0.249642)
							(end 0.1778 -0.2794)
						)
					)
					(width 0)
					(fill yes)
				)
			)
		)
	)
	(footprint ""
		(layer "F.Cu")
		(at 22.86 -197.231 180)
		(property "Reference" "R9619"
			(at 0 0 180)
			(layer "F.SilkS")
			(hide yes)
			(effects
				(font
					(size 1.27 1.27)
				)
			)
		)
		(property "Value" "4K7R2J-2-GP"
			(at 0.064008 -3.993896 180)
			(unlocked yes)
			(layer "F.Fab")
			(hide yes)
			(effects
				(font
					(size 1.016 1.016)
					(thickness 0.1524)
				)
			)
		)
		(property "Device Type" "R402H16"
			(at 0.064008 -5.517896 180)
			(unlocked yes)
			(layer "F.Fab")
			(hide yes)
			(effects
				(font
					(size 1.016 1.016)
					(thickness 0.1524)
				)
			)
		)
		(duplicate_pad_numbers_are_jumpers no)
		(fp_line
			(start 0.508 -0.9398)
			(end -0.508 -0.9398)
			(stroke
				(width 0.1524)
				(type default)
			)
			(layer "F.SilkS")
		)
		(fp_line
			(start -0.508 -0.9398)
			(end -0.508 0.9398)
			(stroke
				(width 0.1524)
				(type default)
			)
			(layer "F.SilkS")
		)
		(fp_rect
			(start -0.508 0.9398)
			(end 0.508 -0.9398)
			(stroke
				(width 0)
				(type default)
			)
			(fill no)
			(layer "F.CrtYd")
		)
		(fp_rect
			(start -0.508 0.9398)
			(end 0.508 -0.9398)
			(stroke
				(width 0)
				(type default)
			)
			(fill no)
			(layer "F.Fab")
		)
		(pad "1" smd custom
			(at 0 -0.4445 180)
			(size 0.1397 0.1397)
			(layers "F.Cu" "F.Mask" "F.Paste")
			(net "P3V3")
			(options
				(clearance outline)
				(anchor circle)
			)
			(primitives
				(gr_poly
					(pts
						(arc
							(start -0.1778 -0.2794)
							(mid -0.249642 -0.249642)
							(end -0.2794 -0.1778)
						)
						(arc
							(start -0.2794 0.1778)
							(mid -0.249642 0.249642)
							(end -0.1778 0.2794)
						)
						(arc
							(start 0.1778 0.2794)
							(mid 0.249642 0.249642)
							(end 0.2794 0.1778)
						)
						(arc
							(start 0.2794 -0.1778)
							(mid 0.249642 -0.249642)
							(end 0.1778 -0.2794)
						)
					)
					(width 0)
					(fill yes)
				)
			)
		)
		(pad "2" smd custom
			(at 0 0.4445 180)
			(size 0.1397 0.1397)
			(layers "F.Cu" "F.Mask" "F.Paste")
			(net "SSD8_PWREN")
			(options
				(clearance outline)
				(anchor circle)
			)
			(primitives
				(gr_poly
					(pts
						(arc
							(start -0.1778 -0.2794)
							(mid -0.249642 -0.249642)
							(end -0.2794 -0.1778)
						)
						(arc
							(start -0.2794 0.1778)
							(mid -0.249642 0.249642)
							(end -0.1778 0.2794)
						)
						(arc
							(start 0.1778 0.2794)
							(mid 0.249642 0.249642)
							(end 0.2794 0.1778)
						)
						(arc
							(start 0.2794 -0.1778)
							(mid 0.249642 -0.249642)
							(end 0.1778 -0.2794)
						)
					)
					(width 0)
					(fill yes)
				)
			)
		)
	)
	(footprint ""
		(layer "F.Cu")
		(at 210.947 -300.9646 -90)
		(property "Reference" "Q36"
			(at 0 0 270)
			(layer "F.SilkS")
			(hide yes)
			(effects
				(font
					(size 1.27 1.27)
				)
			)
		)
		(property "Value" "2N7002A-7-GP"
			(at 0.127 -8.9662 270)
			(unlocked yes)
			(layer "F.Fab")
			(hide yes)
			(effects
				(font
					(size 1.016 1.016)
					(thickness 0.1524)
				)
			)
		)
		(property "Device Type" "SOT23DGS2D4H48"
			(at 0.127 -10.4902 270)
			(unlocked yes)
			(layer "F.Fab")
			(hide yes)
			(effects
				(font
					(size 1.016 1.016)
					(thickness 0.1524)
				)
			)
		)
		(duplicate_pad_numbers_are_jumpers no)
		(fp_line
			(start -1.651 1.778)
			(end 1.651 1.778)
			(stroke
				(width 0.1524)
				(type default)
			)
			(layer "F.SilkS")
		)
		(fp_line
			(start 1.651 1.778)
			(end 1.651 -1.778)
			(stroke
				(width 0.1524)
				(type default)
			)
			(layer "F.SilkS")
		)
		(fp_line
			(start -1.651 -1.778)
			(end -1.651 1.778)
			(stroke
				(width 0.1524)
				(type default)
			)
			(layer "F.SilkS")
		)
		(fp_line
			(start 1.651 -1.778)
			(end -1.651 -1.778)
			(stroke
				(width 0.1524)
				(type default)
			)
			(layer "F.SilkS")
		)
		(fp_poly
			(pts
				(xy -1.778 1.8796) (xy -1.778 -1.8796) (xy 1.778 -1.8796) (xy 1.778 1.8796)
			)
			(stroke
				(width 0)
				(type default)
			)
			(fill no)
			(layer "F.CrtYd")
		)
		(fp_poly
			(pts
				(xy -1.778 1.8796) (xy -1.778 -1.8796) (xy 1.778 -1.8796) (xy 1.778 1.8796)
			)
			(stroke
				(width 0)
				(type default)
			)
			(fill no)
			(layer "F.Fab")
		)
		(pad "D" smd custom
			(at 0 -0.9525 270)
			(size 0.1905 0.1905)
			(layers "F.Cu" "F.Mask" "F.Paste")
			(net "P12V_MOST2_GATE")
			(options
				(clearance outline)
				(anchor circle)
			)
			(primitives
				(gr_poly
					(pts
						(arc
							(start -0.1778 0.5715)
							(mid -0.321484 0.511984)
							(end -0.381 0.3683)
						)
						(arc
							(start -0.381 -0.3683)
							(mid -0.321484 -0.511984)
							(end -0.1778 -0.5715)
						)
						(arc
							(start 0.1778 -0.5715)
							(mid 0.321484 -0.511984)
							(end 0.381 -0.3683)
						)
						(arc
							(start 0.381 0.3683)
							(mid 0.321484 0.511984)
							(end 0.1778 0.5715)
						)
					)
					(width 0)
					(fill yes)
				)
			)
		)
		(pad "G" smd custom
			(at -0.98425 0.9525 270)
			(size 0.1905 0.1905)
			(layers "F.Cu" "F.Mask" "F.Paste")
			(net "SSD2_PWREN_R")
			(options
				(clearance outline)
				(anchor circle)
			)
			(primitives
				(gr_poly
					(pts
						(arc
							(start -0.1778 0.5715)
							(mid -0.321484 0.511984)
							(end -0.381 0.3683)
						)
						(arc
							(start -0.381 -0.3683)
							(mid -0.321484 -0.511984)
							(end -0.1778 -0.5715)
						)
						(arc
							(start 0.1778 -0.5715)
							(mid 0.321484 -0.511984)
							(end 0.381 -0.3683)
						)
						(arc
							(start 0.381 0.3683)
							(mid 0.321484 0.511984)
							(end 0.1778 0.5715)
						)
					)
					(width 0)
					(fill yes)
				)
			)
		)
		(pad "S" smd custom
			(at 0.98425 0.9525 270)
			(size 0.1905 0.1905)
			(layers "F.Cu" "F.Mask" "F.Paste")
			(net "GND")
			(options
				(clearance outline)
				(anchor circle)
			)
			(primitives
				(gr_poly
					(pts
						(arc
							(start -0.1778 0.5715)
							(mid -0.321484 0.511984)
							(end -0.381 0.3683)
						)
						(arc
							(start -0.381 -0.3683)
							(mid -0.321484 -0.511984)
							(end -0.1778 -0.5715)
						)
						(arc
							(start 0.1778 -0.5715)
							(mid 0.321484 -0.511984)
							(end 0.381 -0.3683)
						)
						(arc
							(start 0.381 0.3683)
							(mid 0.321484 0.511984)
							(end 0.1778 0.5715)
						)
					)
					(width 0)
					(fill yes)
				)
			)
		)
	)
	(footprint ""
		(layer "F.Cu")
		(at 225.1075 -244.405658 90)
		(property "Reference" "R9796"
			(at 0 0 90)
			(layer "F.SilkS")
			(hide yes)
			(effects
				(font
					(size 1.27 1.27)
				)
			)
		)
		(property "Value" "0R2J-2-GP"
			(at 0.064008 -3.993896 90)
			(unlocked yes)
			(layer "F.Fab")
			(hide yes)
			(effects
				(font
					(size 1.016 1.016)
					(thickness 0.1524)
				)
			)
		)
		(property "Device Type" "R402H16"
			(at 0.064008 -5.517896 90)
			(unlocked yes)
			(layer "F.Fab")
			(hide yes)
			(effects
				(font
					(size 1.016 1.016)
					(thickness 0.1524)
				)
			)
		)
		(duplicate_pad_numbers_are_jumpers no)
		(fp_line
			(start 0.508 -0.9398)
			(end -0.508 -0.9398)
			(stroke
				(width 0.1524)
				(type default)
			)
			(layer "F.SilkS")
		)
		(fp_line
			(start -0.508 -0.9398)
			(end -0.508 0.9398)
			(stroke
				(width 0.1524)
				(type default)
			)
			(layer "F.SilkS")
		)
		(fp_rect
			(start -0.508 0.9398)
			(end 0.508 -0.9398)
			(stroke
				(width 0)
				(type default)
			)
			(fill no)
			(layer "F.CrtYd")
		)
		(fp_rect
			(start -0.508 0.9398)
			(end 0.508 -0.9398)
			(stroke
				(width 0)
				(type default)
			)
			(fill no)
			(layer "F.Fab")
		)
		(pad "1" smd custom
			(at 0 -0.4445 90)
			(size 0.1397 0.1397)
			(layers "F.Cu" "F.Mask" "F.Paste")
			(net "ATTN_LED_DR2_R")
			(options
				(clearance outline)
				(anchor circle)
			)
			(primitives
				(gr_poly
					(pts
						(arc
							(start -0.1778 -0.2794)
							(mid -0.249642 -0.249642)
							(end -0.2794 -0.1778)
						)
						(arc
							(start -0.2794 0.1778)
							(mid -0.249642 0.249642)
							(end -0.1778 0.2794)
						)
						(arc
							(start 0.1778 0.2794)
							(mid 0.249642 0.249642)
							(end 0.2794 0.1778)
						)
						(arc
							(start 0.2794 -0.1778)
							(mid 0.249642 -0.249642)
							(end 0.1778 -0.2794)
						)
					)
					(width 0)
					(fill yes)
				)
			)
		)
		(pad "2" smd custom
			(at 0 0.4445 90)
			(size 0.1397 0.1397)
			(layers "F.Cu" "F.Mask" "F.Paste")
			(net "ATTN_LED_DR2_N")
			(options
				(clearance outline)
				(anchor circle)
			)
			(primitives
				(gr_poly
					(pts
						(arc
							(start -0.1778 -0.2794)
							(mid -0.249642 -0.249642)
							(end -0.2794 -0.1778)
						)
						(arc
							(start -0.2794 0.1778)
							(mid -0.249642 0.249642)
							(end -0.1778 0.2794)
						)
						(arc
							(start 0.1778 0.2794)
							(mid 0.249642 0.249642)
							(end 0.2794 0.1778)
						)
						(arc
							(start 0.2794 -0.1778)
							(mid 0.249642 -0.249642)
							(end 0.1778 -0.2794)
						)
					)
					(width 0)
					(fill yes)
				)
			)
		)
	)
	(footprint ""
		(layer "F.Cu")
		(at 98.806 -320.167 90)
		(property "Reference" "R9472"
			(at 0 0 90)
			(layer "F.SilkS")
			(hide yes)
			(effects
				(font
					(size 1.27 1.27)
				)
			)
		)
		(property "Value" "4K7R2J-2-GP"
			(at 0.064008 -3.993896 90)
			(unlocked yes)
			(layer "F.Fab")
			(hide yes)
			(effects
				(font
					(size 1.016 1.016)
					(thickness 0.1524)
				)
			)
		)
		(property "Device Type" "R402H16"
			(at 0.064008 -5.517896 90)
			(unlocked yes)
			(layer "F.Fab")
			(hide yes)
			(effects
				(font
					(size 1.016 1.016)
					(thickness 0.1524)
				)
			)
		)
		(duplicate_pad_numbers_are_jumpers no)
		(fp_line
			(start 0.508 -0.9398)
			(end -0.508 -0.9398)
			(stroke
				(width 0.1524)
				(type default)
			)
			(layer "F.SilkS")
		)
		(fp_line
			(start -0.508 -0.9398)
			(end -0.508 0.9398)
			(stroke
				(width 0.1524)
				(type default)
			)
			(layer "F.SilkS")
		)
		(fp_rect
			(start -0.508 0.9398)
			(end 0.508 -0.9398)
			(stroke
				(width 0)
				(type default)
			)
			(fill no)
			(layer "F.CrtYd")
		)
		(fp_rect
			(start -0.508 0.9398)
			(end 0.508 -0.9398)
			(stroke
				(width 0)
				(type default)
			)
			(fill no)
			(layer "F.Fab")
		)
		(pad "1" smd custom
			(at 0 -0.4445 90)
			(size 0.1397 0.1397)
			(layers "F.Cu" "F.Mask" "F.Paste")
			(net "P3V3")
			(options
				(clearance outline)
				(anchor circle)
			)
			(primitives
				(gr_poly
					(pts
						(arc
							(start -0.1778 -0.2794)
							(mid -0.249642 -0.249642)
							(end -0.2794 -0.1778)
						)
						(arc
							(start -0.2794 0.1778)
							(mid -0.249642 0.249642)
							(end -0.1778 0.2794)
						)
						(arc
							(start 0.1778 0.2794)
							(mid 0.249642 0.249642)
							(end 0.2794 0.1778)
						)
						(arc
							(start 0.2794 -0.1778)
							(mid 0.249642 -0.249642)
							(end 0.1778 -0.2794)
						)
					)
					(width 0)
					(fill yes)
				)
			)
		)
		(pad "2" smd custom
			(at 0 0.4445 90)
			(size 0.1397 0.1397)
			(layers "F.Cu" "F.Mask" "F.Paste")
			(net "SSD_PRSNT_NET6")
			(options
				(clearance outline)
				(anchor circle)
			)
			(primitives
				(gr_poly
					(pts
						(arc
							(start -0.1778 -0.2794)
							(mid -0.249642 -0.249642)
							(end -0.2794 -0.1778)
						)
						(arc
							(start -0.2794 0.1778)
							(mid -0.249642 0.249642)
							(end -0.1778 0.2794)
						)
						(arc
							(start 0.1778 0.2794)
							(mid 0.249642 0.249642)
							(end 0.2794 0.1778)
						)
						(arc
							(start 0.2794 -0.1778)
							(mid 0.249642 -0.249642)
							(end 0.1778 -0.2794)
						)
					)
					(width 0)
					(fill yes)
				)
			)
		)
	)
	(footprint ""
		(layer "F.Cu")
		(at 87.757 -320.167 90)
		(property "Reference" "R9515"
			(at 0 0 90)
			(layer "F.SilkS")
			(hide yes)
			(effects
				(font
					(size 1.27 1.27)
				)
			)
		)
		(property "Value" "4K7R2J-2-GP"
			(at 0.064008 -3.993896 90)
			(unlocked yes)
			(layer "F.Fab")
			(hide yes)
			(effects
				(font
					(size 1.016 1.016)
					(thickness 0.1524)
				)
			)
		)
		(property "Device Type" "R402H16"
			(at 0.064008 -5.517896 90)
			(unlocked yes)
			(layer "F.Fab")
			(hide yes)
			(effects
				(font
					(size 1.016 1.016)
					(thickness 0.1524)
				)
			)
		)
		(duplicate_pad_numbers_are_jumpers no)
		(fp_line
			(start 0.508 -0.9398)
			(end -0.508 -0.9398)
			(stroke
				(width 0.1524)
				(type default)
			)
			(layer "F.SilkS")
		)
		(fp_line
			(start -0.508 -0.9398)
			(end -0.508 0.9398)
			(stroke
				(width 0.1524)
				(type default)
			)
			(layer "F.SilkS")
		)
		(fp_rect
			(start -0.508 0.9398)
			(end 0.508 -0.9398)
			(stroke
				(width 0)
				(type default)
			)
			(fill no)
			(layer "F.CrtYd")
		)
		(fp_rect
			(start -0.508 0.9398)
			(end 0.508 -0.9398)
			(stroke
				(width 0)
				(type default)
			)
			(fill no)
			(layer "F.Fab")
		)
		(pad "1" smd custom
			(at 0 -0.4445 90)
			(size 0.1397 0.1397)
			(layers "F.Cu" "F.Mask" "F.Paste")
			(net "P3V3")
			(options
				(clearance outline)
				(anchor circle)
			)
			(primitives
				(gr_poly
					(pts
						(arc
							(start -0.1778 -0.2794)
							(mid -0.249642 -0.249642)
							(end -0.2794 -0.1778)
						)
						(arc
							(start -0.2794 0.1778)
							(mid -0.249642 0.249642)
							(end -0.1778 0.2794)
						)
						(arc
							(start 0.1778 0.2794)
							(mid 0.249642 0.249642)
							(end 0.2794 0.1778)
						)
						(arc
							(start 0.2794 -0.1778)
							(mid 0.249642 -0.249642)
							(end 0.1778 -0.2794)
						)
					)
					(width 0)
					(fill yes)
				)
			)
		)
		(pad "2" smd custom
			(at 0 0.4445 90)
			(size 0.1397 0.1397)
			(layers "F.Cu" "F.Mask" "F.Paste")
			(net "SSD11_CLK0_OE_N")
			(options
				(clearance outline)
				(anchor circle)
			)
			(primitives
				(gr_poly
					(pts
						(arc
							(start -0.1778 -0.2794)
							(mid -0.249642 -0.249642)
							(end -0.2794 -0.1778)
						)
						(arc
							(start -0.2794 0.1778)
							(mid -0.249642 0.249642)
							(end -0.1778 0.2794)
						)
						(arc
							(start 0.1778 0.2794)
							(mid 0.249642 0.249642)
							(end 0.2794 0.1778)
						)
						(arc
							(start 0.2794 -0.1778)
							(mid 0.249642 -0.249642)
							(end 0.1778 -0.2794)
						)
					)
					(width 0)
					(fill yes)
				)
			)
		)
	)
	(footprint ""
		(layer "F.Cu")
		(at 21.231606 -59.10961 180)
		(property "Reference" "R9926"
			(at 0 0 180)
			(layer "F.SilkS")
			(hide yes)
			(effects
				(font
					(size 1.27 1.27)
				)
			)
		)
		(property "Value" "47KR2J-2-GP"
			(at 0.064008 -3.993896 180)
			(unlocked yes)
			(layer "F.Fab")
			(hide yes)
			(effects
				(font
					(size 1.016 1.016)
					(thickness 0.1524)
				)
			)
		)
		(property "Device Type" "R402H16"
			(at 0.064008 -5.517896 180)
			(unlocked yes)
			(layer "F.Fab")
			(hide yes)
			(effects
				(font
					(size 1.016 1.016)
					(thickness 0.1524)
				)
			)
		)
		(duplicate_pad_numbers_are_jumpers no)
		(fp_line
			(start 0.508 -0.9398)
			(end -0.508 -0.9398)
			(stroke
				(width 0.1524)
				(type default)
			)
			(layer "F.SilkS")
		)
		(fp_line
			(start -0.508 -0.9398)
			(end -0.508 0.9398)
			(stroke
				(width 0.1524)
				(type default)
			)
			(layer "F.SilkS")
		)
		(fp_rect
			(start -0.508 0.9398)
			(end 0.508 -0.9398)
			(stroke
				(width 0)
				(type default)
			)
			(fill no)
			(layer "F.CrtYd")
		)
		(fp_rect
			(start -0.508 0.9398)
			(end 0.508 -0.9398)
			(stroke
				(width 0)
				(type default)
			)
			(fill no)
			(layer "F.Fab")
		)
		(pad "1" smd custom
			(at 0 -0.4445 180)
			(size 0.1397 0.1397)
			(layers "F.Cu" "F.Mask" "F.Paste")
			(net "P3V3")
			(options
				(clearance outline)
				(anchor circle)
			)
			(primitives
				(gr_poly
					(pts
						(arc
							(start -0.1778 -0.2794)
							(mid -0.249642 -0.249642)
							(end -0.2794 -0.1778)
						)
						(arc
							(start -0.2794 0.1778)
							(mid -0.249642 0.249642)
							(end -0.1778 0.2794)
						)
						(arc
							(start 0.1778 0.2794)
							(mid 0.249642 0.249642)
							(end 0.2794 0.1778)
						)
						(arc
							(start 0.2794 -0.1778)
							(mid 0.249642 -0.249642)
							(end 0.1778 -0.2794)
						)
					)
					(width 0)
					(fill yes)
				)
			)
		)
		(pad "2" smd custom
			(at 0 0.4445 180)
			(size 0.1397 0.1397)
			(layers "F.Cu" "F.Mask" "F.Paste")
			(net "ATTN_LED_DR14_N")
			(options
				(clearance outline)
				(anchor circle)
			)
			(primitives
				(gr_poly
					(pts
						(arc
							(start -0.1778 -0.2794)
							(mid -0.249642 -0.249642)
							(end -0.2794 -0.1778)
						)
						(arc
							(start -0.2794 0.1778)
							(mid -0.249642 0.249642)
							(end -0.1778 0.2794)
						)
						(arc
							(start 0.1778 0.2794)
							(mid 0.249642 0.249642)
							(end 0.2794 0.1778)
						)
						(arc
							(start 0.2794 -0.1778)
							(mid 0.249642 -0.249642)
							(end 0.1778 -0.2794)
						)
					)
					(width 0)
					(fill yes)
				)
			)
		)
	)
	(footprint ""
		(layer "F.Cu")
		(at 89.789 -225.806 90)
		(property "Reference" "R9479"
			(at 0 0 90)
			(layer "F.SilkS")
			(hide yes)
			(effects
				(font
					(size 1.27 1.27)
				)
			)
		)
		(property "Value" "4K7R2J-2-GP"
			(at 0.064008 -3.993896 90)
			(unlocked yes)
			(layer "F.Fab")
			(hide yes)
			(effects
				(font
					(size 1.016 1.016)
					(thickness 0.1524)
				)
			)
		)
		(property "Device Type" "R402H16"
			(at 0.064008 -5.517896 90)
			(unlocked yes)
			(layer "F.Fab")
			(hide yes)
			(effects
				(font
					(size 1.016 1.016)
					(thickness 0.1524)
				)
			)
		)
		(duplicate_pad_numbers_are_jumpers no)
		(fp_line
			(start 0.508 -0.9398)
			(end -0.508 -0.9398)
			(stroke
				(width 0.1524)
				(type default)
			)
			(layer "F.SilkS")
		)
		(fp_line
			(start -0.508 -0.9398)
			(end -0.508 0.9398)
			(stroke
				(width 0.1524)
				(type default)
			)
			(layer "F.SilkS")
		)
		(fp_rect
			(start -0.508 0.9398)
			(end 0.508 -0.9398)
			(stroke
				(width 0)
				(type default)
			)
			(fill no)
			(layer "F.CrtYd")
		)
		(fp_rect
			(start -0.508 0.9398)
			(end 0.508 -0.9398)
			(stroke
				(width 0)
				(type default)
			)
			(fill no)
			(layer "F.Fab")
		)
		(pad "1" smd custom
			(at 0 -0.4445 90)
			(size 0.1397 0.1397)
			(layers "F.Cu" "F.Mask" "F.Paste")
			(net "P3V3")
			(options
				(clearance outline)
				(anchor circle)
			)
			(primitives
				(gr_poly
					(pts
						(arc
							(start -0.1778 -0.2794)
							(mid -0.249642 -0.249642)
							(end -0.2794 -0.1778)
						)
						(arc
							(start -0.2794 0.1778)
							(mid -0.249642 0.249642)
							(end -0.1778 0.2794)
						)
						(arc
							(start 0.1778 0.2794)
							(mid 0.249642 0.249642)
							(end 0.2794 0.1778)
						)
						(arc
							(start 0.2794 -0.1778)
							(mid 0.249642 -0.249642)
							(end 0.1778 -0.2794)
						)
					)
					(width 0)
					(fill yes)
				)
			)
		)
		(pad "2" smd custom
			(at 0 0.4445 90)
			(size 0.1397 0.1397)
			(layers "F.Cu" "F.Mask" "F.Paste")
			(net "SSD_PRSNT_NET12")
			(options
				(clearance outline)
				(anchor circle)
			)
			(primitives
				(gr_poly
					(pts
						(arc
							(start -0.1778 -0.2794)
							(mid -0.249642 -0.249642)
							(end -0.2794 -0.1778)
						)
						(arc
							(start -0.2794 0.1778)
							(mid -0.249642 0.249642)
							(end -0.1778 0.2794)
						)
						(arc
							(start 0.1778 0.2794)
							(mid 0.249642 0.249642)
							(end 0.2794 0.1778)
						)
						(arc
							(start 0.2794 -0.1778)
							(mid 0.249642 -0.249642)
							(end 0.1778 -0.2794)
						)
					)
					(width 0)
					(fill yes)
				)
			)
		)
	)
	(footprint ""
		(layer "F.Cu")
		(at 14.826488 -425.843192 180)
		(property "Reference" "C9538"
			(at 0 0 180)
			(layer "F.SilkS")
			(hide yes)
			(effects
				(font
					(size 1.27 1.27)
				)
			)
		)
		(property "Value" "SCD01U50V2KX-1GP"
			(at 1.1811 -2.7051 180)
			(unlocked yes)
			(layer "F.Fab")
			(hide yes)
			(effects
				(font
					(size 1.016 1.016)
					(thickness 0.1524)
				)
			)
		)
		(property "Device Type" "C402H22"
			(at 1.1811 -4.2291 180)
			(unlocked yes)
			(layer "F.Fab")
			(hide yes)
			(effects
				(font
					(size 1.016 1.016)
					(thickness 0.1524)
				)
			)
		)
		(duplicate_pad_numbers_are_jumpers no)
		(fp_rect
			(start -0.4318 0.9525)
			(end 0.4318 -0.9525)
			(stroke
				(width 0)
				(type default)
			)
			(fill no)
			(layer "F.CrtYd")
		)
		(fp_rect
			(start -0.4318 0.9525)
			(end 0.4318 -0.9525)
			(stroke
				(width 0)
				(type default)
			)
			(fill no)
			(layer "F.Fab")
		)
		(pad "1" smd custom
			(at 0 -0.4445 180)
			(size 0.1524 0.1524)
			(layers "F.Cu" "F.Mask" "F.Paste")
			(net "PE_100M_CLK3_P")
			(options
				(clearance outline)
				(anchor circle)
			)
			(primitives
				(gr_poly
					(pts
						(arc
							(start 0.3048 -0.2032)
							(mid 0.275042 -0.275042)
							(end 0.2032 -0.3048)
						)
						(arc
							(start -0.2032 -0.3048)
							(mid -0.275042 -0.275042)
							(end -0.3048 -0.2032)
						)
						(arc
							(start -0.3048 0.2032)
							(mid -0.275042 0.275042)
							(end -0.2032 0.3048)
						)
						(arc
							(start 0.2032 0.3048)
							(mid 0.275042 0.275042)
							(end 0.3048 0.2032)
						)
					)
					(width 0)
					(fill yes)
				)
			)
		)
		(pad "2" smd custom
			(at 0 0.4445 180)
			(size 0.1524 0.1524)
			(layers "F.Cu" "F.Mask" "F.Paste")
			(net "PE_100M_CLK3_C_P")
			(options
				(clearance outline)
				(anchor circle)
			)
			(primitives
				(gr_poly
					(pts
						(arc
							(start 0.3048 -0.2032)
							(mid 0.275042 -0.275042)
							(end 0.2032 -0.3048)
						)
						(arc
							(start -0.2032 -0.3048)
							(mid -0.275042 -0.275042)
							(end -0.3048 -0.2032)
						)
						(arc
							(start -0.3048 0.2032)
							(mid -0.275042 0.275042)
							(end -0.2032 0.3048)
						)
						(arc
							(start 0.2032 0.3048)
							(mid 0.275042 0.275042)
							(end 0.3048 0.2032)
						)
					)
					(width 0)
					(fill yes)
				)
			)
		)
	)
	(footprint ""
		(layer "F.Cu")
		(at 84.455 -204.978 90)
		(property "Reference" "PR9039"
			(at 0 0 90)
			(layer "F.SilkS")
			(hide yes)
			(effects
				(font
					(size 1.27 1.27)
				)
			)
		)
		(property "Value" "4K7R2F-GP"
			(at 0.064008 -3.993896 90)
			(unlocked yes)
			(layer "F.Fab")
			(hide yes)
			(effects
				(font
					(size 1.016 1.016)
					(thickness 0.1524)
				)
			)
		)
		(property "Device Type" "R402H16"
			(at 0.064008 -5.517896 90)
			(unlocked yes)
			(layer "F.Fab")
			(hide yes)
			(effects
				(font
					(size 1.016 1.016)
					(thickness 0.1524)
				)
			)
		)
		(duplicate_pad_numbers_are_jumpers no)
		(fp_line
			(start 0.508 -0.9398)
			(end -0.508 -0.9398)
			(stroke
				(width 0.1524)
				(type default)
			)
			(layer "F.SilkS")
		)
		(fp_line
			(start -0.508 -0.9398)
			(end -0.508 0.9398)
			(stroke
				(width 0.1524)
				(type default)
			)
			(layer "F.SilkS")
		)
		(fp_rect
			(start -0.508 0.9398)
			(end 0.508 -0.9398)
			(stroke
				(width 0)
				(type default)
			)
			(fill no)
			(layer "F.CrtYd")
		)
		(fp_rect
			(start -0.508 0.9398)
			(end 0.508 -0.9398)
			(stroke
				(width 0)
				(type default)
			)
			(fill no)
			(layer "F.Fab")
		)
		(pad "1" smd custom
			(at 0 -0.4445 90)
			(size 0.1397 0.1397)
			(layers "F.Cu" "F.Mask" "F.Paste")
			(net "VDD_DIFF_3")
			(options
				(clearance outline)
				(anchor circle)
			)
			(primitives
				(gr_poly
					(pts
						(arc
							(start -0.1778 -0.2794)
							(mid -0.249642 -0.249642)
							(end -0.2794 -0.1778)
						)
						(arc
							(start -0.2794 0.1778)
							(mid -0.249642 0.249642)
							(end -0.1778 0.2794)
						)
						(arc
							(start 0.1778 0.2794)
							(mid 0.249642 0.249642)
							(end 0.2794 0.1778)
						)
						(arc
							(start 0.2794 -0.1778)
							(mid 0.249642 -0.249642)
							(end 0.1778 -0.2794)
						)
					)
					(width 0)
					(fill yes)
				)
			)
		)
		(pad "2" smd custom
			(at 0 0.4445 90)
			(size 0.1397 0.1397)
			(layers "F.Cu" "F.Mask" "F.Paste")
			(net "CLK_BUF_EU3_SMB_A1_TRI")
			(options
				(clearance outline)
				(anchor circle)
			)
			(primitives
				(gr_poly
					(pts
						(arc
							(start -0.1778 -0.2794)
							(mid -0.249642 -0.249642)
							(end -0.2794 -0.1778)
						)
						(arc
							(start -0.2794 0.1778)
							(mid -0.249642 0.249642)
							(end -0.1778 0.2794)
						)
						(arc
							(start 0.1778 0.2794)
							(mid 0.249642 0.249642)
							(end 0.2794 0.1778)
						)
						(arc
							(start 0.2794 -0.1778)
							(mid 0.249642 -0.249642)
							(end 0.1778 -0.2794)
						)
					)
					(width 0)
					(fill yes)
				)
			)
		)
	)
	(footprint ""
		(layer "F.Cu")
		(at 24.003 -54.47411 -90)
		(property "Reference" "SR1149"
			(at 0 0 270)
			(layer "F.SilkS")
			(hide yes)
			(effects
				(font
					(size 1.27 1.27)
				)
			)
		)
		(property "Value" "4K7R2F-GP"
			(at 0.064008 -3.993896 270)
			(unlocked yes)
			(layer "F.Fab")
			(hide yes)
			(effects
				(font
					(size 1.016 1.016)
					(thickness 0.1524)
				)
			)
		)
		(property "Device Type" "R402H16"
			(at 0.064008 -5.517896 270)
			(unlocked yes)
			(layer "F.Fab")
			(hide yes)
			(effects
				(font
					(size 1.016 1.016)
					(thickness 0.1524)
				)
			)
		)
		(duplicate_pad_numbers_are_jumpers no)
		(fp_line
			(start -0.508 -0.9398)
			(end -0.508 0.9398)
			(stroke
				(width 0.1524)
				(type default)
			)
			(layer "F.SilkS")
		)
		(fp_line
			(start 0.508 -0.9398)
			(end -0.508 -0.9398)
			(stroke
				(width 0.1524)
				(type default)
			)
			(layer "F.SilkS")
		)
		(fp_rect
			(start -0.508 0.9398)
			(end 0.508 -0.9398)
			(stroke
				(width 0)
				(type default)
			)
			(fill no)
			(layer "F.CrtYd")
		)
		(fp_rect
			(start -0.508 0.9398)
			(end 0.508 -0.9398)
			(stroke
				(width 0)
				(type default)
			)
			(fill no)
			(layer "F.Fab")
		)
		(pad "1" smd custom
			(at 0 -0.4445 270)
			(size 0.1397 0.1397)
			(layers "F.Cu" "F.Mask" "F.Paste")
			(net "P3V3")
			(options
				(clearance outline)
				(anchor circle)
			)
			(primitives
				(gr_poly
					(pts
						(arc
							(start -0.1778 -0.2794)
							(mid -0.249642 -0.249642)
							(end -0.2794 -0.1778)
						)
						(arc
							(start -0.2794 0.1778)
							(mid -0.249642 0.249642)
							(end -0.1778 0.2794)
						)
						(arc
							(start 0.1778 0.2794)
							(mid 0.249642 0.249642)
							(end 0.2794 0.1778)
						)
						(arc
							(start 0.2794 -0.1778)
							(mid 0.249642 -0.249642)
							(end 0.1778 -0.2794)
						)
					)
					(width 0)
					(fill yes)
				)
			)
		)
		(pad "2" smd custom
			(at 0 0.4445 270)
			(size 0.1397 0.1397)
			(layers "F.Cu" "F.Mask" "F.Paste")
			(net "SSD14_CLK0_OE_MOS_N")
			(options
				(clearance outline)
				(anchor circle)
			)
			(primitives
				(gr_poly
					(pts
						(arc
							(start -0.1778 -0.2794)
							(mid -0.249642 -0.249642)
							(end -0.2794 -0.1778)
						)
						(arc
							(start -0.2794 0.1778)
							(mid -0.249642 0.249642)
							(end -0.1778 0.2794)
						)
						(arc
							(start 0.1778 0.2794)
							(mid 0.249642 0.249642)
							(end 0.2794 0.1778)
						)
						(arc
							(start 0.2794 -0.1778)
							(mid 0.249642 -0.249642)
							(end 0.1778 -0.2794)
						)
					)
					(width 0)
					(fill yes)
				)
			)
		)
	)
	(footprint ""
		(layer "F.Cu")
		(at 80.137 -354.076 180)
		(property "Reference" "SR1052"
			(at 0 0 180)
			(layer "F.SilkS")
			(hide yes)
			(effects
				(font
					(size 1.27 1.27)
				)
			)
		)
		(property "Value" "4K7R2F-GP"
			(at 0.064008 -3.993896 180)
			(unlocked yes)
			(layer "F.Fab")
			(hide yes)
			(effects
				(font
					(size 1.016 1.016)
					(thickness 0.1524)
				)
			)
		)
		(property "Device Type" "R402H16"
			(at 0.064008 -5.517896 180)
			(unlocked yes)
			(layer "F.Fab")
			(hide yes)
			(effects
				(font
					(size 1.016 1.016)
					(thickness 0.1524)
				)
			)
		)
		(duplicate_pad_numbers_are_jumpers no)
		(fp_line
			(start 0.508 -0.9398)
			(end -0.508 -0.9398)
			(stroke
				(width 0.1524)
				(type default)
			)
			(layer "F.SilkS")
		)
		(fp_line
			(start -0.508 -0.9398)
			(end -0.508 0.9398)
			(stroke
				(width 0.1524)
				(type default)
			)
			(layer "F.SilkS")
		)
		(fp_rect
			(start -0.508 0.9398)
			(end 0.508 -0.9398)
			(stroke
				(width 0)
				(type default)
			)
			(fill no)
			(layer "F.CrtYd")
		)
		(fp_rect
			(start -0.508 0.9398)
			(end 0.508 -0.9398)
			(stroke
				(width 0)
				(type default)
			)
			(fill no)
			(layer "F.Fab")
		)
		(pad "1" smd custom
			(at 0 -0.4445 180)
			(size 0.1397 0.1397)
			(layers "F.Cu" "F.Mask" "F.Paste")
			(net "P3V3")
			(options
				(clearance outline)
				(anchor circle)
			)
			(primitives
				(gr_poly
					(pts
						(arc
							(start -0.1778 -0.2794)
							(mid -0.249642 -0.249642)
							(end -0.2794 -0.1778)
						)
						(arc
							(start -0.2794 0.1778)
							(mid -0.249642 0.249642)
							(end -0.1778 0.2794)
						)
						(arc
							(start 0.1778 0.2794)
							(mid 0.249642 0.249642)
							(end 0.2794 0.1778)
						)
						(arc
							(start 0.2794 -0.1778)
							(mid 0.249642 -0.249642)
							(end 0.1778 -0.2794)
						)
					)
					(width 0)
					(fill yes)
				)
			)
		)
		(pad "2" smd custom
			(at 0 0.4445 180)
			(size 0.1397 0.1397)
			(layers "F.Cu" "F.Mask" "F.Paste")
			(net "I2C_SW_EU17_ADDRESS_A1")
			(options
				(clearance outline)
				(anchor circle)
			)
			(primitives
				(gr_poly
					(pts
						(arc
							(start -0.1778 -0.2794)
							(mid -0.249642 -0.249642)
							(end -0.2794 -0.1778)
						)
						(arc
							(start -0.2794 0.1778)
							(mid -0.249642 0.249642)
							(end -0.1778 0.2794)
						)
						(arc
							(start 0.1778 0.2794)
							(mid 0.249642 0.249642)
							(end 0.2794 0.1778)
						)
						(arc
							(start 0.2794 -0.1778)
							(mid 0.249642 -0.249642)
							(end 0.1778 -0.2794)
						)
					)
					(width 0)
					(fill yes)
				)
			)
		)
	)
	(footprint ""
		(layer "F.Cu")
		(at 17.123156 -160.010348)
		(property "Reference" "R9953"
			(at 0 0 0)
			(layer "F.SilkS")
			(hide yes)
			(effects
				(font
					(size 1.27 1.27)
				)
			)
		)
		(property "Value" "4K7R2J-2-GP"
			(at 0.064008 -3.993896 0)
			(unlocked yes)
			(layer "F.Fab")
			(hide yes)
			(effects
				(font
					(size 1.016 1.016)
					(thickness 0.1524)
				)
			)
		)
		(property "Device Type" "R402H16"
			(at 0.064008 -5.517896 0)
			(unlocked yes)
			(layer "F.Fab")
			(hide yes)
			(effects
				(font
					(size 1.016 1.016)
					(thickness 0.1524)
				)
			)
		)
		(duplicate_pad_numbers_are_jumpers no)
		(fp_line
			(start -0.508 -0.9398)
			(end -0.508 0.9398)
			(stroke
				(width 0.1524)
				(type default)
			)
			(layer "F.SilkS")
		)
		(fp_line
			(start 0.508 -0.9398)
			(end -0.508 -0.9398)
			(stroke
				(width 0.1524)
				(type default)
			)
			(layer "F.SilkS")
		)
		(fp_rect
			(start -0.508 0.9398)
			(end 0.508 -0.9398)
			(stroke
				(width 0)
				(type default)
			)
			(fill no)
			(layer "F.CrtYd")
		)
		(fp_rect
			(start -0.508 0.9398)
			(end 0.508 -0.9398)
			(stroke
				(width 0)
				(type default)
			)
			(fill no)
			(layer "F.Fab")
		)
		(pad "1" smd custom
			(at 0 -0.4445)
			(size 0.1397 0.1397)
			(layers "F.Cu" "F.Mask" "F.Paste")
			(net "P3V3")
			(options
				(clearance outline)
				(anchor circle)
			)
			(primitives
				(gr_poly
					(pts
						(arc
							(start -0.1778 -0.2794)
							(mid -0.249642 -0.249642)
							(end -0.2794 -0.1778)
						)
						(arc
							(start -0.2794 0.1778)
							(mid -0.249642 0.249642)
							(end -0.1778 0.2794)
						)
						(arc
							(start 0.1778 0.2794)
							(mid 0.249642 0.249642)
							(end 0.2794 0.1778)
						)
						(arc
							(start 0.2794 -0.1778)
							(mid 0.249642 -0.249642)
							(end 0.1778 -0.2794)
						)
					)
					(width 0)
					(fill yes)
				)
			)
		)
		(pad "2" smd custom
			(at 0 0.4445)
			(size 0.1397 0.1397)
			(layers "F.Cu" "F.Mask" "F.Paste")
			(net "ATTN_LED_DR13_MOS_N")
			(options
				(clearance outline)
				(anchor circle)
			)
			(primitives
				(gr_poly
					(pts
						(arc
							(start -0.1778 -0.2794)
							(mid -0.249642 -0.249642)
							(end -0.2794 -0.1778)
						)
						(arc
							(start -0.2794 0.1778)
							(mid -0.249642 0.249642)
							(end -0.1778 0.2794)
						)
						(arc
							(start 0.1778 0.2794)
							(mid 0.249642 0.249642)
							(end 0.2794 0.1778)
						)
						(arc
							(start 0.2794 -0.1778)
							(mid 0.249642 -0.249642)
							(end 0.1778 -0.2794)
						)
					)
					(width 0)
					(fill yes)
				)
			)
		)
	)
	(footprint ""
		(layer "F.Cu")
		(at 19.547332 -262.002778 90)
		(property "Reference" "Q90"
			(at 0 0 90)
			(layer "F.SilkS")
			(hide yes)
			(effects
				(font
					(size 1.27 1.27)
				)
			)
		)
		(property "Value" "2N7002A-7-GP"
			(at 0.127 -8.9662 90)
			(unlocked yes)
			(layer "F.Fab")
			(hide yes)
			(effects
				(font
					(size 1.016 1.016)
					(thickness 0.1524)
				)
			)
		)
		(property "Device Type" "SOT23DGS2D4H48"
			(at 0.127 -10.4902 90)
			(unlocked yes)
			(layer "F.Fab")
			(hide yes)
			(effects
				(font
					(size 1.016 1.016)
					(thickness 0.1524)
				)
			)
		)
		(duplicate_pad_numbers_are_jumpers no)
		(fp_line
			(start 1.651 -1.778)
			(end -1.651 -1.778)
			(stroke
				(width 0.1524)
				(type default)
			)
			(layer "F.SilkS")
		)
		(fp_line
			(start -1.651 -1.778)
			(end -1.651 1.778)
			(stroke
				(width 0.1524)
				(type default)
			)
			(layer "F.SilkS")
		)
		(fp_line
			(start 1.651 1.778)
			(end 1.651 -1.778)
			(stroke
				(width 0.1524)
				(type default)
			)
			(layer "F.SilkS")
		)
		(fp_line
			(start -1.651 1.778)
			(end 1.651 1.778)
			(stroke
				(width 0.1524)
				(type default)
			)
			(layer "F.SilkS")
		)
		(fp_poly
			(pts
				(xy -1.778 1.8796) (xy -1.778 -1.8796) (xy 1.778 -1.8796) (xy 1.778 1.8796)
			)
			(stroke
				(width 0)
				(type default)
			)
			(fill no)
			(layer "F.CrtYd")
		)
		(fp_poly
			(pts
				(xy -1.778 1.8796) (xy -1.778 -1.8796) (xy 1.778 -1.8796) (xy 1.778 1.8796)
			)
			(stroke
				(width 0)
				(type default)
			)
			(fill no)
			(layer "F.Fab")
		)
		(pad "D" smd custom
			(at 0 -0.9525 90)
			(size 0.1905 0.1905)
			(layers "F.Cu" "F.Mask" "F.Paste")
			(net "ATTN_LED_DR12_MOS_N")
			(options
				(clearance outline)
				(anchor circle)
			)
			(primitives
				(gr_poly
					(pts
						(arc
							(start -0.1778 0.5715)
							(mid -0.321484 0.511984)
							(end -0.381 0.3683)
						)
						(arc
							(start -0.381 -0.3683)
							(mid -0.321484 -0.511984)
							(end -0.1778 -0.5715)
						)
						(arc
							(start 0.1778 -0.5715)
							(mid 0.321484 -0.511984)
							(end 0.381 -0.3683)
						)
						(arc
							(start 0.381 0.3683)
							(mid 0.321484 0.511984)
							(end 0.1778 0.5715)
						)
					)
					(width 0)
					(fill yes)
				)
			)
		)
		(pad "G" smd custom
			(at -0.98425 0.9525 90)
			(size 0.1905 0.1905)
			(layers "F.Cu" "F.Mask" "F.Paste")
			(net "SSD12_CLK0_OE_MOS_N")
			(options
				(clearance outline)
				(anchor circle)
			)
			(primitives
				(gr_poly
					(pts
						(arc
							(start -0.1778 0.5715)
							(mid -0.321484 0.511984)
							(end -0.381 0.3683)
						)
						(arc
							(start -0.381 -0.3683)
							(mid -0.321484 -0.511984)
							(end -0.1778 -0.5715)
						)
						(arc
							(start 0.1778 -0.5715)
							(mid 0.321484 -0.511984)
							(end 0.381 -0.3683)
						)
						(arc
							(start 0.381 0.3683)
							(mid 0.321484 0.511984)
							(end 0.1778 0.5715)
						)
					)
					(width 0)
					(fill yes)
				)
			)
		)
		(pad "S" smd custom
			(at 0.98425 0.9525 90)
			(size 0.1905 0.1905)
			(layers "F.Cu" "F.Mask" "F.Paste")
			(net "ATTN_LED_DR12_R")
			(options
				(clearance outline)
				(anchor circle)
			)
			(primitives
				(gr_poly
					(pts
						(arc
							(start -0.1778 0.5715)
							(mid -0.321484 0.511984)
							(end -0.381 0.3683)
						)
						(arc
							(start -0.381 -0.3683)
							(mid -0.321484 -0.511984)
							(end -0.1778 -0.5715)
						)
						(arc
							(start 0.1778 -0.5715)
							(mid 0.321484 -0.511984)
							(end 0.381 -0.3683)
						)
						(arc
							(start 0.381 0.3683)
							(mid 0.321484 0.511984)
							(end 0.1778 0.5715)
						)
					)
					(width 0)
					(fill yes)
				)
			)
		)
	)
	(footprint ""
		(layer "F.Cu")
		(at 84.455 -96.774 90)
		(property "Reference" "R425"
			(at 0 0 90)
			(layer "F.SilkS")
			(hide yes)
			(effects
				(font
					(size 1.27 1.27)
				)
			)
		)
		(property "Value" "0R2J-2-GP"
			(at 0.064008 -3.993896 90)
			(unlocked yes)
			(layer "F.Fab")
			(hide yes)
			(effects
				(font
					(size 1.016 1.016)
					(thickness 0.1524)
				)
			)
		)
		(property "Device Type" "R402H16"
			(at 0.064008 -5.517896 90)
			(unlocked yes)
			(layer "F.Fab")
			(hide yes)
			(effects
				(font
					(size 1.016 1.016)
					(thickness 0.1524)
				)
			)
		)
		(duplicate_pad_numbers_are_jumpers no)
		(fp_line
			(start 0.508 -0.9398)
			(end -0.508 -0.9398)
			(stroke
				(width 0.1524)
				(type default)
			)
			(layer "F.SilkS")
		)
		(fp_line
			(start -0.508 -0.9398)
			(end -0.508 0.9398)
			(stroke
				(width 0.1524)
				(type default)
			)
			(layer "F.SilkS")
		)
		(fp_rect
			(start -0.508 0.9398)
			(end 0.508 -0.9398)
			(stroke
				(width 0)
				(type default)
			)
			(fill no)
			(layer "F.CrtYd")
		)
		(fp_rect
			(start -0.508 0.9398)
			(end 0.508 -0.9398)
			(stroke
				(width 0)
				(type default)
			)
			(fill no)
			(layer "F.Fab")
		)
		(pad "1" smd custom
			(at 0 -0.4445 90)
			(size 0.1397 0.1397)
			(layers "F.Cu" "F.Mask" "F.Paste")
			(net "BMC_I2C_SCL_BUF_8")
			(options
				(clearance outline)
				(anchor circle)
			)
			(primitives
				(gr_poly
					(pts
						(arc
							(start -0.1778 -0.2794)
							(mid -0.249642 -0.249642)
							(end -0.2794 -0.1778)
						)
						(arc
							(start -0.2794 0.1778)
							(mid -0.249642 0.249642)
							(end -0.1778 0.2794)
						)
						(arc
							(start 0.1778 0.2794)
							(mid 0.249642 0.249642)
							(end 0.2794 0.1778)
						)
						(arc
							(start 0.2794 -0.1778)
							(mid 0.249642 -0.249642)
							(end 0.1778 -0.2794)
						)
					)
					(width 0)
					(fill yes)
				)
			)
		)
		(pad "2" smd custom
			(at 0 0.4445 90)
			(size 0.1397 0.1397)
			(layers "F.Cu" "F.Mask" "F.Paste")
			(net "I2C_SCL_BUF_8_EU4_R")
			(options
				(clearance outline)
				(anchor circle)
			)
			(primitives
				(gr_poly
					(pts
						(arc
							(start -0.1778 -0.2794)
							(mid -0.249642 -0.249642)
							(end -0.2794 -0.1778)
						)
						(arc
							(start -0.2794 0.1778)
							(mid -0.249642 0.249642)
							(end -0.1778 0.2794)
						)
						(arc
							(start 0.1778 0.2794)
							(mid 0.249642 0.249642)
							(end 0.2794 0.1778)
						)
						(arc
							(start 0.2794 -0.1778)
							(mid 0.249642 -0.249642)
							(end 0.1778 -0.2794)
						)
					)
					(width 0)
					(fill yes)
				)
			)
		)
	)
	(footprint ""
		(layer "F.Cu")
		(at 43.50004 -144.100042)
		(property "Reference" "LED8"
			(at 0 0 0)
			(layer "F.SilkS")
			(hide yes)
			(effects
				(font
					(size 1.27 1.27)
				)
			)
		)
		(property "Value" "LED-RB-4-GP"
			(at 5.88899 1.80848 0)
			(unlocked yes)
			(layer "F.Fab")
			(hide yes)
			(effects
				(font
					(size 1.016 1.016)
					(thickness 0.1524)
				)
			)
		)
		(property "Device Type" "LED1613-4PH20"
			(at 5.88899 0.28448 0)
			(unlocked yes)
			(layer "F.Fab")
			(hide yes)
			(effects
				(font
					(size 1.016 1.016)
					(thickness 0.1524)
				)
			)
		)
		(duplicate_pad_numbers_are_jumpers no)
		(fp_line
			(start -1.4478 -0.9652)
			(end 1.4478 -0.9652)
			(stroke
				(width 0.1524)
				(type default)
			)
			(layer "F.SilkS")
		)
		(fp_line
			(start -1.4478 0.9652)
			(end -1.4478 -0.9652)
			(stroke
				(width 0.1524)
				(type default)
			)
			(layer "F.SilkS")
		)
		(fp_line
			(start -1.4478 0.9652)
			(end -1.4478 -0.9652)
			(stroke
				(width 0.508)
				(type default)
			)
			(layer "F.SilkS")
		)
		(fp_line
			(start 1.4478 -0.9652)
			(end 1.4478 0.9652)
			(stroke
				(width 0.1524)
				(type default)
			)
			(layer "F.SilkS")
		)
		(fp_line
			(start 1.4478 0.9652)
			(end -1.4478 0.9652)
			(stroke
				(width 0.1524)
				(type default)
			)
			(layer "F.SilkS")
		)
		(fp_rect
			(start -0.8001 0.6477)
			(end 0.8001 -0.6477)
			(stroke
				(width 0)
				(type default)
			)
			(fill no)
			(layer "F.CrtYd")
		)
		(fp_poly
			(pts
				(xy -1.7018 1.2192) (xy -1.7018 -0.06223) (xy -0.8001 -0.06223) (xy -0.8001 0.6477) (xy 0.8001 0.6477)
				(xy 0.8001 -0.6477) (xy -0.8001 -0.6477) (xy -0.8001 -0.0635) (xy -1.7018 -0.0635) (xy -1.7018 -1.2192)
				(xy 1.7018 -1.2192) (xy 1.7018 1.2192)
			)
			(stroke
				(width 0)
				(type default)
			)
			(fill no)
			(layer "F.CrtYd")
		)
		(fp_rect
			(start -1.7018 1.2192)
			(end 1.7018 -1.2192)
			(stroke
				(width 0)
				(type default)
			)
			(fill no)
			(layer "F.Fab")
		)
		(pad "1" smd rect
			(at -0.73025 0.4064)
			(size 0.9144 0.6096)
			(layers "F.Cu" "F.Mask" "F.Paste")
			(net "SSD_ACT_DR8_MOS_N")
		)
		(pad "2" smd rect
			(at -0.73025 -0.4064)
			(size 0.9144 0.6096)
			(layers "F.Cu" "F.Mask" "F.Paste")
			(net "ATTN_LED_DR8_MOS_N")
		)
		(pad "3" smd rect
			(at 0.73025 -0.4064)
			(size 0.9144 0.6096)
			(layers "F.Cu" "F.Mask" "F.Paste")
			(net "DRV_ATTN_8")
		)
		(pad "4" smd rect
			(at 0.73025 0.4064)
			(size 0.9144 0.6096)
			(layers "F.Cu" "F.Mask" "F.Paste")
			(net "DRV_ACT_8")
		)
	)
	(footprint ""
		(layer "F.Cu")
		(at 37.973 -411.734 180)
		(property "Reference" "R9770"
			(at 0 0 180)
			(layer "F.SilkS")
			(hide yes)
			(effects
				(font
					(size 1.27 1.27)
				)
			)
		)
		(property "Value" "4K7R2J-2-GP"
			(at 0.064008 -3.993896 180)
			(unlocked yes)
			(layer "F.Fab")
			(hide yes)
			(effects
				(font
					(size 1.016 1.016)
					(thickness 0.1524)
				)
			)
		)
		(property "Device Type" "R402H16"
			(at 0.064008 -5.517896 180)
			(unlocked yes)
			(layer "F.Fab")
			(hide yes)
			(effects
				(font
					(size 1.016 1.016)
					(thickness 0.1524)
				)
			)
		)
		(duplicate_pad_numbers_are_jumpers no)
		(fp_line
			(start 0.508 -0.9398)
			(end -0.508 -0.9398)
			(stroke
				(width 0.1524)
				(type default)
			)
			(layer "F.SilkS")
		)
		(fp_line
			(start -0.508 -0.9398)
			(end -0.508 0.9398)
			(stroke
				(width 0.1524)
				(type default)
			)
			(layer "F.SilkS")
		)
		(fp_rect
			(start -0.508 0.9398)
			(end 0.508 -0.9398)
			(stroke
				(width 0)
				(type default)
			)
			(fill no)
			(layer "F.CrtYd")
		)
		(fp_rect
			(start -0.508 0.9398)
			(end 0.508 -0.9398)
			(stroke
				(width 0)
				(type default)
			)
			(fill no)
			(layer "F.Fab")
		)
		(pad "1" smd custom
			(at 0 -0.4445 180)
			(size 0.1397 0.1397)
			(layers "F.Cu" "F.Mask" "F.Paste")
			(net "SSD10_PWREN")
			(options
				(clearance outline)
				(anchor circle)
			)
			(primitives
				(gr_poly
					(pts
						(arc
							(start -0.1778 -0.2794)
							(mid -0.249642 -0.249642)
							(end -0.2794 -0.1778)
						)
						(arc
							(start -0.2794 0.1778)
							(mid -0.249642 0.249642)
							(end -0.1778 0.2794)
						)
						(arc
							(start 0.1778 0.2794)
							(mid 0.249642 0.249642)
							(end 0.2794 0.1778)
						)
						(arc
							(start 0.2794 -0.1778)
							(mid 0.249642 -0.249642)
							(end 0.1778 -0.2794)
						)
					)
					(width 0)
					(fill yes)
				)
			)
		)
		(pad "2" smd custom
			(at 0 0.4445 180)
			(size 0.1397 0.1397)
			(layers "F.Cu" "F.Mask" "F.Paste")
			(net "GND")
			(options
				(clearance outline)
				(anchor circle)
			)
			(primitives
				(gr_poly
					(pts
						(arc
							(start -0.1778 -0.2794)
							(mid -0.249642 -0.249642)
							(end -0.2794 -0.1778)
						)
						(arc
							(start -0.2794 0.1778)
							(mid -0.249642 0.249642)
							(end -0.1778 0.2794)
						)
						(arc
							(start 0.1778 0.2794)
							(mid 0.249642 0.249642)
							(end 0.2794 0.1778)
						)
						(arc
							(start 0.2794 -0.1778)
							(mid 0.249642 -0.249642)
							(end 0.1778 -0.2794)
						)
					)
					(width 0)
					(fill yes)
				)
			)
		)
	)
	(footprint ""
		(layer "F.Cu")
		(at 253.499874 -174.497492)
		(property "Reference" "H8"
			(at 0 0 0)
			(layer "F.SilkS")
			(hide yes)
			(effects
				(font
					(size 1.27 1.27)
				)
			)
		)
		(property "Value" "GEN276X162R197X296-6-F-A-GP"
			(at -6.7183 4.1402 0)
			(unlocked yes)
			(layer "F.Fab")
			(hide yes)
			(effects
				(font
					(size 1.016 1.016)
					(thickness 0.1524)
				)
			)
		)
		(property "Device Type" "GEN276X162R197X296-6-F-A"
			(at -6.7183 2.6162 0)
			(unlocked yes)
			(layer "F.Fab")
			(hide yes)
			(effects
				(font
					(size 1.016 1.016)
					(thickness 0.1524)
				)
			)
		)
		(duplicate_pad_numbers_are_jumpers no)
		(fp_poly
			(pts
				(arc
					(start 2.723642 4.777232)
					(mid -0.000169 6.508462)
					(end -2.723896 4.776978)
				)
				(arc
					(start -2.723896 4.776978)
					(mid 0.000173 -5.499012)
					(end 2.723642 4.777232)
				)
			)
			(stroke
				(width 0)
				(type default)
			)
			(fill no)
			(layer "B.CrtYd")
		)
		(fp_poly
			(pts
				(arc
					(start 2.723642 4.777232)
					(mid -0.000169 6.508462)
					(end -2.723896 4.776978)
				)
				(arc
					(start -2.723896 4.776978)
					(mid 0.000173 -5.499012)
					(end 2.723642 4.777232)
				)
			)
			(stroke
				(width 0)
				(type default)
			)
			(fill no)
			(layer "F.CrtYd")
		)
		(fp_poly
			(pts
				(arc
					(start 2.723642 4.777232)
					(mid -0.000169 6.508462)
					(end -2.723896 4.776978)
				)
				(arc
					(start -2.723896 4.776978)
					(mid 0.000173 -5.499012)
					(end 2.723642 4.777232)
				)
			)
			(stroke
				(width 0)
				(type default)
			)
			(fill no)
			(layer "B.Fab")
		)
		(fp_poly
			(pts
				(arc
					(start 2.723642 4.777232)
					(mid -0.000169 6.508462)
					(end -2.723896 4.776978)
				)
				(arc
					(start -2.723896 4.776978)
					(mid 0.000173 -5.499012)
					(end 2.723642 4.777232)
				)
			)
			(stroke
				(width 0)
				(type default)
			)
			(fill no)
			(layer "F.Fab")
		)
		(pad "" np_thru_hole circle
			(at 0 0)
			(size 0.254 0.254)
			(drill 0.0254)
			(layers "*.Cu" "*.Mask")
			(clearance 3.135376)
			(thermal_gap 3.135376)
		)
		(pad "1" thru_hole circle
			(at 2.549906 0)
			(size 0.8636 0.8636)
			(drill 0.508)
			(layers "*.Cu" "*.Mask")
			(remove_unused_layers no)
			(net "GND")
			(clearance 0.8255)
			(thermal_gap 0.8255)
		)
		(pad "2" thru_hole circle
			(at 2.210054 -1.27)
			(size 0.8636 0.8636)
			(drill 0.508)
			(layers "*.Cu" "*.Mask")
			(remove_unused_layers no)
			(net "GND")
			(clearance 0.8255)
			(thermal_gap 0.8255)
		)
		(pad "3" thru_hole circle
			(at 1.27 -2.210054)
			(size 0.8636 0.8636)
			(drill 0.508)
			(layers "*.Cu" "*.Mask")
			(remove_unused_layers no)
			(net "GND")
			(clearance 0.8255)
			(thermal_gap 0.8255)
		)
		(pad "4" thru_hole circle
			(at -1.279906 -2.210054)
			(size 0.8636 0.8636)
			(drill 0.508)
			(layers "*.Cu" "*.Mask")
			(remove_unused_layers no)
			(net "GND")
			(clearance 0.8255)
			(thermal_gap 0.8255)
		)
		(pad "5" thru_hole circle
			(at -2.210054 -1.27)
			(size 0.8636 0.8636)
			(drill 0.508)
			(layers "*.Cu" "*.Mask")
			(remove_unused_layers no)
			(net "GND")
			(clearance 0.8255)
			(thermal_gap 0.8255)
		)
		(pad "6" thru_hole circle
			(at -2.549906 0)
			(size 0.8636 0.8636)
			(drill 0.508)
			(layers "*.Cu" "*.Mask")
			(remove_unused_layers no)
			(net "GND")
			(clearance 0.8255)
			(thermal_gap 0.8255)
		)
		(zone
			(layers "F.Cu" "B.Cu" "In1.Cu" "In2.Cu" "In3.Cu" "In4.Cu" "In5.Cu" "In6.Cu")
			(hatch none 0.5)
			(connect_pads
				(clearance 0)
			)
			(min_thickness 0.25)
			(keepout
				(tracks allowed)
				(vias not_allowed)
				(pads allowed)
				(copperpour not_allowed)
				(footprints allowed)
			)
			(placement
				(enabled no)
				(sheetname "")
			)
			(fill
				(thermal_gap 0.5)
				(thermal_bridge_width 0.5)
				(island_removal_mode 0)
			)
			(polygon
				(pts
					(arc
						(start 257.817874 -174.50054)
						(mid 249.181874 -174.50054)
						(end 257.817874 -174.50054)
					)
				)
			)
		)
		(zone
			(layers "F.Cu" "B.Cu" "In1.Cu" "In2.Cu" "In3.Cu" "In4.Cu" "In5.Cu" "In6.Cu")
			(hatch none 0.5)
			(connect_pads
				(clearance 0)
			)
			(min_thickness 0.25)
			(keepout
				(tracks not_allowed)
				(vias allowed)
				(pads allowed)
				(copperpour not_allowed)
				(footprints allowed)
			)
			(placement
				(enabled no)
				(sheetname "")
			)
			(fill
				(thermal_gap 0.5)
				(thermal_bridge_width 0.5)
				(island_removal_mode 0)
			)
			(polygon
				(pts
					(arc
						(start 255.839214 -172.888148)
						(mid 253.499954 -167.989045)
						(end 251.16028 -172.888148)
					)
					(arc
						(start 251.16028 -172.888148)
						(mid 251.406247 -173.328514)
						(end 251.491496 -173.825662)
					)
					(arc
						(start 251.491496 -174.497492)
						(mid 253.499874 -176.50587)
						(end 255.507998 -174.497492)
					)
					(arc
						(start 255.507998 -173.825662)
						(mid 255.593233 -173.328508)
						(end 255.839214 -172.888148)
					)
				)
			)
		)
	)
	(footprint ""
		(layer "F.Cu")
		(at 200.365106 -495.174778 180)
		(property "Reference" "Q8"
			(at 0 0 180)
			(layer "F.SilkS")
			(hide yes)
			(effects
				(font
					(size 1.27 1.27)
				)
			)
		)
		(property "Value" "2N7002A-7-GP"
			(at 0.127 -8.9662 180)
			(unlocked yes)
			(layer "F.Fab")
			(hide yes)
			(effects
				(font
					(size 1.016 1.016)
					(thickness 0.1524)
				)
			)
		)
		(property "Device Type" "SOT23DGS2D4H48"
			(at 0.127 -10.4902 180)
			(unlocked yes)
			(layer "F.Fab")
			(hide yes)
			(effects
				(font
					(size 1.016 1.016)
					(thickness 0.1524)
				)
			)
		)
		(duplicate_pad_numbers_are_jumpers no)
		(fp_line
			(start 1.651 1.778)
			(end 1.651 -1.778)
			(stroke
				(width 0.1524)
				(type default)
			)
			(layer "F.SilkS")
		)
		(fp_line
			(start 1.651 -1.778)
			(end -1.651 -1.778)
			(stroke
				(width 0.1524)
				(type default)
			)
			(layer "F.SilkS")
		)
		(fp_line
			(start -1.651 1.778)
			(end 1.651 1.778)
			(stroke
				(width 0.1524)
				(type default)
			)
			(layer "F.SilkS")
		)
		(fp_line
			(start -1.651 -1.778)
			(end -1.651 1.778)
			(stroke
				(width 0.1524)
				(type default)
			)
			(layer "F.SilkS")
		)
		(fp_poly
			(pts
				(xy -1.778 1.8796) (xy -1.778 -1.8796) (xy 1.778 -1.8796) (xy 1.778 1.8796)
			)
			(stroke
				(width 0)
				(type default)
			)
			(fill no)
			(layer "F.CrtYd")
		)
		(fp_poly
			(pts
				(xy -1.778 1.8796) (xy -1.778 -1.8796) (xy 1.778 -1.8796) (xy 1.778 1.8796)
			)
			(stroke
				(width 0)
				(type default)
			)
			(fill no)
			(layer "F.Fab")
		)
		(pad "D" smd custom
			(at 0 -0.9525 180)
			(size 0.1905 0.1905)
			(layers "F.Cu" "F.Mask" "F.Paste")
			(net "SW_SSD0_R")
			(options
				(clearance outline)
				(anchor circle)
			)
			(primitives
				(gr_poly
					(pts
						(arc
							(start -0.1778 0.5715)
							(mid -0.321484 0.511984)
							(end -0.381 0.3683)
						)
						(arc
							(start -0.381 -0.3683)
							(mid -0.321484 -0.511984)
							(end -0.1778 -0.5715)
						)
						(arc
							(start 0.1778 -0.5715)
							(mid 0.321484 -0.511984)
							(end 0.381 -0.3683)
						)
						(arc
							(start 0.381 0.3683)
							(mid 0.321484 0.511984)
							(end 0.1778 0.5715)
						)
					)
					(width 0)
					(fill yes)
				)
			)
		)
		(pad "G" smd custom
			(at -0.98425 0.9525 180)
			(size 0.1905 0.1905)
			(layers "F.Cu" "F.Mask" "F.Paste")
			(net "SSD0_PWREN")
			(options
				(clearance outline)
				(anchor circle)
			)
			(primitives
				(gr_poly
					(pts
						(arc
							(start -0.1778 0.5715)
							(mid -0.321484 0.511984)
							(end -0.381 0.3683)
						)
						(arc
							(start -0.381 -0.3683)
							(mid -0.321484 -0.511984)
							(end -0.1778 -0.5715)
						)
						(arc
							(start 0.1778 -0.5715)
							(mid 0.321484 -0.511984)
							(end 0.381 -0.3683)
						)
						(arc
							(start 0.381 0.3683)
							(mid 0.321484 0.511984)
							(end 0.1778 0.5715)
						)
					)
					(width 0)
					(fill yes)
				)
			)
		)
		(pad "S" smd custom
			(at 0.98425 0.9525 180)
			(size 0.1905 0.1905)
			(layers "F.Cu" "F.Mask" "F.Paste")
			(net "GND")
			(options
				(clearance outline)
				(anchor circle)
			)
			(primitives
				(gr_poly
					(pts
						(arc
							(start -0.1778 0.5715)
							(mid -0.321484 0.511984)
							(end -0.381 0.3683)
						)
						(arc
							(start -0.381 -0.3683)
							(mid -0.321484 -0.511984)
							(end -0.1778 -0.5715)
						)
						(arc
							(start 0.1778 -0.5715)
							(mid 0.321484 -0.511984)
							(end 0.381 -0.3683)
						)
						(arc
							(start 0.381 0.3683)
							(mid 0.321484 0.511984)
							(end 0.1778 0.5715)
						)
					)
					(width 0)
					(fill yes)
				)
			)
		)
	)
	(footprint ""
		(layer "F.Cu")
		(at 221.615 -268.351 180)
		(property "Reference" "PC1194"
			(at 0 0 180)
			(layer "F.SilkS")
			(hide yes)
			(effects
				(font
					(size 1.27 1.27)
				)
			)
		)
		(property "Value" "SCD1U25V3KX-GP"
			(at 0 -2.8194 180)
			(unlocked yes)
			(layer "F.Fab")
			(hide yes)
			(effects
				(font
					(size 1.016 1.016)
					(thickness 0.1524)
				)
			)
		)
		(property "Device Type" "C603H36"
			(at 0 -4.3434 180)
			(unlocked yes)
			(layer "F.Fab")
			(hide yes)
			(effects
				(font
					(size 1.016 1.016)
					(thickness 0.1524)
				)
			)
		)
		(duplicate_pad_numbers_are_jumpers no)
		(fp_line
			(start 0.508 0)
			(end -0.508 0)
			(stroke
				(width 0.2032)
				(type default)
			)
			(layer "F.SilkS")
		)
		(fp_rect
			(start -0.5842 1.3335)
			(end 0.5842 -1.3335)
			(stroke
				(width 0)
				(type default)
			)
			(fill no)
			(layer "F.CrtYd")
		)
		(fp_rect
			(start -0.5842 1.3335)
			(end 0.5842 -1.3335)
			(stroke
				(width 0)
				(type default)
			)
			(fill no)
			(layer "F.Fab")
		)
		(pad "1" smd custom
			(at 0 -0.762 180)
			(size 0.2159 0.2159)
			(layers "F.Cu" "F.Mask" "F.Paste")
			(net "P3V3")
			(options
				(clearance outline)
				(anchor circle)
			)
			(primitives
				(gr_poly
					(pts
						(arc
							(start -0.3302 -0.4318)
							(mid -0.402042 -0.402042)
							(end -0.4318 -0.3302)
						)
						(arc
							(start -0.4318 0.3302)
							(mid -0.402042 0.402042)
							(end -0.3302 0.4318)
						)
						(arc
							(start 0.3302 0.4318)
							(mid 0.402042 0.402042)
							(end 0.4318 0.3302)
						)
						(arc
							(start 0.4318 -0.3302)
							(mid 0.402042 -0.402042)
							(end 0.3302 -0.4318)
						)
					)
					(width 0)
					(fill yes)
				)
			)
		)
		(pad "2" smd custom
			(at 0 0.762 180)
			(size 0.2159 0.2159)
			(layers "F.Cu" "F.Mask" "F.Paste")
			(net "GND")
			(options
				(clearance outline)
				(anchor circle)
			)
			(primitives
				(gr_poly
					(pts
						(arc
							(start -0.3302 -0.4318)
							(mid -0.402042 -0.402042)
							(end -0.4318 -0.3302)
						)
						(arc
							(start -0.4318 0.3302)
							(mid -0.402042 0.402042)
							(end -0.3302 0.4318)
						)
						(arc
							(start 0.3302 0.4318)
							(mid 0.402042 0.402042)
							(end 0.4318 0.3302)
						)
						(arc
							(start 0.4318 -0.3302)
							(mid 0.402042 -0.402042)
							(end 0.3302 -0.4318)
						)
					)
					(width 0)
					(fill yes)
				)
			)
		)
	)
	(footprint ""
		(layer "F.Cu")
		(at 42.92473 -142.345664 90)
		(property "Reference" "R9944"
			(at 0 0 90)
			(layer "F.SilkS")
			(hide yes)
			(effects
				(font
					(size 1.27 1.27)
				)
			)
		)
		(property "Value" "4K7R2J-2-GP"
			(at 0.064008 -3.993896 90)
			(unlocked yes)
			(layer "F.Fab")
			(hide yes)
			(effects
				(font
					(size 1.016 1.016)
					(thickness 0.1524)
				)
			)
		)
		(property "Device Type" "R402H16"
			(at 0.064008 -5.517896 90)
			(unlocked yes)
			(layer "F.Fab")
			(hide yes)
			(effects
				(font
					(size 1.016 1.016)
					(thickness 0.1524)
				)
			)
		)
		(duplicate_pad_numbers_are_jumpers no)
		(fp_line
			(start 0.508 -0.9398)
			(end -0.508 -0.9398)
			(stroke
				(width 0.1524)
				(type default)
			)
			(layer "F.SilkS")
		)
		(fp_line
			(start -0.508 -0.9398)
			(end -0.508 0.9398)
			(stroke
				(width 0.1524)
				(type default)
			)
			(layer "F.SilkS")
		)
		(fp_rect
			(start -0.508 0.9398)
			(end 0.508 -0.9398)
			(stroke
				(width 0)
				(type default)
			)
			(fill no)
			(layer "F.CrtYd")
		)
		(fp_rect
			(start -0.508 0.9398)
			(end 0.508 -0.9398)
			(stroke
				(width 0)
				(type default)
			)
			(fill no)
			(layer "F.Fab")
		)
		(pad "1" smd custom
			(at 0 -0.4445 90)
			(size 0.1397 0.1397)
			(layers "F.Cu" "F.Mask" "F.Paste")
			(net "P3V3")
			(options
				(clearance outline)
				(anchor circle)
			)
			(primitives
				(gr_poly
					(pts
						(arc
							(start -0.1778 -0.2794)
							(mid -0.249642 -0.249642)
							(end -0.2794 -0.1778)
						)
						(arc
							(start -0.2794 0.1778)
							(mid -0.249642 0.249642)
							(end -0.1778 0.2794)
						)
						(arc
							(start 0.1778 0.2794)
							(mid 0.249642 0.249642)
							(end 0.2794 0.1778)
						)
						(arc
							(start 0.2794 -0.1778)
							(mid 0.249642 -0.249642)
							(end 0.1778 -0.2794)
						)
					)
					(width 0)
					(fill yes)
				)
			)
		)
		(pad "2" smd custom
			(at 0 0.4445 90)
			(size 0.1397 0.1397)
			(layers "F.Cu" "F.Mask" "F.Paste")
			(net "SSD_ACT_DR8_MOS_N")
			(options
				(clearance outline)
				(anchor circle)
			)
			(primitives
				(gr_poly
					(pts
						(arc
							(start -0.1778 -0.2794)
							(mid -0.249642 -0.249642)
							(end -0.2794 -0.1778)
						)
						(arc
							(start -0.2794 0.1778)
							(mid -0.249642 0.249642)
							(end -0.1778 0.2794)
						)
						(arc
							(start 0.1778 0.2794)
							(mid 0.249642 0.249642)
							(end 0.2794 0.1778)
						)
						(arc
							(start 0.2794 -0.1778)
							(mid 0.249642 -0.249642)
							(end 0.1778 -0.2794)
						)
					)
					(width 0)
					(fill yes)
				)
			)
		)
	)
	(footprint ""
		(layer "F.Cu")
		(at 97.028 -293.116 90)
		(property "Reference" "C939"
			(at 0 0 90)
			(layer "F.SilkS")
			(hide yes)
			(effects
				(font
					(size 1.27 1.27)
				)
			)
		)
		(property "Value" "SC1KP50V2KX-1GP"
			(at 1.1811 -2.7051 90)
			(unlocked yes)
			(layer "F.Fab")
			(hide yes)
			(effects
				(font
					(size 1.016 1.016)
					(thickness 0.1524)
				)
			)
		)
		(property "Device Type" "C402H22"
			(at 1.1811 -4.2291 90)
			(unlocked yes)
			(layer "F.Fab")
			(hide yes)
			(effects
				(font
					(size 1.016 1.016)
					(thickness 0.1524)
				)
			)
		)
		(duplicate_pad_numbers_are_jumpers no)
		(fp_rect
			(start -0.4318 0.9525)
			(end 0.4318 -0.9525)
			(stroke
				(width 0)
				(type default)
			)
			(fill no)
			(layer "F.CrtYd")
		)
		(fp_rect
			(start -0.4318 0.9525)
			(end 0.4318 -0.9525)
			(stroke
				(width 0)
				(type default)
			)
			(fill no)
			(layer "F.Fab")
		)
		(pad "1" smd custom
			(at 0 -0.4445 90)
			(size 0.1524 0.1524)
			(layers "F.Cu" "F.Mask" "F.Paste")
			(net "SSD_PRSNT2")
			(options
				(clearance outline)
				(anchor circle)
			)
			(primitives
				(gr_poly
					(pts
						(arc
							(start 0.3048 -0.2032)
							(mid 0.275042 -0.275042)
							(end 0.2032 -0.3048)
						)
						(arc
							(start -0.2032 -0.3048)
							(mid -0.275042 -0.275042)
							(end -0.3048 -0.2032)
						)
						(arc
							(start -0.3048 0.2032)
							(mid -0.275042 0.275042)
							(end -0.2032 0.3048)
						)
						(arc
							(start 0.2032 0.3048)
							(mid 0.275042 0.275042)
							(end 0.3048 0.2032)
						)
					)
					(width 0)
					(fill yes)
				)
			)
		)
		(pad "2" smd custom
			(at 0 0.4445 90)
			(size 0.1524 0.1524)
			(layers "F.Cu" "F.Mask" "F.Paste")
			(net "GND")
			(options
				(clearance outline)
				(anchor circle)
			)
			(primitives
				(gr_poly
					(pts
						(arc
							(start 0.3048 -0.2032)
							(mid 0.275042 -0.275042)
							(end 0.2032 -0.3048)
						)
						(arc
							(start -0.2032 -0.3048)
							(mid -0.275042 -0.275042)
							(end -0.3048 -0.2032)
						)
						(arc
							(start -0.3048 0.2032)
							(mid -0.275042 0.275042)
							(end -0.2032 0.3048)
						)
						(arc
							(start 0.2032 0.3048)
							(mid 0.275042 0.275042)
							(end 0.3048 0.2032)
						)
					)
					(width 0)
					(fill yes)
				)
			)
		)
	)
	(footprint ""
		(layer "F.Cu")
		(at 21.017992 -370.877592 180)
		(property "Reference" "C9529"
			(at 0 0 180)
			(layer "F.SilkS")
			(hide yes)
			(effects
				(font
					(size 1.27 1.27)
				)
			)
		)
		(property "Value" "SCD1U16V2KX-3GP"
			(at 1.1811 -2.7051 180)
			(unlocked yes)
			(layer "F.Fab")
			(hide yes)
			(effects
				(font
					(size 1.016 1.016)
					(thickness 0.1524)
				)
			)
		)
		(property "Device Type" "C402H22"
			(at 1.1811 -4.2291 180)
			(unlocked yes)
			(layer "F.Fab")
			(hide yes)
			(effects
				(font
					(size 1.016 1.016)
					(thickness 0.1524)
				)
			)
		)
		(duplicate_pad_numbers_are_jumpers no)
		(fp_rect
			(start -0.4318 0.9525)
			(end 0.4318 -0.9525)
			(stroke
				(width 0)
				(type default)
			)
			(fill no)
			(layer "F.CrtYd")
		)
		(fp_rect
			(start -0.4318 0.9525)
			(end 0.4318 -0.9525)
			(stroke
				(width 0)
				(type default)
			)
			(fill no)
			(layer "F.Fab")
		)
		(pad "1" smd custom
			(at 0 -0.4445 180)
			(size 0.1524 0.1524)
			(layers "F.Cu" "F.Mask" "F.Paste")
			(net "P3V3")
			(options
				(clearance outline)
				(anchor circle)
			)
			(primitives
				(gr_poly
					(pts
						(arc
							(start 0.3048 -0.2032)
							(mid 0.275042 -0.275042)
							(end 0.2032 -0.3048)
						)
						(arc
							(start -0.2032 -0.3048)
							(mid -0.275042 -0.275042)
							(end -0.3048 -0.2032)
						)
						(arc
							(start -0.3048 0.2032)
							(mid -0.275042 0.275042)
							(end -0.2032 0.3048)
						)
						(arc
							(start 0.2032 0.3048)
							(mid 0.275042 0.275042)
							(end 0.3048 0.2032)
						)
					)
					(width 0)
					(fill yes)
				)
			)
		)
		(pad "2" smd custom
			(at 0 0.4445 180)
			(size 0.1524 0.1524)
			(layers "F.Cu" "F.Mask" "F.Paste")
			(net "GND")
			(options
				(clearance outline)
				(anchor circle)
			)
			(primitives
				(gr_poly
					(pts
						(arc
							(start 0.3048 -0.2032)
							(mid 0.275042 -0.275042)
							(end 0.2032 -0.3048)
						)
						(arc
							(start -0.2032 -0.3048)
							(mid -0.275042 -0.275042)
							(end -0.3048 -0.2032)
						)
						(arc
							(start -0.3048 0.2032)
							(mid -0.275042 0.275042)
							(end -0.2032 0.3048)
						)
						(arc
							(start 0.2032 0.3048)
							(mid 0.275042 0.275042)
							(end 0.3048 0.2032)
						)
					)
					(width 0)
					(fill yes)
				)
			)
		)
	)
	(footprint ""
		(layer "F.Cu")
		(at 38.9128 -315.8744 180)
		(property "Reference" "R562"
			(at 0 0 180)
			(layer "F.SilkS")
			(hide yes)
			(effects
				(font
					(size 1.27 1.27)
				)
			)
		)
		(property "Value" "200KR2F-L-GP"
			(at 0.064008 -3.993896 180)
			(unlocked yes)
			(layer "F.Fab")
			(hide yes)
			(effects
				(font
					(size 1.016 1.016)
					(thickness 0.1524)
				)
			)
		)
		(property "Device Type" "R402H16"
			(at 0.064008 -5.517896 180)
			(unlocked yes)
			(layer "F.Fab")
			(hide yes)
			(effects
				(font
					(size 1.016 1.016)
					(thickness 0.1524)
				)
			)
		)
		(duplicate_pad_numbers_are_jumpers no)
		(fp_line
			(start 0.508 -0.9398)
			(end -0.508 -0.9398)
			(stroke
				(width 0.1524)
				(type default)
			)
			(layer "F.SilkS")
		)
		(fp_line
			(start -0.508 -0.9398)
			(end -0.508 0.9398)
			(stroke
				(width 0.1524)
				(type default)
			)
			(layer "F.SilkS")
		)
		(fp_rect
			(start -0.508 0.9398)
			(end 0.508 -0.9398)
			(stroke
				(width 0)
				(type default)
			)
			(fill no)
			(layer "F.CrtYd")
		)
		(fp_rect
			(start -0.508 0.9398)
			(end 0.508 -0.9398)
			(stroke
				(width 0)
				(type default)
			)
			(fill no)
			(layer "F.Fab")
		)
		(pad "1" smd custom
			(at 0 -0.4445 180)
			(size 0.1397 0.1397)
			(layers "F.Cu" "F.Mask" "F.Paste")
			(net "SW_SSD11_R")
			(options
				(clearance outline)
				(anchor circle)
			)
			(primitives
				(gr_poly
					(pts
						(arc
							(start -0.1778 -0.2794)
							(mid -0.249642 -0.249642)
							(end -0.2794 -0.1778)
						)
						(arc
							(start -0.2794 0.1778)
							(mid -0.249642 0.249642)
							(end -0.1778 0.2794)
						)
						(arc
							(start 0.1778 0.2794)
							(mid 0.249642 0.249642)
							(end 0.2794 0.1778)
						)
						(arc
							(start 0.2794 -0.1778)
							(mid 0.249642 -0.249642)
							(end 0.1778 -0.2794)
						)
					)
					(width 0)
					(fill yes)
				)
			)
		)
		(pad "2" smd custom
			(at 0 0.4445 180)
			(size 0.1397 0.1397)
			(layers "F.Cu" "F.Mask" "F.Paste")
			(net "SW_SSD11_N")
			(options
				(clearance outline)
				(anchor circle)
			)
			(primitives
				(gr_poly
					(pts
						(arc
							(start -0.1778 -0.2794)
							(mid -0.249642 -0.249642)
							(end -0.2794 -0.1778)
						)
						(arc
							(start -0.2794 0.1778)
							(mid -0.249642 0.249642)
							(end -0.1778 0.2794)
						)
						(arc
							(start 0.1778 0.2794)
							(mid 0.249642 0.249642)
							(end 0.2794 0.1778)
						)
						(arc
							(start 0.2794 -0.1778)
							(mid 0.249642 -0.249642)
							(end 0.1778 -0.2794)
						)
					)
					(width 0)
					(fill yes)
				)
			)
		)
	)
	(footprint ""
		(layer "F.Cu")
		(at 234.061 -142.494 -90)
		(property "Reference" "R9895"
			(at 0 0 270)
			(layer "F.SilkS")
			(hide yes)
			(effects
				(font
					(size 1.27 1.27)
				)
			)
		)
		(property "Value" "1K82R2F-1-GP"
			(at 0.064008 -3.993896 270)
			(unlocked yes)
			(layer "F.Fab")
			(hide yes)
			(effects
				(font
					(size 1.016 1.016)
					(thickness 0.1524)
				)
			)
		)
		(property "Device Type" "R402H16"
			(at 0.064008 -5.517896 270)
			(unlocked yes)
			(layer "F.Fab")
			(hide yes)
			(effects
				(font
					(size 1.016 1.016)
					(thickness 0.1524)
				)
			)
		)
		(duplicate_pad_numbers_are_jumpers no)
		(fp_line
			(start -0.508 -0.9398)
			(end -0.508 0.9398)
			(stroke
				(width 0.1524)
				(type default)
			)
			(layer "F.SilkS")
		)
		(fp_line
			(start 0.508 -0.9398)
			(end -0.508 -0.9398)
			(stroke
				(width 0.1524)
				(type default)
			)
			(layer "F.SilkS")
		)
		(fp_rect
			(start -0.508 0.9398)
			(end 0.508 -0.9398)
			(stroke
				(width 0)
				(type default)
			)
			(fill no)
			(layer "F.CrtYd")
		)
		(fp_rect
			(start -0.508 0.9398)
			(end 0.508 -0.9398)
			(stroke
				(width 0)
				(type default)
			)
			(fill no)
			(layer "F.Fab")
		)
		(pad "1" smd custom
			(at 0 -0.4445 270)
			(size 0.1397 0.1397)
			(layers "F.Cu" "F.Mask" "F.Paste")
			(net "P12V")
			(options
				(clearance outline)
				(anchor circle)
			)
			(primitives
				(gr_poly
					(pts
						(arc
							(start -0.1778 -0.2794)
							(mid -0.249642 -0.249642)
							(end -0.2794 -0.1778)
						)
						(arc
							(start -0.2794 0.1778)
							(mid -0.249642 0.249642)
							(end -0.1778 0.2794)
						)
						(arc
							(start 0.1778 0.2794)
							(mid 0.249642 0.249642)
							(end 0.2794 0.1778)
						)
						(arc
							(start 0.2794 -0.1778)
							(mid 0.249642 -0.249642)
							(end 0.1778 -0.2794)
						)
					)
					(width 0)
					(fill yes)
				)
			)
		)
		(pad "2" smd custom
			(at 0 0.4445 270)
			(size 0.1397 0.1397)
			(layers "F.Cu" "F.Mask" "F.Paste")
			(net "DRV_ACT_3")
			(options
				(clearance outline)
				(anchor circle)
			)
			(primitives
				(gr_poly
					(pts
						(arc
							(start -0.1778 -0.2794)
							(mid -0.249642 -0.249642)
							(end -0.2794 -0.1778)
						)
						(arc
							(start -0.2794 0.1778)
							(mid -0.249642 0.249642)
							(end -0.1778 0.2794)
						)
						(arc
							(start 0.1778 0.2794)
							(mid 0.249642 0.249642)
							(end 0.2794 0.1778)
						)
						(arc
							(start 0.2794 -0.1778)
							(mid 0.249642 -0.249642)
							(end 0.1778 -0.2794)
						)
					)
					(width 0)
					(fill yes)
				)
			)
		)
	)
	(footprint ""
		(layer "F.Cu")
		(at 212.217 -439.674 180)
		(property "Reference" "PC1272"
			(at 0 0 180)
			(layer "F.SilkS")
			(hide yes)
			(effects
				(font
					(size 1.27 1.27)
				)
			)
		)
		(property "Value" "SC22U6D3V5MX-5-GP"
			(at -0.0762 -6.1214 180)
			(unlocked yes)
			(layer "F.Fab")
			(hide yes)
			(effects
				(font
					(size 1.016 1.016)
					(thickness 0.1524)
				)
			)
		)
		(property "Device Type" "C805H56"
			(at -0.0762 -8.1534 180)
			(unlocked yes)
			(layer "F.Fab")
			(hide yes)
			(effects
				(font
					(size 1.016 1.016)
					(thickness 0.1524)
				)
			)
		)
		(duplicate_pad_numbers_are_jumpers no)
		(fp_line
			(start 0.635 0)
			(end -0.635 0)
			(stroke
				(width 0.508)
				(type default)
			)
			(layer "F.SilkS")
		)
		(fp_rect
			(start -0.9652 1.778)
			(end 0.9652 -1.778)
			(stroke
				(width 0)
				(type default)
			)
			(fill no)
			(layer "F.CrtYd")
		)
		(fp_poly
			(pts
				(xy -0.9652 -1.778) (xy 0.9652 -1.778) (xy 0.9652 1.778) (xy -0.9652 1.778)
			)
			(stroke
				(width 0)
				(type default)
			)
			(fill no)
			(layer "F.Fab")
		)
		(pad "1" smd rect
			(at 0 -0.9652 180)
			(size 1.397 1.143)
			(layers "F.Cu" "F.Mask" "F.Paste")
			(net "P3V3_OUT")
		)
		(pad "2" smd rect
			(at 0 0.9652 180)
			(size 1.397 1.143)
			(layers "F.Cu" "F.Mask" "F.Paste")
			(net "GND")
		)
	)
	(footprint ""
		(layer "F.Cu")
		(at 41.150032 -170.669966 90)
		(property "Reference" "J8"
			(at 0 0 90)
			(layer "F.SilkS")
			(hide yes)
			(effects
				(font
					(size 1.27 1.27)
				)
			)
		)
		(property "Value" "PCISLT68-14-GP-U1"
			(at -22.225 12.7508 90)
			(unlocked yes)
			(layer "F.Fab")
			(hide yes)
			(effects
				(font
					(size 1.016 1.016)
					(thickness 0.1524)
				)
			)
		)
		(property "Device Type" "SD-78827-0001"
			(at -22.225 11.2268 90)
			(unlocked yes)
			(layer "F.Fab")
			(hide yes)
			(effects
				(font
					(size 1.016 1.016)
					(thickness 0.1524)
				)
			)
		)
		(duplicate_pad_numbers_are_jumpers no)
		(fp_line
			(start 20.4724 -3.4036)
			(end 20.4724 0.0254)
			(stroke
				(width 0.1524)
				(type default)
			)
			(layer "F.SilkS")
		)
		(fp_line
			(start -20.4724 -3.4036)
			(end 20.4724 -3.4036)
			(stroke
				(width 0.1524)
				(type default)
			)
			(layer "F.SilkS")
		)
		(fp_line
			(start 23.749 0.0254)
			(end 23.749 4.6736)
			(stroke
				(width 0.1524)
				(type default)
			)
			(layer "F.SilkS")
		)
		(fp_line
			(start 20.4724 0.0254)
			(end 23.749 0.0254)
			(stroke
				(width 0.1524)
				(type default)
			)
			(layer "F.SilkS")
		)
		(fp_line
			(start -20.4724 0.0254)
			(end -20.4724 -3.4036)
			(stroke
				(width 0.1524)
				(type default)
			)
			(layer "F.SilkS")
		)
		(fp_line
			(start -23.749 0.0254)
			(end -20.4724 0.0254)
			(stroke
				(width 0.1524)
				(type default)
			)
			(layer "F.SilkS")
		)
		(fp_line
			(start 23.117556 1.803908)
			(end 23.117556 2.896108)
			(stroke
				(width 0.3048)
				(type default)
			)
			(layer "F.SilkS")
		)
		(fp_line
			(start -20.882356 1.803908)
			(end -20.882356 2.896108)
			(stroke
				(width 0.3048)
				(type default)
			)
			(layer "F.SilkS")
		)
		(fp_line
			(start 20.882356 2.896108)
			(end 20.882356 1.803908)
			(stroke
				(width 0.3048)
				(type default)
			)
			(layer "F.SilkS")
		)
		(fp_line
			(start -23.117556 2.896108)
			(end -23.117556 1.803908)
			(stroke
				(width 0.3048)
				(type default)
			)
			(layer "F.SilkS")
		)
		(fp_line
			(start 23.749 4.6736)
			(end 20.4724 4.6736)
			(stroke
				(width 0.1524)
				(type default)
			)
			(layer "F.SilkS")
		)
		(fp_line
			(start 20.4724 4.6736)
			(end 20.4724 12.0142)
			(stroke
				(width 0.1524)
				(type default)
			)
			(layer "F.SilkS")
		)
		(fp_line
			(start -20.4724 4.6736)
			(end -23.749 4.6736)
			(stroke
				(width 0.1524)
				(type default)
			)
			(layer "F.SilkS")
		)
		(fp_line
			(start -23.749 4.6736)
			(end -23.749 0.0254)
			(stroke
				(width 0.1524)
				(type default)
			)
			(layer "F.SilkS")
		)
		(fp_line
			(start 17.8435 10.3124)
			(end -17.8435 10.3124)
			(stroke
				(width 0.1524)
				(type default)
			)
			(layer "F.SilkS")
		)
		(fp_line
			(start -17.8435 10.3124)
			(end -17.8435 12.0142)
			(stroke
				(width 0.1524)
				(type default)
			)
			(layer "F.SilkS")
		)
		(fp_line
			(start 20.4724 12.0142)
			(end 17.8435 12.0142)
			(stroke
				(width 0.1524)
				(type default)
			)
			(layer "F.SilkS")
		)
		(fp_line
			(start 17.8435 12.0142)
			(end 17.8435 10.3124)
			(stroke
				(width 0.1524)
				(type default)
			)
			(layer "F.SilkS")
		)
		(fp_line
			(start -17.8435 12.0142)
			(end -20.4724 12.0142)
			(stroke
				(width 0.1524)
				(type default)
			)
			(layer "F.SilkS")
		)
		(fp_line
			(start -20.4724 12.0142)
			(end -20.4724 4.6736)
			(stroke
				(width 0.1524)
				(type default)
			)
			(layer "F.SilkS")
		)
		(fp_arc
			(start 20.882356 1.803908)
			(mid 21.999956 0.686308)
			(end 23.117556 1.803908)
			(stroke
				(width 0.3048)
				(type default)
			)
			(layer "F.SilkS")
		)
		(fp_arc
			(start -23.117556 1.803908)
			(mid -21.999956 0.686308)
			(end -20.882356 1.803908)
			(stroke
				(width 0.3048)
				(type default)
			)
			(layer "F.SilkS")
		)
		(fp_arc
			(start 23.117556 2.896108)
			(mid 21.999956 4.013708)
			(end 20.882356 2.896108)
			(stroke
				(width 0.3048)
				(type default)
			)
			(layer "F.SilkS")
		)
		(fp_arc
			(start -20.882356 2.896108)
			(mid -21.999956 4.013708)
			(end -23.117556 2.896108)
			(stroke
				(width 0.3048)
				(type default)
			)
			(layer "F.SilkS")
		)
		(fp_poly
			(pts
				(xy -20.2184 11.7602) (xy -20.2184 4.4196) (xy -23.495 4.4196) (xy -23.495 0.2794) (xy -20.2184 0.2794)
				(xy -20.2184 -3.1496) (xy 20.2184 -3.1496) (xy 20.2184 0.2794) (xy 23.495 0.2794) (xy 23.495 4.4196)
				(xy 20.2184 4.4196) (xy 20.2184 11.7602) (xy 18.0975 11.7602) (xy 18.0975 10.0584) (xy -18.0975 10.0584)
				(xy -18.0975 11.7602)
			)
			(stroke
				(width 0)
				(type default)
			)
			(fill no)
			(layer "F.CrtYd")
		)
		(fp_poly
			(pts
				(xy -21.2471 16.256) (xy -21.2471 4.9276) (xy -24.003 4.9276) (xy -24.003 -0.2286) (xy -20.7264 -0.2286)
				(xy -20.7264 -3.6576) (xy 20.7264 -3.6576) (xy 20.7264 -0.2286) (xy 24.003 -0.2286) (xy 24.003 -0.00635)
				(xy 20.2184 -0.00635) (xy 20.2184 -3.1496) (xy -20.2184 -3.1496) (xy -20.2184 0.2794) (xy -23.495 0.2794)
				(xy -23.495 4.4196) (xy -20.2184 4.4196) (xy -20.2184 11.7602) (xy -18.0975 11.7602) (xy -18.0975 10.0584)
				(xy 18.0975 10.0584) (xy 18.0975 11.7602) (xy 20.2184 11.7602) (xy 20.2184 4.4196) (xy 23.495 4.4196)
				(xy 23.495 0.2794) (xy 20.2184 0.2794) (xy 20.2184 0.00635) (xy 24.003 0.00635) (xy 24.003 4.9276)
				(xy 21.2471 4.9276) (xy 21.2471 16.256)
			)
			(stroke
				(width 0)
				(type default)
			)
			(fill no)
			(layer "F.CrtYd")
		)
		(fp_poly
			(pts
				(xy -21.2471 16.256) (xy -21.2471 4.9276) (xy -24.003 4.9276) (xy -24.003 -0.2286) (xy -20.7264 -0.2286)
				(xy -20.7264 -3.6576) (xy 20.7264 -3.6576) (xy 20.7264 -0.2286) (xy 24.003 -0.2286) (xy 24.003 4.9276)
				(xy 21.2471 4.9276) (xy 21.2471 16.256)
			)
			(stroke
				(width 0)
				(type default)
			)
			(fill no)
			(layer "F.Fab")
		)
		(pad "" np_thru_hole circle
			(at -18.999962 0 90)
			(size 0.254 0.254)
			(drill 1.8542)
			(layers "*.Cu" "*.Mask")
			(clearance 1.1557)
			(thermal_gap 1.1557)
		)
		(pad "" np_thru_hole circle
			(at 18.999962 0 90)
			(size 0.254 0.254)
			(drill 1.8542)
			(layers "*.Cu" "*.Mask")
			(clearance 1.1557)
			(thermal_gap 1.1557)
		)
		(pad "E1" smd rect
			(at -7.079996 1.240028 90)
			(size 0.508 2.0066)
			(layers "F.Cu" "F.Mask" "F.Paste")
			(net "PE_CLK100M_DR8_2_P")
		)
		(pad "E2" smd rect
			(at -6.279896 1.240028 90)
			(size 0.508 2.0066)
			(layers "F.Cu" "F.Mask" "F.Paste")
			(net "PE_CLK100M_DR8_2_N")
		)
		(pad "E3" smd rect
			(at -5.48005 1.240028 90)
			(size 0.508 2.0066)
			(layers "F.Cu" "F.Mask" "F.Paste")
			(net "P3V3")
		)
		(pad "E4" smd rect
			(at -4.67995 1.240028 90)
			(size 0.508 2.0066)
			(layers "F.Cu" "F.Mask" "F.Paste")
			(net "SSD8_PERST_N")
		)
		(pad "E5" smd rect
			(at -3.880104 1.240028 90)
			(size 0.508 2.0066)
			(layers "F.Cu" "F.Mask" "F.Paste")
			(net "SSD8_PERST_N")
		)
		(pad "E6" smd rect
			(at -3.080004 1.240028 90)
			(size 0.508 2.0066)
			(layers "F.Cu" "F.Mask" "F.Paste")
			(net "Net_1089")
		)
		(pad "E7" smd rect
			(at -15.48003 -1.949958 90)
			(size 0.508 2.0066)
			(layers "F.Cu" "F.Mask" "F.Paste")
			(net "PE_CLK100M_DR8_1_P")
		)
		(pad "E8" smd rect
			(at -14.67993 -1.949958 90)
			(size 0.508 2.0066)
			(layers "F.Cu" "F.Mask" "F.Paste")
			(net "PE_CLK100M_DR8_1_N")
		)
		(pad "E9" smd rect
			(at -13.880084 -1.949958 90)
			(size 0.508 2.0066)
			(layers "F.Cu" "F.Mask" "F.Paste")
			(net "GND")
		)
		(pad "E10" smd rect
			(at -13.079984 -1.949958 90)
			(size 0.508 2.0066)
			(layers "F.Cu" "F.Mask" "F.Paste")
			(net "PE_TX1_DR8_N")
		)
		(pad "E11" smd rect
			(at -12.279884 -1.949958 90)
			(size 0.508 2.0066)
			(layers "F.Cu" "F.Mask" "F.Paste")
			(net "PE_TX1_DR8_P")
		)
		(pad "E12" smd rect
			(at -11.480038 -1.949958 90)
			(size 0.508 2.0066)
			(layers "F.Cu" "F.Mask" "F.Paste")
			(net "GND")
		)
		(pad "E13" smd rect
			(at -10.679938 -1.949958 90)
			(size 0.508 2.0066)
			(layers "F.Cu" "F.Mask" "F.Paste")
			(net "PE_RX1_DR8_N")
		)
		(pad "E14" smd rect
			(at -9.880092 -1.949958 90)
			(size 0.508 2.0066)
			(layers "F.Cu" "F.Mask" "F.Paste")
			(net "PE_RX1_DR8_P")
		)
		(pad "E15" smd rect
			(at -9.079992 -1.949958 90)
			(size 0.508 2.0066)
			(layers "F.Cu" "F.Mask" "F.Paste")
			(net "GND")
		)
		(pad "E16" smd rect
			(at -8.279892 -1.949958 90)
			(size 0.508 2.0066)
			(layers "F.Cu" "F.Mask" "F.Paste")
			(net "Net_1096")
		)
		(pad "E17" smd rect
			(at 9.320022 -1.949958 90)
			(size 0.508 2.0066)
			(layers "F.Cu" "F.Mask" "F.Paste")
			(net "PE_TX4_DR8_N")
		)
		(pad "E18" smd rect
			(at 10.120122 -1.949958 90)
			(size 0.508 2.0066)
			(layers "F.Cu" "F.Mask" "F.Paste")
			(net "PE_TX4_DR8_P")
		)
		(pad "E19" smd rect
			(at 10.919968 -1.949958 90)
			(size 0.508 2.0066)
			(layers "F.Cu" "F.Mask" "F.Paste")
			(net "GND")
		)
		(pad "E20" smd rect
			(at 11.720068 -1.949958 90)
			(size 0.508 2.0066)
			(layers "F.Cu" "F.Mask" "F.Paste")
			(net "PE_RX4_DR8_N")
		)
		(pad "E21" smd rect
			(at 12.519914 -1.949958 90)
			(size 0.508 2.0066)
			(layers "F.Cu" "F.Mask" "F.Paste")
			(net "PE_RX4_DR8_P")
		)
		(pad "E22" smd rect
			(at 13.320014 -1.949958 90)
			(size 0.508 2.0066)
			(layers "F.Cu" "F.Mask" "F.Paste")
			(net "GND")
		)
		(pad "E23" smd rect
			(at 14.120114 -1.949958 90)
			(size 0.508 2.0066)
			(layers "F.Cu" "F.Mask" "F.Paste")
			(net "SCL_DR8_R")
		)
		(pad "E24" smd rect
			(at 14.91996 -1.949958 90)
			(size 0.508 2.0066)
			(layers "F.Cu" "F.Mask" "F.Paste")
			(net "SDA_DR8_R")
		)
		(pad "E25" smd rect
			(at 15.72006 -1.949958 90)
			(size 0.508 2.0066)
			(layers "F.Cu" "F.Mask" "F.Paste")
			(net "DUALPORTEN#8")
		)
		(pad "P1" smd rect
			(at -1.905 0.824992 90)
			(size 0.6604 2.0574)
			(layers "F.Cu" "F.Mask" "F.Paste")
			(net "Net_1092")
		)
		(pad "P2" smd rect
			(at -0.635 0.824992 90)
			(size 0.6604 2.0574)
			(layers "F.Cu" "F.Mask" "F.Paste")
			(net "Net_1091")
		)
		(pad "P3" smd rect
			(at 0.635 0.824992 90)
			(size 0.6604 2.0574)
			(layers "F.Cu" "F.Mask" "F.Paste")
			(net "Net_1090")
		)
		(pad "P4" smd rect
			(at 1.905 0.824992 90)
			(size 0.6604 2.0574)
			(layers "F.Cu" "F.Mask" "F.Paste")
			(net "SSD8_CLK0_OE_N")
		)
		(pad "P5" smd rect
			(at 3.175 0.824992 90)
			(size 0.6604 2.0574)
			(layers "F.Cu" "F.Mask" "F.Paste")
			(net "GND")
		)
		(pad "P6" smd rect
			(at 4.445 0.824992 90)
			(size 0.6604 2.0574)
			(layers "F.Cu" "F.Mask" "F.Paste")
			(net "GND")
		)
		(pad "P7" smd rect
			(at 5.715 0.824992 90)
			(size 0.6604 2.0574)
			(layers "F.Cu" "F.Mask" "F.Paste")
			(net "Net_97")
		)
		(pad "P8" smd rect
			(at 6.985 0.824992 90)
			(size 0.6604 2.0574)
			(layers "F.Cu" "F.Mask" "F.Paste")
			(net "Net_69")
		)
		(pad "P9" smd rect
			(at 8.255 0.824992 90)
			(size 0.6604 2.0574)
			(layers "F.Cu" "F.Mask" "F.Paste")
			(net "Net_83")
		)
		(pad "P10" smd rect
			(at 9.525 0.824992 90)
			(size 0.6604 2.0574)
			(layers "F.Cu" "F.Mask" "F.Paste")
			(net "SSD_PRSNT_NET8")
		)
		(pad "P11" smd rect
			(at 10.795 0.824992 90)
			(size 0.6604 2.0574)
			(layers "F.Cu" "F.Mask" "F.Paste")
			(net "SSD_ACT_DR8")
		)
		(pad "P12" smd rect
			(at 12.065 0.824992 90)
			(size 0.6604 2.0574)
			(layers "F.Cu" "F.Mask" "F.Paste")
			(net "GND")
		)
		(pad "P13" smd rect
			(at 13.335 0.824992 90)
			(size 0.6604 2.0574)
			(layers "F.Cu" "F.Mask" "F.Paste")
			(net "12V_PRECH_SSD8")
		)
		(pad "P14" smd rect
			(at 14.605 0.824992 90)
			(size 0.6604 2.0574)
			(layers "F.Cu" "F.Mask" "F.Paste")
			(net "P12V_SSD8")
		)
		(pad "P15" smd rect
			(at 15.875 0.824992 90)
			(size 0.6604 2.0574)
			(layers "F.Cu" "F.Mask" "F.Paste")
			(net "P12V_SSD8")
		)
		(pad "PTH1" thru_hole oval
			(at -21.999956 2.350008 90)
			(size 1.524 2.6162)
			(drill oval 0.8128 1.905)
			(layers "*.Cu" "*.Mask")
			(remove_unused_layers no)
			(net "Net_1101")
			(clearance 0.1524)
			(thermal_gap 0.1524)
		)
		(pad "PTH2" thru_hole oval
			(at 21.999956 2.350008 90)
			(size 1.524 2.6162)
			(drill oval 0.8128 1.905)
			(layers "*.Cu" "*.Mask")
			(remove_unused_layers no)
			(net "Net_1085")
			(clearance 0.1524)
			(thermal_gap 0.1524)
		)
		(pad "S1" smd rect
			(at -15.875 0.824992 90)
			(size 0.6604 2.0574)
			(layers "F.Cu" "F.Mask" "F.Paste")
			(net "GND")
		)
		(pad "S2" smd rect
			(at -14.605 0.824992 90)
			(size 0.6604 2.0574)
			(layers "F.Cu" "F.Mask" "F.Paste")
			(net "Net_1100")
		)
		(pad "S3" smd rect
			(at -13.335 0.824992 90)
			(size 0.6604 2.0574)
			(layers "F.Cu" "F.Mask" "F.Paste")
			(net "Net_1099")
		)
		(pad "S4" smd rect
			(at -12.065 0.824992 90)
			(size 0.6604 2.0574)
			(layers "F.Cu" "F.Mask" "F.Paste")
			(net "GND")
		)
		(pad "S5" smd rect
			(at -10.795 0.824992 90)
			(size 0.6604 2.0574)
			(layers "F.Cu" "F.Mask" "F.Paste")
			(net "Net_1098")
		)
		(pad "S6" smd rect
			(at -9.525 0.824992 90)
			(size 0.6604 2.0574)
			(layers "F.Cu" "F.Mask" "F.Paste")
			(net "Net_1097")
		)
		(pad "S7" smd rect
			(at -8.255 0.824992 90)
			(size 0.6604 2.0574)
			(layers "F.Cu" "F.Mask" "F.Paste")
			(net "GND")
		)
		(pad "S8" smd rect
			(at -7.480046 -1.949958 90)
			(size 0.508 2.0066)
			(layers "F.Cu" "F.Mask" "F.Paste")
			(net "GND")
		)
		(pad "S9" smd rect
			(at -6.679946 -1.949958 90)
			(size 0.508 2.0066)
			(layers "F.Cu" "F.Mask" "F.Paste")
			(net "Net_1095")
		)
		(pad "S10" smd rect
			(at -5.8801 -1.949958 90)
			(size 0.508 2.0066)
			(layers "F.Cu" "F.Mask" "F.Paste")
			(net "Net_1094")
		)
		(pad "S11" smd rect
			(at -5.08 -1.949958 90)
			(size 0.508 2.0066)
			(layers "F.Cu" "F.Mask" "F.Paste")
			(net "GND")
		)
		(pad "S12" smd rect
			(at -4.2799 -1.949958 90)
			(size 0.508 2.0066)
			(layers "F.Cu" "F.Mask" "F.Paste")
			(net "Net_1093")
		)
		(pad "S13" smd rect
			(at -3.480054 -1.949958 90)
			(size 0.508 2.0066)
			(layers "F.Cu" "F.Mask" "F.Paste")
			(net "Net_1088")
		)
		(pad "S14" smd rect
			(at -2.679954 -1.949958 90)
			(size 0.508 2.0066)
			(layers "F.Cu" "F.Mask" "F.Paste")
			(net "GND")
		)
		(pad "S15" smd rect
			(at -1.880108 -1.949958 90)
			(size 0.508 2.0066)
			(layers "F.Cu" "F.Mask" "F.Paste")
			(net "Net_1087")
		)
		(pad "S16" smd rect
			(at -1.080008 -1.949958 90)
			(size 0.508 2.0066)
			(layers "F.Cu" "F.Mask" "F.Paste")
			(net "GND")
		)
		(pad "S17" smd rect
			(at -0.279908 -1.949958 90)
			(size 0.508 2.0066)
			(layers "F.Cu" "F.Mask" "F.Paste")
			(net "PE_TX2_DR8_N")
		)
		(pad "S18" smd rect
			(at 0.519938 -1.949958 90)
			(size 0.508 2.0066)
			(layers "F.Cu" "F.Mask" "F.Paste")
			(net "PE_TX2_DR8_P")
		)
		(pad "S19" smd rect
			(at 1.320038 -1.949958 90)
			(size 0.508 2.0066)
			(layers "F.Cu" "F.Mask" "F.Paste")
			(net "GND")
		)
		(pad "S20" smd rect
			(at 2.119884 -1.949958 90)
			(size 0.508 2.0066)
			(layers "F.Cu" "F.Mask" "F.Paste")
			(net "PE_RX2_DR8_N")
		)
		(pad "S21" smd rect
			(at 2.919984 -1.949958 90)
			(size 0.508 2.0066)
			(layers "F.Cu" "F.Mask" "F.Paste")
			(net "PE_RX2_DR8_P")
		)
		(pad "S22" smd rect
			(at 3.720084 -1.949958 90)
			(size 0.508 2.0066)
			(layers "F.Cu" "F.Mask" "F.Paste")
			(net "GND")
		)
		(pad "S23" smd rect
			(at 4.51993 -1.949958 90)
			(size 0.508 2.0066)
			(layers "F.Cu" "F.Mask" "F.Paste")
			(net "PE_TX3_DR8_N")
		)
		(pad "S24" smd rect
			(at 5.32003 -1.949958 90)
			(size 0.508 2.0066)
			(layers "F.Cu" "F.Mask" "F.Paste")
			(net "PE_TX3_DR8_P")
		)
		(pad "S25" smd rect
			(at 6.119876 -1.949958 90)
			(size 0.508 2.0066)
			(layers "F.Cu" "F.Mask" "F.Paste")
			(net "GND")
		)
		(pad "S26" smd rect
			(at 6.919976 -1.949958 90)
			(size 0.508 2.0066)
			(layers "F.Cu" "F.Mask" "F.Paste")
			(net "PE_RX3_DR8_N")
		)
		(pad "S27" smd rect
			(at 7.720076 -1.949958 90)
			(size 0.508 2.0066)
			(layers "F.Cu" "F.Mask" "F.Paste")
			(net "PE_RX3_DR8_P")
		)
		(pad "S28" smd rect
			(at 8.519922 -1.949958 90)
			(size 0.508 2.0066)
			(layers "F.Cu" "F.Mask" "F.Paste")
			(net "GND")
		)
		(zone
			(layers "F.Cu" "B.Cu" "In1.Cu" "In2.Cu" "In3.Cu" "In4.Cu" "In5.Cu" "In6.Cu")
			(hatch none 0.5)
			(connect_pads
				(clearance 0)
			)
			(min_thickness 0.25)
			(keepout
				(tracks not_allowed)
				(vias allowed)
				(pads allowed)
				(copperpour not_allowed)
				(footprints allowed)
			)
			(placement
				(enabled no)
				(sheetname "")
			)
			(fill
				(thermal_gap 0.5)
				(thermal_bridge_width 0.5)
				(island_removal_mode 0)
			)
			(polygon
				(pts
					(arc
						(start 42.381932 -189.669928)
						(mid 39.918132 -189.669928)
						(end 42.381932 -189.669928)
					)
				)
			)
		)
		(zone
			(layers "F.Cu" "B.Cu" "In1.Cu" "In2.Cu" "In3.Cu" "In4.Cu" "In5.Cu" "In6.Cu")
			(hatch none 0.5)
			(connect_pads
				(clearance 0)
			)
			(min_thickness 0.25)
			(keepout
				(tracks not_allowed)
				(vias allowed)
				(pads allowed)
				(copperpour not_allowed)
				(footprints allowed)
			)
			(placement
				(enabled no)
				(sheetname "")
			)
			(fill
				(thermal_gap 0.5)
				(thermal_bridge_width 0.5)
				(island_removal_mode 0)
			)
			(polygon
				(pts
					(arc
						(start 42.381932 -151.670004)
						(mid 39.918132 -151.670004)
						(end 42.381932 -151.670004)
					)
				)
			)
		)
	)
	(footprint ""
		(layer "F.Cu")
		(at 22.733 -493.141 -90)
		(property "Reference" "U14"
			(at 0 0 270)
			(layer "F.SilkS")
			(hide yes)
			(effects
				(font
					(size 1.27 1.27)
				)
			)
		)
		(property "Value" "P2003EVG-GP"
			(at 0 -11.1252 270)
			(unlocked yes)
			(layer "F.Fab")
			(hide yes)
			(effects
				(font
					(size 1.016 1.016)
					(thickness 0.1524)
				)
			)
		)
		(property "Device Type" "SOIC8H79"
			(at 0 -12.6492 270)
			(unlocked yes)
			(layer "F.Fab")
			(hide yes)
			(effects
				(font
					(size 1.016 1.016)
					(thickness 0.1524)
				)
			)
		)
		(duplicate_pad_numbers_are_jumpers no)
		(fp_line
			(start -2.6162 3.429)
			(end -2.6162 1.4732)
			(stroke
				(width 0.4064)
				(type default)
			)
			(layer "F.SilkS")
		)
		(fp_line
			(start -2.7432 1.4224)
			(end 2.1336 1.4224)
			(stroke
				(width 0.1524)
				(type default)
			)
			(layer "F.SilkS")
		)
		(fp_line
			(start 2.1336 1.4224)
			(end 2.1336 -1.4224)
			(stroke
				(width 0.1524)
				(type default)
			)
			(layer "F.SilkS")
		)
		(fp_line
			(start -2.2352 0)
			(end -2.7432 0.508)
			(stroke
				(width 0.1524)
				(type default)
			)
			(layer "F.SilkS")
		)
		(fp_line
			(start -2.7432 -0.508)
			(end -2.2352 0)
			(stroke
				(width 0.1524)
				(type default)
			)
			(layer "F.SilkS")
		)
		(fp_line
			(start -2.7432 -1.4224)
			(end -2.7432 1.4224)
			(stroke
				(width 0.1524)
				(type default)
			)
			(layer "F.SilkS")
		)
		(fp_line
			(start 2.1336 -1.4224)
			(end -2.7432 -1.4224)
			(stroke
				(width 0.1524)
				(type default)
			)
			(layer "F.SilkS")
		)
		(fp_poly
			(pts
				(xy 2.2098 -1.4224) (xy 2.2098 1.4224) (xy -2.2225 1.4224) (xy -2.2225 -1.4224)
			)
			(stroke
				(width 0)
				(type default)
			)
			(fill yes)
			(layer "F.SilkS")
		)
		(fp_rect
			(start -2.4511 2.9972)
			(end 2.4511 -2.9972)
			(stroke
				(width 0)
				(type default)
			)
			(fill no)
			(layer "F.CrtYd")
		)
		(fp_poly
			(pts
				(xy -2.8194 3.6322) (xy -2.8194 -3.6322) (xy 2.8194 -3.6322) (xy 2.8194 -2.2987) (xy 2.4511 -2.2987)
				(xy 2.4511 -2.9972) (xy -2.4511 -2.9972) (xy -2.4511 2.9972) (xy 2.4511 2.9972) (xy 2.4511 -2.286)
				(xy 2.8194 -2.286) (xy 2.8194 3.6322)
			)
			(stroke
				(width 0)
				(type default)
			)
			(fill no)
			(layer "F.CrtYd")
		)
		(fp_rect
			(start -2.8194 3.6322)
			(end 2.8194 -3.6322)
			(stroke
				(width 0)
				(type default)
			)
			(fill no)
			(layer "F.Fab")
		)
		(pad "1" smd rect
			(at -1.905 2.54 270)
			(size 0.635 1.651)
			(layers "F.Cu" "F.Mask" "F.Paste")
			(net "P12V")
		)
		(pad "2" smd rect
			(at -0.635 2.54 270)
			(size 0.635 1.651)
			(layers "F.Cu" "F.Mask" "F.Paste")
			(net "P12V")
		)
		(pad "3" smd rect
			(at 0.635 2.54 270)
			(size 0.635 1.651)
			(layers "F.Cu" "F.Mask" "F.Paste")
			(net "P12V")
		)
		(pad "4" smd rect
			(at 1.905 2.54 270)
			(size 0.635 1.651)
			(layers "F.Cu" "F.Mask" "F.Paste")
			(net "SW_SSD5_N")
		)
		(pad "5" smd rect
			(at 1.905 -2.54 270)
			(size 0.635 1.651)
			(layers "F.Cu" "F.Mask" "F.Paste")
			(net "P12V_SSD5")
		)
		(pad "6" smd rect
			(at 0.635 -2.54 270)
			(size 0.635 1.651)
			(layers "F.Cu" "F.Mask" "F.Paste")
			(net "P12V_SSD5")
		)
		(pad "7" smd rect
			(at -0.635 -2.54 270)
			(size 0.635 1.651)
			(layers "F.Cu" "F.Mask" "F.Paste")
			(net "P12V_SSD5")
		)
		(pad "8" smd rect
			(at -1.905 -2.54 270)
			(size 0.635 1.651)
			(layers "F.Cu" "F.Mask" "F.Paste")
			(net "P12V_SSD5")
		)
	)
	(footprint ""
		(layer "F.Cu")
		(at 25.4 -134.112 180)
		(property "Reference" "PC1214"
			(at 0 0 180)
			(layer "F.SilkS")
			(hide yes)
			(effects
				(font
					(size 1.27 1.27)
				)
			)
		)
		(property "Value" "SCD1U25V3KX-GP"
			(at 0 -2.8194 180)
			(unlocked yes)
			(layer "F.Fab")
			(hide yes)
			(effects
				(font
					(size 1.016 1.016)
					(thickness 0.1524)
				)
			)
		)
		(property "Device Type" "C603H36"
			(at 0 -4.3434 180)
			(unlocked yes)
			(layer "F.Fab")
			(hide yes)
			(effects
				(font
					(size 1.016 1.016)
					(thickness 0.1524)
				)
			)
		)
		(duplicate_pad_numbers_are_jumpers no)
		(fp_line
			(start 0.508 0)
			(end -0.508 0)
			(stroke
				(width 0.2032)
				(type default)
			)
			(layer "F.SilkS")
		)
		(fp_rect
			(start -0.5842 1.3335)
			(end 0.5842 -1.3335)
			(stroke
				(width 0)
				(type default)
			)
			(fill no)
			(layer "F.CrtYd")
		)
		(fp_rect
			(start -0.5842 1.3335)
			(end 0.5842 -1.3335)
			(stroke
				(width 0)
				(type default)
			)
			(fill no)
			(layer "F.Fab")
		)
		(pad "1" smd custom
			(at 0 -0.762 180)
			(size 0.2159 0.2159)
			(layers "F.Cu" "F.Mask" "F.Paste")
			(net "P3V3")
			(options
				(clearance outline)
				(anchor circle)
			)
			(primitives
				(gr_poly
					(pts
						(arc
							(start -0.3302 -0.4318)
							(mid -0.402042 -0.402042)
							(end -0.4318 -0.3302)
						)
						(arc
							(start -0.4318 0.3302)
							(mid -0.402042 0.402042)
							(end -0.3302 0.4318)
						)
						(arc
							(start 0.3302 0.4318)
							(mid 0.402042 0.402042)
							(end 0.4318 0.3302)
						)
						(arc
							(start 0.4318 -0.3302)
							(mid 0.402042 -0.402042)
							(end 0.3302 -0.4318)
						)
					)
					(width 0)
					(fill yes)
				)
			)
		)
		(pad "2" smd custom
			(at 0 0.762 180)
			(size 0.2159 0.2159)
			(layers "F.Cu" "F.Mask" "F.Paste")
			(net "GND")
			(options
				(clearance outline)
				(anchor circle)
			)
			(primitives
				(gr_poly
					(pts
						(arc
							(start -0.3302 -0.4318)
							(mid -0.402042 -0.402042)
							(end -0.4318 -0.3302)
						)
						(arc
							(start -0.4318 0.3302)
							(mid -0.402042 0.402042)
							(end -0.3302 0.4318)
						)
						(arc
							(start 0.3302 0.4318)
							(mid 0.402042 0.402042)
							(end 0.4318 0.3302)
						)
						(arc
							(start 0.4318 -0.3302)
							(mid 0.402042 -0.402042)
							(end 0.3302 -0.4318)
						)
					)
					(width 0)
					(fill yes)
				)
			)
		)
	)
	(footprint ""
		(layer "F.Cu")
		(at 89.789 -317.246 -90)
		(property "Reference" "C9349"
			(at 0 0 270)
			(layer "F.SilkS")
			(hide yes)
			(effects
				(font
					(size 1.27 1.27)
				)
			)
		)
		(property "Value" "SC1KP50V2KX-1GP"
			(at 1.1811 -2.7051 270)
			(unlocked yes)
			(layer "F.Fab")
			(hide yes)
			(effects
				(font
					(size 1.016 1.016)
					(thickness 0.1524)
				)
			)
		)
		(property "Device Type" "C402H22"
			(at 1.1811 -4.2291 270)
			(unlocked yes)
			(layer "F.Fab")
			(hide yes)
			(effects
				(font
					(size 1.016 1.016)
					(thickness 0.1524)
				)
			)
		)
		(duplicate_pad_numbers_are_jumpers no)
		(fp_rect
			(start -0.4318 0.9525)
			(end 0.4318 -0.9525)
			(stroke
				(width 0)
				(type default)
			)
			(fill no)
			(layer "F.CrtYd")
		)
		(fp_rect
			(start -0.4318 0.9525)
			(end 0.4318 -0.9525)
			(stroke
				(width 0)
				(type default)
			)
			(fill no)
			(layer "F.Fab")
		)
		(pad "1" smd custom
			(at 0 -0.4445 270)
			(size 0.1524 0.1524)
			(layers "F.Cu" "F.Mask" "F.Paste")
			(net "SSD_PRSNT11")
			(options
				(clearance outline)
				(anchor circle)
			)
			(primitives
				(gr_poly
					(pts
						(arc
							(start 0.3048 -0.2032)
							(mid 0.275042 -0.275042)
							(end 0.2032 -0.3048)
						)
						(arc
							(start -0.2032 -0.3048)
							(mid -0.275042 -0.275042)
							(end -0.3048 -0.2032)
						)
						(arc
							(start -0.3048 0.2032)
							(mid -0.275042 0.275042)
							(end -0.2032 0.3048)
						)
						(arc
							(start 0.2032 0.3048)
							(mid 0.275042 0.275042)
							(end 0.3048 0.2032)
						)
					)
					(width 0)
					(fill yes)
				)
			)
		)
		(pad "2" smd custom
			(at 0 0.4445 270)
			(size 0.1524 0.1524)
			(layers "F.Cu" "F.Mask" "F.Paste")
			(net "GND")
			(options
				(clearance outline)
				(anchor circle)
			)
			(primitives
				(gr_poly
					(pts
						(arc
							(start 0.3048 -0.2032)
							(mid 0.275042 -0.275042)
							(end 0.2032 -0.3048)
						)
						(arc
							(start -0.2032 -0.3048)
							(mid -0.275042 -0.275042)
							(end -0.3048 -0.2032)
						)
						(arc
							(start -0.3048 0.2032)
							(mid -0.275042 0.275042)
							(end -0.2032 0.3048)
						)
						(arc
							(start 0.2032 0.3048)
							(mid 0.275042 0.275042)
							(end 0.3048 0.2032)
						)
					)
					(width 0)
					(fill yes)
				)
			)
		)
	)
	(footprint ""
		(layer "F.Cu")
		(at 222.123 -400.685 180)
		(property "Reference" "PC1235"
			(at 0 0 180)
			(layer "F.SilkS")
			(hide yes)
			(effects
				(font
					(size 1.27 1.27)
				)
			)
		)
		(property "Value" "SC22U25V6KX-GP-U"
			(at -2.860802 -5.279644 180)
			(unlocked yes)
			(layer "F.Fab")
			(hide yes)
			(effects
				(font
					(size 1.016 1.016)
					(thickness 0.1524)
				)
			)
		)
		(property "Device Type" "C1206-TO0D3H75"
			(at -2.860802 -6.803644 180)
			(unlocked yes)
			(layer "F.Fab")
			(hide yes)
			(effects
				(font
					(size 1.016 1.016)
					(thickness 0.1524)
				)
			)
		)
		(duplicate_pad_numbers_are_jumpers no)
		(fp_line
			(start 1.3081 2.3749)
			(end -1.3081 2.3749)
			(stroke
				(width 0.1524)
				(type default)
			)
			(layer "F.SilkS")
		)
		(fp_line
			(start 1.3081 -2.3749)
			(end 1.3081 2.3749)
			(stroke
				(width 0.1524)
				(type default)
			)
			(layer "F.SilkS")
		)
		(fp_line
			(start -1.3081 2.3749)
			(end -1.3081 -2.3749)
			(stroke
				(width 0.1524)
				(type default)
			)
			(layer "F.SilkS")
		)
		(fp_line
			(start -1.3081 -2.3749)
			(end 1.3081 -2.3749)
			(stroke
				(width 0.1524)
				(type default)
			)
			(layer "F.SilkS")
		)
		(fp_rect
			(start -0.8001 1.6002)
			(end 0.8001 -1.6002)
			(stroke
				(width 0)
				(type default)
			)
			(fill no)
			(layer "F.CrtYd")
		)
		(fp_poly
			(pts
				(xy -1.5621 2.4511) (xy -1.5621 1.6002) (xy 0.8001 1.6002) (xy 0.8001 -1.6002) (xy -0.8001 -1.6002)
				(xy -0.8001 1.5875) (xy -1.5621 1.5875) (xy -1.5621 -2.4511) (xy 1.5621 -2.4511) (xy 1.5621 2.4511)
			)
			(stroke
				(width 0)
				(type default)
			)
			(fill no)
			(layer "F.CrtYd")
		)
		(fp_rect
			(start -1.5621 2.4511)
			(end 1.5621 -2.4511)
			(stroke
				(width 0)
				(type default)
			)
			(fill no)
			(layer "F.Fab")
		)
		(pad "1" smd rect
			(at 0 -1.392936 180)
			(size 2.1082 1.4478)
			(layers "F.Cu" "F.Mask" "F.Paste")
			(net "P12V_SSD1")
		)
		(pad "2" smd rect
			(at 0 1.392936 180)
			(size 2.1082 1.4478)
			(layers "F.Cu" "F.Mask" "F.Paste")
			(net "GND")
		)
	)
	(footprint ""
		(layer "F.Cu")
		(at 96.774 -317.246 -90)
		(property "Reference" "C9368"
			(at 0 0 270)
			(layer "F.SilkS")
			(hide yes)
			(effects
				(font
					(size 1.27 1.27)
				)
			)
		)
		(property "Value" "SC1KP50V2KX-1GP"
			(at 1.1811 -2.7051 270)
			(unlocked yes)
			(layer "F.Fab")
			(hide yes)
			(effects
				(font
					(size 1.016 1.016)
					(thickness 0.1524)
				)
			)
		)
		(property "Device Type" "C402H22"
			(at 1.1811 -4.2291 270)
			(unlocked yes)
			(layer "F.Fab")
			(hide yes)
			(effects
				(font
					(size 1.016 1.016)
					(thickness 0.1524)
				)
			)
		)
		(duplicate_pad_numbers_are_jumpers no)
		(fp_rect
			(start -0.4318 0.9525)
			(end 0.4318 -0.9525)
			(stroke
				(width 0)
				(type default)
			)
			(fill no)
			(layer "F.CrtYd")
		)
		(fp_rect
			(start -0.4318 0.9525)
			(end 0.4318 -0.9525)
			(stroke
				(width 0)
				(type default)
			)
			(fill no)
			(layer "F.Fab")
		)
		(pad "1" smd custom
			(at 0 -0.4445 270)
			(size 0.1524 0.1524)
			(layers "F.Cu" "F.Mask" "F.Paste")
			(net "SSD6_CLK0_OE_R_N")
			(options
				(clearance outline)
				(anchor circle)
			)
			(primitives
				(gr_poly
					(pts
						(arc
							(start 0.3048 -0.2032)
							(mid 0.275042 -0.275042)
							(end 0.2032 -0.3048)
						)
						(arc
							(start -0.2032 -0.3048)
							(mid -0.275042 -0.275042)
							(end -0.3048 -0.2032)
						)
						(arc
							(start -0.3048 0.2032)
							(mid -0.275042 0.275042)
							(end -0.2032 0.3048)
						)
						(arc
							(start 0.2032 0.3048)
							(mid 0.275042 0.275042)
							(end 0.3048 0.2032)
						)
					)
					(width 0)
					(fill yes)
				)
			)
		)
		(pad "2" smd custom
			(at 0 0.4445 270)
			(size 0.1524 0.1524)
			(layers "F.Cu" "F.Mask" "F.Paste")
			(net "GND")
			(options
				(clearance outline)
				(anchor circle)
			)
			(primitives
				(gr_poly
					(pts
						(arc
							(start 0.3048 -0.2032)
							(mid 0.275042 -0.275042)
							(end 0.2032 -0.3048)
						)
						(arc
							(start -0.2032 -0.3048)
							(mid -0.275042 -0.275042)
							(end -0.3048 -0.2032)
						)
						(arc
							(start -0.3048 0.2032)
							(mid -0.275042 0.275042)
							(end -0.2032 0.3048)
						)
						(arc
							(start 0.2032 0.3048)
							(mid 0.275042 0.275042)
							(end 0.3048 0.2032)
						)
					)
					(width 0)
					(fill yes)
				)
			)
		)
	)
	(footprint ""
		(layer "F.Cu")
		(at 19.547332 -56.002936 90)
		(property "Reference" "Q100"
			(at 0 0 90)
			(layer "F.SilkS")
			(hide yes)
			(effects
				(font
					(size 1.27 1.27)
				)
			)
		)
		(property "Value" "2N7002A-7-GP"
			(at 0.127 -8.9662 90)
			(unlocked yes)
			(layer "F.Fab")
			(hide yes)
			(effects
				(font
					(size 1.016 1.016)
					(thickness 0.1524)
				)
			)
		)
		(property "Device Type" "SOT23DGS2D4H48"
			(at 0.127 -10.4902 90)
			(unlocked yes)
			(layer "F.Fab")
			(hide yes)
			(effects
				(font
					(size 1.016 1.016)
					(thickness 0.1524)
				)
			)
		)
		(duplicate_pad_numbers_are_jumpers no)
		(fp_line
			(start 1.651 -1.778)
			(end -1.651 -1.778)
			(stroke
				(width 0.1524)
				(type default)
			)
			(layer "F.SilkS")
		)
		(fp_line
			(start -1.651 -1.778)
			(end -1.651 1.778)
			(stroke
				(width 0.1524)
				(type default)
			)
			(layer "F.SilkS")
		)
		(fp_line
			(start 1.651 1.778)
			(end 1.651 -1.778)
			(stroke
				(width 0.1524)
				(type default)
			)
			(layer "F.SilkS")
		)
		(fp_line
			(start -1.651 1.778)
			(end 1.651 1.778)
			(stroke
				(width 0.1524)
				(type default)
			)
			(layer "F.SilkS")
		)
		(fp_poly
			(pts
				(xy -1.778 1.8796) (xy -1.778 -1.8796) (xy 1.778 -1.8796) (xy 1.778 1.8796)
			)
			(stroke
				(width 0)
				(type default)
			)
			(fill no)
			(layer "F.CrtYd")
		)
		(fp_poly
			(pts
				(xy -1.778 1.8796) (xy -1.778 -1.8796) (xy 1.778 -1.8796) (xy 1.778 1.8796)
			)
			(stroke
				(width 0)
				(type default)
			)
			(fill no)
			(layer "F.Fab")
		)
		(pad "D" smd custom
			(at 0 -0.9525 90)
			(size 0.1905 0.1905)
			(layers "F.Cu" "F.Mask" "F.Paste")
			(net "ATTN_LED_DR14_MOS_N")
			(options
				(clearance outline)
				(anchor circle)
			)
			(primitives
				(gr_poly
					(pts
						(arc
							(start -0.1778 0.5715)
							(mid -0.321484 0.511984)
							(end -0.381 0.3683)
						)
						(arc
							(start -0.381 -0.3683)
							(mid -0.321484 -0.511984)
							(end -0.1778 -0.5715)
						)
						(arc
							(start 0.1778 -0.5715)
							(mid 0.321484 -0.511984)
							(end 0.381 -0.3683)
						)
						(arc
							(start 0.381 0.3683)
							(mid 0.321484 0.511984)
							(end 0.1778 0.5715)
						)
					)
					(width 0)
					(fill yes)
				)
			)
		)
		(pad "G" smd custom
			(at -0.98425 0.9525 90)
			(size 0.1905 0.1905)
			(layers "F.Cu" "F.Mask" "F.Paste")
			(net "SSD14_CLK0_OE_MOS_N")
			(options
				(clearance outline)
				(anchor circle)
			)
			(primitives
				(gr_poly
					(pts
						(arc
							(start -0.1778 0.5715)
							(mid -0.321484 0.511984)
							(end -0.381 0.3683)
						)
						(arc
							(start -0.381 -0.3683)
							(mid -0.321484 -0.511984)
							(end -0.1778 -0.5715)
						)
						(arc
							(start 0.1778 -0.5715)
							(mid 0.321484 -0.511984)
							(end 0.381 -0.3683)
						)
						(arc
							(start 0.381 0.3683)
							(mid 0.321484 0.511984)
							(end 0.1778 0.5715)
						)
					)
					(width 0)
					(fill yes)
				)
			)
		)
		(pad "S" smd custom
			(at 0.98425 0.9525 90)
			(size 0.1905 0.1905)
			(layers "F.Cu" "F.Mask" "F.Paste")
			(net "ATTN_LED_DR14_R")
			(options
				(clearance outline)
				(anchor circle)
			)
			(primitives
				(gr_poly
					(pts
						(arc
							(start -0.1778 0.5715)
							(mid -0.321484 0.511984)
							(end -0.381 0.3683)
						)
						(arc
							(start -0.381 -0.3683)
							(mid -0.321484 -0.511984)
							(end -0.1778 -0.5715)
						)
						(arc
							(start 0.1778 -0.5715)
							(mid 0.321484 -0.511984)
							(end 0.381 -0.3683)
						)
						(arc
							(start 0.381 0.3683)
							(mid 0.321484 0.511984)
							(end 0.1778 0.5715)
						)
					)
					(width 0)
					(fill yes)
				)
			)
		)
	)
	(footprint ""
		(layer "F.Cu")
		(at 224.623122 -424.443398 -90)
		(property "Reference" "PC1276"
			(at 0 0 270)
			(layer "F.SilkS")
			(hide yes)
			(effects
				(font
					(size 1.27 1.27)
				)
			)
		)
		(property "Value" "SC22U25V6KX-GP-U"
			(at -2.860802 -5.279644 270)
			(unlocked yes)
			(layer "F.Fab")
			(hide yes)
			(effects
				(font
					(size 1.016 1.016)
					(thickness 0.1524)
				)
			)
		)
		(property "Device Type" "C1206-TO0D3H75"
			(at -2.860802 -6.803644 270)
			(unlocked yes)
			(layer "F.Fab")
			(hide yes)
			(effects
				(font
					(size 1.016 1.016)
					(thickness 0.1524)
				)
			)
		)
		(duplicate_pad_numbers_are_jumpers no)
		(fp_line
			(start -1.3081 2.3749)
			(end -1.3081 -2.3749)
			(stroke
				(width 0.1524)
				(type default)
			)
			(layer "F.SilkS")
		)
		(fp_line
			(start 1.3081 2.3749)
			(end -1.3081 2.3749)
			(stroke
				(width 0.1524)
				(type default)
			)
			(layer "F.SilkS")
		)
		(fp_line
			(start -1.3081 -2.3749)
			(end 1.3081 -2.3749)
			(stroke
				(width 0.1524)
				(type default)
			)
			(layer "F.SilkS")
		)
		(fp_line
			(start 1.3081 -2.3749)
			(end 1.3081 2.3749)
			(stroke
				(width 0.1524)
				(type default)
			)
			(layer "F.SilkS")
		)
		(fp_rect
			(start -0.8001 1.6002)
			(end 0.8001 -1.6002)
			(stroke
				(width 0)
				(type default)
			)
			(fill no)
			(layer "F.CrtYd")
		)
		(fp_poly
			(pts
				(xy -1.5621 2.4511) (xy -1.5621 1.6002) (xy 0.8001 1.6002) (xy 0.8001 -1.6002) (xy -0.8001 -1.6002)
				(xy -0.8001 1.5875) (xy -1.5621 1.5875) (xy -1.5621 -2.4511) (xy 1.5621 -2.4511) (xy 1.5621 2.4511)
			)
			(stroke
				(width 0)
				(type default)
			)
			(fill no)
			(layer "F.CrtYd")
		)
		(fp_rect
			(start -1.5621 2.4511)
			(end 1.5621 -2.4511)
			(stroke
				(width 0)
				(type default)
			)
			(fill no)
			(layer "F.Fab")
		)
		(pad "1" smd rect
			(at 0 -1.392936 270)
			(size 2.1082 1.4478)
			(layers "F.Cu" "F.Mask" "F.Paste")
			(net "P3V3_VIN")
		)
		(pad "2" smd rect
			(at 0 1.392936 270)
			(size 2.1082 1.4478)
			(layers "F.Cu" "F.Mask" "F.Paste")
			(net "GND")
		)
	)
	(footprint ""
		(layer "F.Cu")
		(at 221.361 -474.218 180)
		(property "Reference" "PC1189"
			(at 0 0 180)
			(layer "F.SilkS")
			(hide yes)
			(effects
				(font
					(size 1.27 1.27)
				)
			)
		)
		(property "Value" "SCD1U25V3KX-GP"
			(at 0 -2.8194 180)
			(unlocked yes)
			(layer "F.Fab")
			(hide yes)
			(effects
				(font
					(size 1.016 1.016)
					(thickness 0.1524)
				)
			)
		)
		(property "Device Type" "C603H36"
			(at 0 -4.3434 180)
			(unlocked yes)
			(layer "F.Fab")
			(hide yes)
			(effects
				(font
					(size 1.016 1.016)
					(thickness 0.1524)
				)
			)
		)
		(duplicate_pad_numbers_are_jumpers no)
		(fp_line
			(start 0.508 0)
			(end -0.508 0)
			(stroke
				(width 0.2032)
				(type default)
			)
			(layer "F.SilkS")
		)
		(fp_rect
			(start -0.5842 1.3335)
			(end 0.5842 -1.3335)
			(stroke
				(width 0)
				(type default)
			)
			(fill no)
			(layer "F.CrtYd")
		)
		(fp_rect
			(start -0.5842 1.3335)
			(end 0.5842 -1.3335)
			(stroke
				(width 0)
				(type default)
			)
			(fill no)
			(layer "F.Fab")
		)
		(pad "1" smd custom
			(at 0 -0.762 180)
			(size 0.2159 0.2159)
			(layers "F.Cu" "F.Mask" "F.Paste")
			(net "P3V3")
			(options
				(clearance outline)
				(anchor circle)
			)
			(primitives
				(gr_poly
					(pts
						(arc
							(start -0.3302 -0.4318)
							(mid -0.402042 -0.402042)
							(end -0.4318 -0.3302)
						)
						(arc
							(start -0.4318 0.3302)
							(mid -0.402042 0.402042)
							(end -0.3302 0.4318)
						)
						(arc
							(start 0.3302 0.4318)
							(mid 0.402042 0.402042)
							(end 0.4318 0.3302)
						)
						(arc
							(start 0.4318 -0.3302)
							(mid 0.402042 -0.402042)
							(end 0.3302 -0.4318)
						)
					)
					(width 0)
					(fill yes)
				)
			)
		)
		(pad "2" smd custom
			(at 0 0.762 180)
			(size 0.2159 0.2159)
			(layers "F.Cu" "F.Mask" "F.Paste")
			(net "GND")
			(options
				(clearance outline)
				(anchor circle)
			)
			(primitives
				(gr_poly
					(pts
						(arc
							(start -0.3302 -0.4318)
							(mid -0.402042 -0.402042)
							(end -0.4318 -0.3302)
						)
						(arc
							(start -0.4318 0.3302)
							(mid -0.402042 0.402042)
							(end -0.3302 0.4318)
						)
						(arc
							(start 0.3302 0.4318)
							(mid 0.402042 0.402042)
							(end 0.4318 0.3302)
						)
						(arc
							(start 0.4318 -0.3302)
							(mid 0.402042 -0.402042)
							(end 0.3302 -0.4318)
						)
					)
					(width 0)
					(fill yes)
				)
			)
		)
	)
	(footprint ""
		(layer "F.Cu")
		(at 85.5472 -210.3247 180)
		(property "Reference" "R9969"
			(at 0 0 180)
			(layer "F.SilkS")
			(hide yes)
			(effects
				(font
					(size 1.27 1.27)
				)
			)
		)
		(property "Value" "100R1F-GP"
			(at -3.3274 -1.3335 180)
			(unlocked yes)
			(layer "F.Fab")
			(hide yes)
			(effects
				(font
					(size 1.016 1.016)
					(thickness 0.1524)
				)
			)
		)
		(property "Device Type" "R0201H12"
			(at -3.3274 -2.8575 180)
			(unlocked yes)
			(layer "F.Fab")
			(hide yes)
			(effects
				(font
					(size 1.016 1.016)
					(thickness 0.1524)
				)
			)
		)
		(duplicate_pad_numbers_are_jumpers no)
		(fp_rect
			(start -0.2794 0.6477)
			(end 0.2794 -0.6477)
			(stroke
				(width 0)
				(type default)
			)
			(fill no)
			(layer "F.CrtYd")
		)
		(fp_rect
			(start -0.2794 0.6477)
			(end 0.2794 -0.6477)
			(stroke
				(width 0)
				(type default)
			)
			(fill no)
			(layer "F.Fab")
		)
		(pad "1" smd custom
			(at 0 -0.2794 180)
			(size 0.0762 0.0762)
			(layers "F.Cu" "F.Mask" "F.Paste")
			(net "PE_100M_CLK2_N")
			(options
				(clearance outline)
				(anchor circle)
			)
			(primitives
				(gr_poly
					(pts
						(arc
							(start 0.1524 -0.127)
							(mid 0.137521 -0.162921)
							(end 0.1016 -0.1778)
						)
						(arc
							(start -0.1016 -0.1778)
							(mid -0.137521 -0.162921)
							(end -0.1524 -0.127)
						)
						(arc
							(start -0.1524 0.127)
							(mid -0.137521 0.162921)
							(end -0.1016 0.1778)
						)
						(arc
							(start 0.1016 0.1778)
							(mid 0.137521 0.162921)
							(end 0.1524 0.127)
						)
					)
					(width 0)
					(fill yes)
				)
			)
		)
		(pad "2" smd custom
			(at 0 0.2794 180)
			(size 0.0762 0.0762)
			(layers "F.Cu" "F.Mask" "F.Paste")
			(net "PE_100M_CLK2_P")
			(options
				(clearance outline)
				(anchor circle)
			)
			(primitives
				(gr_poly
					(pts
						(arc
							(start 0.1524 -0.127)
							(mid 0.137521 -0.162921)
							(end 0.1016 -0.1778)
						)
						(arc
							(start -0.1016 -0.1778)
							(mid -0.137521 -0.162921)
							(end -0.1524 -0.127)
						)
						(arc
							(start -0.1524 0.127)
							(mid -0.137521 0.162921)
							(end -0.1016 0.1778)
						)
						(arc
							(start 0.1016 0.1778)
							(mid 0.137521 0.162921)
							(end 0.1524 0.127)
						)
					)
					(width 0)
					(fill yes)
				)
			)
		)
	)
	(footprint ""
		(layer "F.Cu")
		(at 21.5138 -192.532)
		(property "Reference" "D26"
			(at 0 0 0)
			(layer "F.SilkS")
			(hide yes)
			(effects
				(font
					(size 1.27 1.27)
				)
			)
		)
		(property "Value" "RB551V30-1-GP"
			(at 0 -6.7818 0)
			(unlocked yes)
			(layer "F.Fab")
			(hide yes)
			(effects
				(font
					(size 1.016 1.016)
					(thickness 0.1524)
				)
			)
		)
		(property "Device Type" "SOD323AKH44"
			(at 0 -8.6868 0)
			(unlocked yes)
			(layer "F.Fab")
			(hide yes)
			(effects
				(font
					(size 1.016 1.016)
					(thickness 0.1524)
				)
			)
		)
		(duplicate_pad_numbers_are_jumpers no)
		(fp_line
			(start -0.889 -1.9304)
			(end 0.889 -1.9304)
			(stroke
				(width 0.1524)
				(type default)
			)
			(layer "F.SilkS")
		)
		(fp_line
			(start -0.889 2.159)
			(end -0.889 -1.9304)
			(stroke
				(width 0.1524)
				(type default)
			)
			(layer "F.SilkS")
		)
		(fp_line
			(start 0.762 2.0574)
			(end -0.762 2.0574)
			(stroke
				(width 0.508)
				(type default)
			)
			(layer "F.SilkS")
		)
		(fp_line
			(start 0.889 -1.9304)
			(end 0.889 2.159)
			(stroke
				(width 0.1524)
				(type default)
			)
			(layer "F.SilkS")
		)
		(fp_line
			(start 0.889 2.159)
			(end -0.889 2.159)
			(stroke
				(width 0.1524)
				(type default)
			)
			(layer "F.SilkS")
		)
		(fp_rect
			(start -1.016 2.3114)
			(end 1.016 -2.0066)
			(stroke
				(width 0)
				(type default)
			)
			(fill no)
			(layer "F.CrtYd")
		)
		(fp_poly
			(pts
				(xy -1.016 -2.0066) (xy 1.016 -2.0066) (xy 1.016 2.3114) (xy -1.016 2.3114)
			)
			(stroke
				(width 0)
				(type default)
			)
			(fill no)
			(layer "F.Fab")
		)
		(pad "A" smd rect
			(at 0 -1.143)
			(size 0.5588 1.016)
			(layers "F.Cu" "F.Mask" "F.Paste")
			(net "SW_SSD8_R")
		)
		(pad "K" smd rect
			(at 0 1.143)
			(size 0.5588 1.016)
			(layers "F.Cu" "F.Mask" "F.Paste")
			(net "SW_SSD8_N")
		)
	)
	(footprint ""
		(layer "F.Cu")
		(at 85.471 -98.806 90)
		(property "Reference" "R9121"
			(at 0 0 90)
			(layer "F.SilkS")
			(hide yes)
			(effects
				(font
					(size 1.27 1.27)
				)
			)
		)
		(property "Value" "4K7R2F-GP"
			(at 0.064008 -3.993896 90)
			(unlocked yes)
			(layer "F.Fab")
			(hide yes)
			(effects
				(font
					(size 1.016 1.016)
					(thickness 0.1524)
				)
			)
		)
		(property "Device Type" "R402H16"
			(at 0.064008 -5.517896 90)
			(unlocked yes)
			(layer "F.Fab")
			(hide yes)
			(effects
				(font
					(size 1.016 1.016)
					(thickness 0.1524)
				)
			)
		)
		(duplicate_pad_numbers_are_jumpers no)
		(fp_line
			(start 0.508 -0.9398)
			(end -0.508 -0.9398)
			(stroke
				(width 0.1524)
				(type default)
			)
			(layer "F.SilkS")
		)
		(fp_line
			(start -0.508 -0.9398)
			(end -0.508 0.9398)
			(stroke
				(width 0.1524)
				(type default)
			)
			(layer "F.SilkS")
		)
		(fp_rect
			(start -0.508 0.9398)
			(end 0.508 -0.9398)
			(stroke
				(width 0)
				(type default)
			)
			(fill no)
			(layer "F.CrtYd")
		)
		(fp_rect
			(start -0.508 0.9398)
			(end 0.508 -0.9398)
			(stroke
				(width 0)
				(type default)
			)
			(fill no)
			(layer "F.Fab")
		)
		(pad "1" smd custom
			(at 0 -0.4445 90)
			(size 0.1397 0.1397)
			(layers "F.Cu" "F.Mask" "F.Paste")
			(net "VDD_DIFF_4")
			(options
				(clearance outline)
				(anchor circle)
			)
			(primitives
				(gr_poly
					(pts
						(arc
							(start -0.1778 -0.2794)
							(mid -0.249642 -0.249642)
							(end -0.2794 -0.1778)
						)
						(arc
							(start -0.2794 0.1778)
							(mid -0.249642 0.249642)
							(end -0.1778 0.2794)
						)
						(arc
							(start 0.1778 0.2794)
							(mid 0.249642 0.249642)
							(end 0.2794 0.1778)
						)
						(arc
							(start 0.2794 -0.1778)
							(mid 0.249642 -0.249642)
							(end 0.1778 -0.2794)
						)
					)
					(width 0)
					(fill yes)
				)
			)
		)
		(pad "2" smd custom
			(at 0 0.4445 90)
			(size 0.1397 0.1397)
			(layers "F.Cu" "F.Mask" "F.Paste")
			(net "CLK_BUF_EU4_SMB_A0_TRI")
			(options
				(clearance outline)
				(anchor circle)
			)
			(primitives
				(gr_poly
					(pts
						(arc
							(start -0.1778 -0.2794)
							(mid -0.249642 -0.249642)
							(end -0.2794 -0.1778)
						)
						(arc
							(start -0.2794 0.1778)
							(mid -0.249642 0.249642)
							(end -0.1778 0.2794)
						)
						(arc
							(start 0.1778 0.2794)
							(mid 0.249642 0.249642)
							(end 0.2794 0.1778)
						)
						(arc
							(start 0.2794 -0.1778)
							(mid 0.249642 -0.249642)
							(end 0.1778 -0.2794)
						)
					)
					(width 0)
					(fill yes)
				)
			)
		)
	)
	(footprint ""
		(layer "F.Cu")
		(at 209.296 -190.119 180)
		(property "Reference" "R569"
			(at 0 0 180)
			(layer "F.SilkS")
			(hide yes)
			(effects
				(font
					(size 1.27 1.27)
				)
			)
		)
		(property "Value" "300KR2F-GP"
			(at 0.064008 -3.993896 180)
			(unlocked yes)
			(layer "F.Fab")
			(hide yes)
			(effects
				(font
					(size 1.016 1.016)
					(thickness 0.1524)
				)
			)
		)
		(property "Device Type" "R402H16"
			(at 0.064008 -5.517896 180)
			(unlocked yes)
			(layer "F.Fab")
			(hide yes)
			(effects
				(font
					(size 1.016 1.016)
					(thickness 0.1524)
				)
			)
		)
		(duplicate_pad_numbers_are_jumpers no)
		(fp_line
			(start 0.508 -0.9398)
			(end -0.508 -0.9398)
			(stroke
				(width 0.1524)
				(type default)
			)
			(layer "F.SilkS")
		)
		(fp_line
			(start -0.508 -0.9398)
			(end -0.508 0.9398)
			(stroke
				(width 0.1524)
				(type default)
			)
			(layer "F.SilkS")
		)
		(fp_rect
			(start -0.508 0.9398)
			(end 0.508 -0.9398)
			(stroke
				(width 0)
				(type default)
			)
			(fill no)
			(layer "F.CrtYd")
		)
		(fp_rect
			(start -0.508 0.9398)
			(end 0.508 -0.9398)
			(stroke
				(width 0)
				(type default)
			)
			(fill no)
			(layer "F.Fab")
		)
		(pad "1" smd custom
			(at 0 -0.4445 180)
			(size 0.1397 0.1397)
			(layers "F.Cu" "F.Mask" "F.Paste")
			(net "SW_SSD3_N")
			(options
				(clearance outline)
				(anchor circle)
			)
			(primitives
				(gr_poly
					(pts
						(arc
							(start -0.1778 -0.2794)
							(mid -0.249642 -0.249642)
							(end -0.2794 -0.1778)
						)
						(arc
							(start -0.2794 0.1778)
							(mid -0.249642 0.249642)
							(end -0.1778 0.2794)
						)
						(arc
							(start 0.1778 0.2794)
							(mid 0.249642 0.249642)
							(end 0.2794 0.1778)
						)
						(arc
							(start 0.2794 -0.1778)
							(mid 0.249642 -0.249642)
							(end 0.1778 -0.2794)
						)
					)
					(width 0)
					(fill yes)
				)
			)
		)
		(pad "2" smd custom
			(at 0 0.4445 180)
			(size 0.1397 0.1397)
			(layers "F.Cu" "F.Mask" "F.Paste")
			(net "P12V")
			(options
				(clearance outline)
				(anchor circle)
			)
			(primitives
				(gr_poly
					(pts
						(arc
							(start -0.1778 -0.2794)
							(mid -0.249642 -0.249642)
							(end -0.2794 -0.1778)
						)
						(arc
							(start -0.2794 0.1778)
							(mid -0.249642 0.249642)
							(end -0.1778 0.2794)
						)
						(arc
							(start 0.1778 0.2794)
							(mid 0.249642 0.249642)
							(end 0.2794 0.1778)
						)
						(arc
							(start 0.2794 -0.1778)
							(mid 0.249642 -0.249642)
							(end 0.1778 -0.2794)
						)
					)
					(width 0)
					(fill yes)
				)
			)
		)
	)
	(footprint ""
		(layer "F.Cu")
		(at 49.276 -246.253 -90)
		(property "Reference" "R9899"
			(at 0 0 270)
			(layer "F.SilkS")
			(hide yes)
			(effects
				(font
					(size 1.27 1.27)
				)
			)
		)
		(property "Value" "1K82R2F-1-GP"
			(at 0.064008 -3.993896 270)
			(unlocked yes)
			(layer "F.Fab")
			(hide yes)
			(effects
				(font
					(size 1.016 1.016)
					(thickness 0.1524)
				)
			)
		)
		(property "Device Type" "R402H16"
			(at 0.064008 -5.517896 270)
			(unlocked yes)
			(layer "F.Fab")
			(hide yes)
			(effects
				(font
					(size 1.016 1.016)
					(thickness 0.1524)
				)
			)
		)
		(duplicate_pad_numbers_are_jumpers no)
		(fp_line
			(start -0.508 -0.9398)
			(end -0.508 0.9398)
			(stroke
				(width 0.1524)
				(type default)
			)
			(layer "F.SilkS")
		)
		(fp_line
			(start 0.508 -0.9398)
			(end -0.508 -0.9398)
			(stroke
				(width 0.1524)
				(type default)
			)
			(layer "F.SilkS")
		)
		(fp_rect
			(start -0.508 0.9398)
			(end 0.508 -0.9398)
			(stroke
				(width 0)
				(type default)
			)
			(fill no)
			(layer "F.CrtYd")
		)
		(fp_rect
			(start -0.508 0.9398)
			(end 0.508 -0.9398)
			(stroke
				(width 0)
				(type default)
			)
			(fill no)
			(layer "F.Fab")
		)
		(pad "1" smd custom
			(at 0 -0.4445 270)
			(size 0.1397 0.1397)
			(layers "F.Cu" "F.Mask" "F.Paste")
			(net "P12V")
			(options
				(clearance outline)
				(anchor circle)
			)
			(primitives
				(gr_poly
					(pts
						(arc
							(start -0.1778 -0.2794)
							(mid -0.249642 -0.249642)
							(end -0.2794 -0.1778)
						)
						(arc
							(start -0.2794 0.1778)
							(mid -0.249642 0.249642)
							(end -0.1778 0.2794)
						)
						(arc
							(start 0.1778 0.2794)
							(mid 0.249642 0.249642)
							(end 0.2794 0.1778)
						)
						(arc
							(start 0.2794 -0.1778)
							(mid 0.249642 -0.249642)
							(end 0.1778 -0.2794)
						)
					)
					(width 0)
					(fill yes)
				)
			)
		)
		(pad "2" smd custom
			(at 0 0.4445 270)
			(size 0.1397 0.1397)
			(layers "F.Cu" "F.Mask" "F.Paste")
			(net "DRV_ACT_7")
			(options
				(clearance outline)
				(anchor circle)
			)
			(primitives
				(gr_poly
					(pts
						(arc
							(start -0.1778 -0.2794)
							(mid -0.249642 -0.249642)
							(end -0.2794 -0.1778)
						)
						(arc
							(start -0.2794 0.1778)
							(mid -0.249642 0.249642)
							(end -0.1778 0.2794)
						)
						(arc
							(start 0.1778 0.2794)
							(mid 0.249642 0.249642)
							(end 0.2794 0.1778)
						)
						(arc
							(start 0.2794 -0.1778)
							(mid 0.249642 -0.249642)
							(end 0.1778 -0.2794)
						)
					)
					(width 0)
					(fill yes)
				)
			)
		)
	)
	(footprint ""
		(layer "F.Cu")
		(at 21.336 -396.24)
		(property "Reference" "D24"
			(at 0 0 0)
			(layer "F.SilkS")
			(hide yes)
			(effects
				(font
					(size 1.27 1.27)
				)
			)
		)
		(property "Value" "RB551V30-1-GP"
			(at 0 -6.7818 0)
			(unlocked yes)
			(layer "F.Fab")
			(hide yes)
			(effects
				(font
					(size 1.016 1.016)
					(thickness 0.1524)
				)
			)
		)
		(property "Device Type" "SOD323AKH44"
			(at 0 -8.6868 0)
			(unlocked yes)
			(layer "F.Fab")
			(hide yes)
			(effects
				(font
					(size 1.016 1.016)
					(thickness 0.1524)
				)
			)
		)
		(duplicate_pad_numbers_are_jumpers no)
		(fp_line
			(start -0.889 -1.9304)
			(end 0.889 -1.9304)
			(stroke
				(width 0.1524)
				(type default)
			)
			(layer "F.SilkS")
		)
		(fp_line
			(start -0.889 2.159)
			(end -0.889 -1.9304)
			(stroke
				(width 0.1524)
				(type default)
			)
			(layer "F.SilkS")
		)
		(fp_line
			(start 0.762 2.0574)
			(end -0.762 2.0574)
			(stroke
				(width 0.508)
				(type default)
			)
			(layer "F.SilkS")
		)
		(fp_line
			(start 0.889 -1.9304)
			(end 0.889 2.159)
			(stroke
				(width 0.1524)
				(type default)
			)
			(layer "F.SilkS")
		)
		(fp_line
			(start 0.889 2.159)
			(end -0.889 2.159)
			(stroke
				(width 0.1524)
				(type default)
			)
			(layer "F.SilkS")
		)
		(fp_rect
			(start -1.016 2.3114)
			(end 1.016 -2.0066)
			(stroke
				(width 0)
				(type default)
			)
			(fill no)
			(layer "F.CrtYd")
		)
		(fp_poly
			(pts
				(xy -1.016 -2.0066) (xy 1.016 -2.0066) (xy 1.016 2.3114) (xy -1.016 2.3114)
			)
			(stroke
				(width 0)
				(type default)
			)
			(fill no)
			(layer "F.Fab")
		)
		(pad "A" smd rect
			(at 0 -1.143)
			(size 0.5588 1.016)
			(layers "F.Cu" "F.Mask" "F.Paste")
			(net "SW_SSD6_R")
		)
		(pad "K" smd rect
			(at 0 1.143)
			(size 0.5588 1.016)
			(layers "F.Cu" "F.Mask" "F.Paste")
			(net "SW_SSD6_N")
		)
	)
	(footprint ""
		(layer "F.Cu")
		(at 74.041 -454.66)
		(property "Reference" "R345"
			(at 0 0 0)
			(layer "F.SilkS")
			(hide yes)
			(effects
				(font
					(size 1.27 1.27)
				)
			)
		)
		(property "Value" "4K7R2J-2-GP"
			(at 0.064008 -3.993896 0)
			(unlocked yes)
			(layer "F.Fab")
			(hide yes)
			(effects
				(font
					(size 1.016 1.016)
					(thickness 0.1524)
				)
			)
		)
		(property "Device Type" "R402H16"
			(at 0.064008 -5.517896 0)
			(unlocked yes)
			(layer "F.Fab")
			(hide yes)
			(effects
				(font
					(size 1.016 1.016)
					(thickness 0.1524)
				)
			)
		)
		(duplicate_pad_numbers_are_jumpers no)
		(fp_line
			(start -0.508 -0.9398)
			(end -0.508 0.9398)
			(stroke
				(width 0.1524)
				(type default)
			)
			(layer "F.SilkS")
		)
		(fp_line
			(start 0.508 -0.9398)
			(end -0.508 -0.9398)
			(stroke
				(width 0.1524)
				(type default)
			)
			(layer "F.SilkS")
		)
		(fp_rect
			(start -0.508 0.9398)
			(end 0.508 -0.9398)
			(stroke
				(width 0)
				(type default)
			)
			(fill no)
			(layer "F.CrtYd")
		)
		(fp_rect
			(start -0.508 0.9398)
			(end 0.508 -0.9398)
			(stroke
				(width 0)
				(type default)
			)
			(fill no)
			(layer "F.Fab")
		)
		(pad "1" smd custom
			(at 0 -0.4445)
			(size 0.1397 0.1397)
			(layers "F.Cu" "F.Mask" "F.Paste")
			(net "P3V3")
			(options
				(clearance outline)
				(anchor circle)
			)
			(primitives
				(gr_poly
					(pts
						(arc
							(start -0.1778 -0.2794)
							(mid -0.249642 -0.249642)
							(end -0.2794 -0.1778)
						)
						(arc
							(start -0.2794 0.1778)
							(mid -0.249642 0.249642)
							(end -0.1778 0.2794)
						)
						(arc
							(start 0.1778 0.2794)
							(mid 0.249642 0.249642)
							(end 0.2794 0.1778)
						)
						(arc
							(start 0.2794 -0.1778)
							(mid 0.249642 -0.249642)
							(end 0.1778 -0.2794)
						)
					)
					(width 0)
					(fill yes)
				)
			)
		)
		(pad "2" smd custom
			(at 0 0.4445)
			(size 0.1397 0.1397)
			(layers "F.Cu" "F.Mask" "F.Paste")
			(net "EEPROM_A0")
			(options
				(clearance outline)
				(anchor circle)
			)
			(primitives
				(gr_poly
					(pts
						(arc
							(start -0.1778 -0.2794)
							(mid -0.249642 -0.249642)
							(end -0.2794 -0.1778)
						)
						(arc
							(start -0.2794 0.1778)
							(mid -0.249642 0.249642)
							(end -0.1778 0.2794)
						)
						(arc
							(start 0.1778 0.2794)
							(mid 0.249642 0.249642)
							(end 0.2794 0.1778)
						)
						(arc
							(start 0.2794 -0.1778)
							(mid 0.249642 -0.249642)
							(end 0.1778 -0.2794)
						)
					)
					(width 0)
					(fill yes)
				)
			)
		)
	)
	(footprint ""
		(layer "F.Cu")
		(at 27.5336 -105.3592)
		(property "Reference" "PC1212"
			(at 0 0 0)
			(layer "F.SilkS")
			(hide yes)
			(effects
				(font
					(size 1.27 1.27)
				)
			)
		)
		(property "Value" "SCD1U50V3KX-GP"
			(at 0 -2.8194 0)
			(unlocked yes)
			(layer "F.Fab")
			(hide yes)
			(effects
				(font
					(size 1.016 1.016)
					(thickness 0.1524)
				)
			)
		)
		(property "Device Type" "C603H36"
			(at 0 -4.3434 0)
			(unlocked yes)
			(layer "F.Fab")
			(hide yes)
			(effects
				(font
					(size 1.016 1.016)
					(thickness 0.1524)
				)
			)
		)
		(duplicate_pad_numbers_are_jumpers no)
		(fp_line
			(start 0.508 0)
			(end -0.508 0)
			(stroke
				(width 0.2032)
				(type default)
			)
			(layer "F.SilkS")
		)
		(fp_rect
			(start -0.5842 1.3335)
			(end 0.5842 -1.3335)
			(stroke
				(width 0)
				(type default)
			)
			(fill no)
			(layer "F.CrtYd")
		)
		(fp_rect
			(start -0.5842 1.3335)
			(end 0.5842 -1.3335)
			(stroke
				(width 0)
				(type default)
			)
			(fill no)
			(layer "F.Fab")
		)
		(pad "1" smd custom
			(at 0 -0.762)
			(size 0.2159 0.2159)
			(layers "F.Cu" "F.Mask" "F.Paste")
			(net "P12V_SSD13")
			(options
				(clearance outline)
				(anchor circle)
			)
			(primitives
				(gr_poly
					(pts
						(arc
							(start -0.3302 -0.4318)
							(mid -0.402042 -0.402042)
							(end -0.4318 -0.3302)
						)
						(arc
							(start -0.4318 0.3302)
							(mid -0.402042 0.402042)
							(end -0.3302 0.4318)
						)
						(arc
							(start 0.3302 0.4318)
							(mid 0.402042 0.402042)
							(end 0.4318 0.3302)
						)
						(arc
							(start 0.4318 -0.3302)
							(mid 0.402042 -0.402042)
							(end 0.3302 -0.4318)
						)
					)
					(width 0)
					(fill yes)
				)
			)
		)
		(pad "2" smd custom
			(at 0 0.762)
			(size 0.2159 0.2159)
			(layers "F.Cu" "F.Mask" "F.Paste")
			(net "GND")
			(options
				(clearance outline)
				(anchor circle)
			)
			(primitives
				(gr_poly
					(pts
						(arc
							(start -0.3302 -0.4318)
							(mid -0.402042 -0.402042)
							(end -0.4318 -0.3302)
						)
						(arc
							(start -0.4318 0.3302)
							(mid -0.402042 0.402042)
							(end -0.3302 0.4318)
						)
						(arc
							(start 0.3302 0.4318)
							(mid 0.402042 0.402042)
							(end 0.4318 0.3302)
						)
						(arc
							(start 0.4318 -0.3302)
							(mid 0.402042 -0.402042)
							(end 0.3302 -0.4318)
						)
					)
					(width 0)
					(fill yes)
				)
			)
		)
	)
	(footprint ""
		(layer "F.Cu")
		(at 208.153 -87.122)
		(property "Reference" "R555"
			(at 0 0 0)
			(layer "F.SilkS")
			(hide yes)
			(effects
				(font
					(size 1.27 1.27)
				)
			)
		)
		(property "Value" "200KR2F-L-GP"
			(at 0.064008 -3.993896 0)
			(unlocked yes)
			(layer "F.Fab")
			(hide yes)
			(effects
				(font
					(size 1.016 1.016)
					(thickness 0.1524)
				)
			)
		)
		(property "Device Type" "R402H16"
			(at 0.064008 -5.517896 0)
			(unlocked yes)
			(layer "F.Fab")
			(hide yes)
			(effects
				(font
					(size 1.016 1.016)
					(thickness 0.1524)
				)
			)
		)
		(duplicate_pad_numbers_are_jumpers no)
		(fp_line
			(start -0.508 -0.9398)
			(end -0.508 0.9398)
			(stroke
				(width 0.1524)
				(type default)
			)
			(layer "F.SilkS")
		)
		(fp_line
			(start 0.508 -0.9398)
			(end -0.508 -0.9398)
			(stroke
				(width 0.1524)
				(type default)
			)
			(layer "F.SilkS")
		)
		(fp_rect
			(start -0.508 0.9398)
			(end 0.508 -0.9398)
			(stroke
				(width 0)
				(type default)
			)
			(fill no)
			(layer "F.CrtYd")
		)
		(fp_rect
			(start -0.508 0.9398)
			(end 0.508 -0.9398)
			(stroke
				(width 0)
				(type default)
			)
			(fill no)
			(layer "F.Fab")
		)
		(pad "1" smd custom
			(at 0 -0.4445)
			(size 0.1397 0.1397)
			(layers "F.Cu" "F.Mask" "F.Paste")
			(net "SW_SSD4_R")
			(options
				(clearance outline)
				(anchor circle)
			)
			(primitives
				(gr_poly
					(pts
						(arc
							(start -0.1778 -0.2794)
							(mid -0.249642 -0.249642)
							(end -0.2794 -0.1778)
						)
						(arc
							(start -0.2794 0.1778)
							(mid -0.249642 0.249642)
							(end -0.1778 0.2794)
						)
						(arc
							(start 0.1778 0.2794)
							(mid 0.249642 0.249642)
							(end 0.2794 0.1778)
						)
						(arc
							(start 0.2794 -0.1778)
							(mid 0.249642 -0.249642)
							(end 0.1778 -0.2794)
						)
					)
					(width 0)
					(fill yes)
				)
			)
		)
		(pad "2" smd custom
			(at 0 0.4445)
			(size 0.1397 0.1397)
			(layers "F.Cu" "F.Mask" "F.Paste")
			(net "SW_SSD4_N")
			(options
				(clearance outline)
				(anchor circle)
			)
			(primitives
				(gr_poly
					(pts
						(arc
							(start -0.1778 -0.2794)
							(mid -0.249642 -0.249642)
							(end -0.2794 -0.1778)
						)
						(arc
							(start -0.2794 0.1778)
							(mid -0.249642 0.249642)
							(end -0.1778 0.2794)
						)
						(arc
							(start 0.1778 0.2794)
							(mid 0.249642 0.249642)
							(end 0.2794 0.1778)
						)
						(arc
							(start 0.2794 -0.1778)
							(mid 0.249642 -0.249642)
							(end 0.1778 -0.2794)
						)
					)
					(width 0)
					(fill yes)
				)
			)
		)
	)
	(footprint ""
		(layer "F.Cu")
		(at 52.832 -12.446 180)
		(property "Reference" "D32"
			(at 0 0 180)
			(layer "F.SilkS")
			(hide yes)
			(effects
				(font
					(size 1.27 1.27)
				)
			)
		)
		(property "Value" "RB551V30-1-GP"
			(at 0 -6.7818 180)
			(unlocked yes)
			(layer "F.Fab")
			(hide yes)
			(effects
				(font
					(size 1.016 1.016)
					(thickness 0.1524)
				)
			)
		)
		(property "Device Type" "SOD323AKH44"
			(at 0 -8.6868 180)
			(unlocked yes)
			(layer "F.Fab")
			(hide yes)
			(effects
				(font
					(size 1.016 1.016)
					(thickness 0.1524)
				)
			)
		)
		(duplicate_pad_numbers_are_jumpers no)
		(fp_line
			(start 0.889 2.159)
			(end -0.889 2.159)
			(stroke
				(width 0.1524)
				(type default)
			)
			(layer "F.SilkS")
		)
		(fp_line
			(start 0.889 -1.9304)
			(end 0.889 2.159)
			(stroke
				(width 0.1524)
				(type default)
			)
			(layer "F.SilkS")
		)
		(fp_line
			(start 0.762 2.0574)
			(end -0.762 2.0574)
			(stroke
				(width 0.508)
				(type default)
			)
			(layer "F.SilkS")
		)
		(fp_line
			(start -0.889 2.159)
			(end -0.889 -1.9304)
			(stroke
				(width 0.1524)
				(type default)
			)
			(layer "F.SilkS")
		)
		(fp_line
			(start -0.889 -1.9304)
			(end 0.889 -1.9304)
			(stroke
				(width 0.1524)
				(type default)
			)
			(layer "F.SilkS")
		)
		(fp_rect
			(start -1.016 2.3114)
			(end 1.016 -2.0066)
			(stroke
				(width 0)
				(type default)
			)
			(fill no)
			(layer "F.CrtYd")
		)
		(fp_poly
			(pts
				(xy -1.016 -2.0066) (xy 1.016 -2.0066) (xy 1.016 2.3114) (xy -1.016 2.3114)
			)
			(stroke
				(width 0)
				(type default)
			)
			(fill no)
			(layer "F.Fab")
		)
		(pad "A" smd rect
			(at 0 -1.143 180)
			(size 0.5588 1.016)
			(layers "F.Cu" "F.Mask" "F.Paste")
			(net "SW_SSD14_R")
		)
		(pad "K" smd rect
			(at 0 1.143 180)
			(size 0.5588 1.016)
			(layers "F.Cu" "F.Mask" "F.Paste")
			(net "SW_SSD14_N")
		)
	)
	(footprint ""
		(layer "F.Cu")
		(at 78.9686 -215.0618 -90)
		(property "Reference" "C8930"
			(at 0 0 270)
			(layer "F.SilkS")
			(hide yes)
			(effects
				(font
					(size 1.27 1.27)
				)
			)
		)
		(property "Value" "SC10U25V3MX-GP"
			(at 0 -2.8194 270)
			(unlocked yes)
			(layer "F.Fab")
			(hide yes)
			(effects
				(font
					(size 1.016 1.016)
					(thickness 0.1524)
				)
			)
		)
		(property "Device Type" "C603H40"
			(at 0 -4.3434 270)
			(unlocked yes)
			(layer "F.Fab")
			(hide yes)
			(effects
				(font
					(size 1.016 1.016)
					(thickness 0.1524)
				)
			)
		)
		(duplicate_pad_numbers_are_jumpers no)
		(fp_line
			(start 0.508 0)
			(end -0.508 0)
			(stroke
				(width 0.2032)
				(type default)
			)
			(layer "F.SilkS")
		)
		(fp_rect
			(start -0.5842 1.3335)
			(end 0.5842 -1.3335)
			(stroke
				(width 0)
				(type default)
			)
			(fill no)
			(layer "F.CrtYd")
		)
		(fp_rect
			(start -0.5842 1.3335)
			(end 0.5842 -1.3335)
			(stroke
				(width 0)
				(type default)
			)
			(fill no)
			(layer "F.Fab")
		)
		(pad "1" smd custom
			(at 0 -0.762 270)
			(size 0.2159 0.2159)
			(layers "F.Cu" "F.Mask" "F.Paste")
			(net "VDD_DIFF_3")
			(options
				(clearance outline)
				(anchor circle)
			)
			(primitives
				(gr_poly
					(pts
						(arc
							(start -0.3302 -0.4318)
							(mid -0.402042 -0.402042)
							(end -0.4318 -0.3302)
						)
						(arc
							(start -0.4318 0.3302)
							(mid -0.402042 0.402042)
							(end -0.3302 0.4318)
						)
						(arc
							(start 0.3302 0.4318)
							(mid 0.402042 0.402042)
							(end 0.4318 0.3302)
						)
						(arc
							(start 0.4318 -0.3302)
							(mid 0.402042 -0.402042)
							(end 0.3302 -0.4318)
						)
					)
					(width 0)
					(fill yes)
				)
			)
		)
		(pad "2" smd custom
			(at 0 0.762 270)
			(size 0.2159 0.2159)
			(layers "F.Cu" "F.Mask" "F.Paste")
			(net "GND")
			(options
				(clearance outline)
				(anchor circle)
			)
			(primitives
				(gr_poly
					(pts
						(arc
							(start -0.3302 -0.4318)
							(mid -0.402042 -0.402042)
							(end -0.4318 -0.3302)
						)
						(arc
							(start -0.4318 0.3302)
							(mid -0.402042 0.402042)
							(end -0.3302 0.4318)
						)
						(arc
							(start 0.3302 0.4318)
							(mid 0.402042 0.402042)
							(end 0.4318 0.3302)
						)
						(arc
							(start 0.4318 -0.3302)
							(mid 0.402042 -0.402042)
							(end 0.3302 -0.4318)
						)
					)
					(width 0)
					(fill yes)
				)
			)
		)
	)
	(footprint ""
		(layer "F.Cu")
		(at 232.029 -429.514 -90)
		(property "Reference" "PC1283"
			(at 0 0 270)
			(layer "F.SilkS")
			(hide yes)
			(effects
				(font
					(size 1.27 1.27)
				)
			)
		)
		(property "Value" "SC1KP50V2KX-1GP"
			(at 1.1811 -2.7051 270)
			(unlocked yes)
			(layer "F.Fab")
			(hide yes)
			(effects
				(font
					(size 1.016 1.016)
					(thickness 0.1524)
				)
			)
		)
		(property "Device Type" "C402H22"
			(at 1.1811 -4.2291 270)
			(unlocked yes)
			(layer "F.Fab")
			(hide yes)
			(effects
				(font
					(size 1.016 1.016)
					(thickness 0.1524)
				)
			)
		)
		(duplicate_pad_numbers_are_jumpers no)
		(fp_rect
			(start -0.4318 0.9525)
			(end 0.4318 -0.9525)
			(stroke
				(width 0)
				(type default)
			)
			(fill no)
			(layer "F.CrtYd")
		)
		(fp_rect
			(start -0.4318 0.9525)
			(end 0.4318 -0.9525)
			(stroke
				(width 0)
				(type default)
			)
			(fill no)
			(layer "F.Fab")
		)
		(pad "1" smd custom
			(at 0 -0.4445 270)
			(size 0.1524 0.1524)
			(layers "F.Cu" "F.Mask" "F.Paste")
			(net "P3V3_VFB_R")
			(options
				(clearance outline)
				(anchor circle)
			)
			(primitives
				(gr_poly
					(pts
						(arc
							(start 0.3048 -0.2032)
							(mid 0.275042 -0.275042)
							(end 0.2032 -0.3048)
						)
						(arc
							(start -0.2032 -0.3048)
							(mid -0.275042 -0.275042)
							(end -0.3048 -0.2032)
						)
						(arc
							(start -0.3048 0.2032)
							(mid -0.275042 0.275042)
							(end -0.2032 0.3048)
						)
						(arc
							(start 0.2032 0.3048)
							(mid 0.275042 0.275042)
							(end 0.3048 0.2032)
						)
					)
					(width 0)
					(fill yes)
				)
			)
		)
		(pad "2" smd custom
			(at 0 0.4445 270)
			(size 0.1524 0.1524)
			(layers "F.Cu" "F.Mask" "F.Paste")
			(net "P3V3_VFB")
			(options
				(clearance outline)
				(anchor circle)
			)
			(primitives
				(gr_poly
					(pts
						(arc
							(start 0.3048 -0.2032)
							(mid 0.275042 -0.275042)
							(end 0.2032 -0.3048)
						)
						(arc
							(start -0.2032 -0.3048)
							(mid -0.275042 -0.275042)
							(end -0.3048 -0.2032)
						)
						(arc
							(start -0.3048 0.2032)
							(mid -0.275042 0.275042)
							(end -0.2032 0.3048)
						)
						(arc
							(start 0.2032 0.3048)
							(mid 0.275042 0.275042)
							(end 0.3048 0.2032)
						)
					)
					(width 0)
					(fill yes)
				)
			)
		)
	)
	(footprint ""
		(layer "F.Cu")
		(at 227.83165 -39.299896 90)
		(property "Reference" "R9936"
			(at 0 0 90)
			(layer "F.SilkS")
			(hide yes)
			(effects
				(font
					(size 1.27 1.27)
				)
			)
		)
		(property "Value" "4K7R2J-2-GP"
			(at 0.064008 -3.993896 90)
			(unlocked yes)
			(layer "F.Fab")
			(hide yes)
			(effects
				(font
					(size 1.016 1.016)
					(thickness 0.1524)
				)
			)
		)
		(property "Device Type" "R402H16"
			(at 0.064008 -5.517896 90)
			(unlocked yes)
			(layer "F.Fab")
			(hide yes)
			(effects
				(font
					(size 1.016 1.016)
					(thickness 0.1524)
				)
			)
		)
		(duplicate_pad_numbers_are_jumpers no)
		(fp_line
			(start 0.508 -0.9398)
			(end -0.508 -0.9398)
			(stroke
				(width 0.1524)
				(type default)
			)
			(layer "F.SilkS")
		)
		(fp_line
			(start -0.508 -0.9398)
			(end -0.508 0.9398)
			(stroke
				(width 0.1524)
				(type default)
			)
			(layer "F.SilkS")
		)
		(fp_rect
			(start -0.508 0.9398)
			(end 0.508 -0.9398)
			(stroke
				(width 0)
				(type default)
			)
			(fill no)
			(layer "F.CrtYd")
		)
		(fp_rect
			(start -0.508 0.9398)
			(end 0.508 -0.9398)
			(stroke
				(width 0)
				(type default)
			)
			(fill no)
			(layer "F.Fab")
		)
		(pad "1" smd custom
			(at 0 -0.4445 90)
			(size 0.1397 0.1397)
			(layers "F.Cu" "F.Mask" "F.Paste")
			(net "P3V3")
			(options
				(clearance outline)
				(anchor circle)
			)
			(primitives
				(gr_poly
					(pts
						(arc
							(start -0.1778 -0.2794)
							(mid -0.249642 -0.249642)
							(end -0.2794 -0.1778)
						)
						(arc
							(start -0.2794 0.1778)
							(mid -0.249642 0.249642)
							(end -0.1778 0.2794)
						)
						(arc
							(start 0.1778 0.2794)
							(mid 0.249642 0.249642)
							(end 0.2794 0.1778)
						)
						(arc
							(start 0.2794 -0.1778)
							(mid 0.249642 -0.249642)
							(end 0.1778 -0.2794)
						)
					)
					(width 0)
					(fill yes)
				)
			)
		)
		(pad "2" smd custom
			(at 0 0.4445 90)
			(size 0.1397 0.1397)
			(layers "F.Cu" "F.Mask" "F.Paste")
			(net "SSD_ACT_DR4_MOS_N")
			(options
				(clearance outline)
				(anchor circle)
			)
			(primitives
				(gr_poly
					(pts
						(arc
							(start -0.1778 -0.2794)
							(mid -0.249642 -0.249642)
							(end -0.2794 -0.1778)
						)
						(arc
							(start -0.2794 0.1778)
							(mid -0.249642 0.249642)
							(end -0.1778 0.2794)
						)
						(arc
							(start 0.1778 0.2794)
							(mid 0.249642 0.249642)
							(end 0.2794 0.1778)
						)
						(arc
							(start 0.2794 -0.1778)
							(mid 0.249642 -0.249642)
							(end 0.1778 -0.2794)
						)
					)
					(width 0)
					(fill yes)
				)
			)
		)
	)
	(footprint ""
		(layer "F.Cu")
		(at 16.204438 -362.581952 180)
		(property "Reference" "R9949"
			(at 0 0 180)
			(layer "F.SilkS")
			(hide yes)
			(effects
				(font
					(size 1.27 1.27)
				)
			)
		)
		(property "Value" "4K7R2J-2-GP"
			(at 0.064008 -3.993896 180)
			(unlocked yes)
			(layer "F.Fab")
			(hide yes)
			(effects
				(font
					(size 1.016 1.016)
					(thickness 0.1524)
				)
			)
		)
		(property "Device Type" "R402H16"
			(at 0.064008 -5.517896 180)
			(unlocked yes)
			(layer "F.Fab")
			(hide yes)
			(effects
				(font
					(size 1.016 1.016)
					(thickness 0.1524)
				)
			)
		)
		(duplicate_pad_numbers_are_jumpers no)
		(fp_line
			(start 0.508 -0.9398)
			(end -0.508 -0.9398)
			(stroke
				(width 0.1524)
				(type default)
			)
			(layer "F.SilkS")
		)
		(fp_line
			(start -0.508 -0.9398)
			(end -0.508 0.9398)
			(stroke
				(width 0.1524)
				(type default)
			)
			(layer "F.SilkS")
		)
		(fp_rect
			(start -0.508 0.9398)
			(end 0.508 -0.9398)
			(stroke
				(width 0)
				(type default)
			)
			(fill no)
			(layer "F.CrtYd")
		)
		(fp_rect
			(start -0.508 0.9398)
			(end 0.508 -0.9398)
			(stroke
				(width 0)
				(type default)
			)
			(fill no)
			(layer "F.Fab")
		)
		(pad "1" smd custom
			(at 0 -0.4445 180)
			(size 0.1397 0.1397)
			(layers "F.Cu" "F.Mask" "F.Paste")
			(net "P3V3")
			(options
				(clearance outline)
				(anchor circle)
			)
			(primitives
				(gr_poly
					(pts
						(arc
							(start -0.1778 -0.2794)
							(mid -0.249642 -0.249642)
							(end -0.2794 -0.1778)
						)
						(arc
							(start -0.2794 0.1778)
							(mid -0.249642 0.249642)
							(end -0.1778 0.2794)
						)
						(arc
							(start 0.1778 0.2794)
							(mid 0.249642 0.249642)
							(end 0.2794 0.1778)
						)
						(arc
							(start 0.2794 -0.1778)
							(mid 0.249642 -0.249642)
							(end 0.1778 -0.2794)
						)
					)
					(width 0)
					(fill yes)
				)
			)
		)
		(pad "2" smd custom
			(at 0 0.4445 180)
			(size 0.1397 0.1397)
			(layers "F.Cu" "F.Mask" "F.Paste")
			(net "ATTN_LED_DR11_MOS_N")
			(options
				(clearance outline)
				(anchor circle)
			)
			(primitives
				(gr_poly
					(pts
						(arc
							(start -0.1778 -0.2794)
							(mid -0.249642 -0.249642)
							(end -0.2794 -0.1778)
						)
						(arc
							(start -0.2794 0.1778)
							(mid -0.249642 0.249642)
							(end -0.1778 0.2794)
						)
						(arc
							(start 0.1778 0.2794)
							(mid 0.249642 0.249642)
							(end 0.2794 0.1778)
						)
						(arc
							(start 0.2794 -0.1778)
							(mid 0.249642 -0.249642)
							(end 0.1778 -0.2794)
						)
					)
					(width 0)
					(fill yes)
				)
			)
		)
	)
	(footprint ""
		(layer "F.Cu")
		(at 41.654476 -38.871144 180)
		(property "Reference" "R9946"
			(at 0 0 180)
			(layer "F.SilkS")
			(hide yes)
			(effects
				(font
					(size 1.27 1.27)
				)
			)
		)
		(property "Value" "4K7R2J-2-GP"
			(at 0.064008 -3.993896 180)
			(unlocked yes)
			(layer "F.Fab")
			(hide yes)
			(effects
				(font
					(size 1.016 1.016)
					(thickness 0.1524)
				)
			)
		)
		(property "Device Type" "R402H16"
			(at 0.064008 -5.517896 180)
			(unlocked yes)
			(layer "F.Fab")
			(hide yes)
			(effects
				(font
					(size 1.016 1.016)
					(thickness 0.1524)
				)
			)
		)
		(duplicate_pad_numbers_are_jumpers no)
		(fp_line
			(start 0.508 -0.9398)
			(end -0.508 -0.9398)
			(stroke
				(width 0.1524)
				(type default)
			)
			(layer "F.SilkS")
		)
		(fp_line
			(start -0.508 -0.9398)
			(end -0.508 0.9398)
			(stroke
				(width 0.1524)
				(type default)
			)
			(layer "F.SilkS")
		)
		(fp_rect
			(start -0.508 0.9398)
			(end 0.508 -0.9398)
			(stroke
				(width 0)
				(type default)
			)
			(fill no)
			(layer "F.CrtYd")
		)
		(fp_rect
			(start -0.508 0.9398)
			(end 0.508 -0.9398)
			(stroke
				(width 0)
				(type default)
			)
			(fill no)
			(layer "F.Fab")
		)
		(pad "1" smd custom
			(at 0 -0.4445 180)
			(size 0.1397 0.1397)
			(layers "F.Cu" "F.Mask" "F.Paste")
			(net "P3V3")
			(options
				(clearance outline)
				(anchor circle)
			)
			(primitives
				(gr_poly
					(pts
						(arc
							(start -0.1778 -0.2794)
							(mid -0.249642 -0.249642)
							(end -0.2794 -0.1778)
						)
						(arc
							(start -0.2794 0.1778)
							(mid -0.249642 0.249642)
							(end -0.1778 0.2794)
						)
						(arc
							(start 0.1778 0.2794)
							(mid 0.249642 0.249642)
							(end 0.2794 0.1778)
						)
						(arc
							(start 0.2794 -0.1778)
							(mid 0.249642 -0.249642)
							(end 0.1778 -0.2794)
						)
					)
					(width 0)
					(fill yes)
				)
			)
		)
		(pad "2" smd custom
			(at 0 0.4445 180)
			(size 0.1397 0.1397)
			(layers "F.Cu" "F.Mask" "F.Paste")
			(net "SSD_ACT_DR9_MOS_N")
			(options
				(clearance outline)
				(anchor circle)
			)
			(primitives
				(gr_poly
					(pts
						(arc
							(start -0.1778 -0.2794)
							(mid -0.249642 -0.249642)
							(end -0.2794 -0.1778)
						)
						(arc
							(start -0.2794 0.1778)
							(mid -0.249642 0.249642)
							(end -0.1778 0.2794)
						)
						(arc
							(start 0.1778 0.2794)
							(mid 0.249642 0.249642)
							(end 0.2794 0.1778)
						)
						(arc
							(start 0.2794 -0.1778)
							(mid 0.249642 -0.249642)
							(end 0.1778 -0.2794)
						)
					)
					(width 0)
					(fill yes)
				)
			)
		)
	)
	(footprint ""
		(layer "F.Cu")
		(at 20.828 -165.354 180)
		(property "Reference" "C9531"
			(at 0 0 180)
			(layer "F.SilkS")
			(hide yes)
			(effects
				(font
					(size 1.27 1.27)
				)
			)
		)
		(property "Value" "SCD1U16V2KX-3GP"
			(at 1.1811 -2.7051 180)
			(unlocked yes)
			(layer "F.Fab")
			(hide yes)
			(effects
				(font
					(size 1.016 1.016)
					(thickness 0.1524)
				)
			)
		)
		(property "Device Type" "C402H22"
			(at 1.1811 -4.2291 180)
			(unlocked yes)
			(layer "F.Fab")
			(hide yes)
			(effects
				(font
					(size 1.016 1.016)
					(thickness 0.1524)
				)
			)
		)
		(duplicate_pad_numbers_are_jumpers no)
		(fp_rect
			(start -0.4318 0.9525)
			(end 0.4318 -0.9525)
			(stroke
				(width 0)
				(type default)
			)
			(fill no)
			(layer "F.CrtYd")
		)
		(fp_rect
			(start -0.4318 0.9525)
			(end 0.4318 -0.9525)
			(stroke
				(width 0)
				(type default)
			)
			(fill no)
			(layer "F.Fab")
		)
		(pad "1" smd custom
			(at 0 -0.4445 180)
			(size 0.1524 0.1524)
			(layers "F.Cu" "F.Mask" "F.Paste")
			(net "P3V3")
			(options
				(clearance outline)
				(anchor circle)
			)
			(primitives
				(gr_poly
					(pts
						(arc
							(start 0.3048 -0.2032)
							(mid 0.275042 -0.275042)
							(end 0.2032 -0.3048)
						)
						(arc
							(start -0.2032 -0.3048)
							(mid -0.275042 -0.275042)
							(end -0.3048 -0.2032)
						)
						(arc
							(start -0.3048 0.2032)
							(mid -0.275042 0.275042)
							(end -0.2032 0.3048)
						)
						(arc
							(start 0.2032 0.3048)
							(mid 0.275042 0.275042)
							(end 0.3048 0.2032)
						)
					)
					(width 0)
					(fill yes)
				)
			)
		)
		(pad "2" smd custom
			(at 0 0.4445 180)
			(size 0.1524 0.1524)
			(layers "F.Cu" "F.Mask" "F.Paste")
			(net "GND")
			(options
				(clearance outline)
				(anchor circle)
			)
			(primitives
				(gr_poly
					(pts
						(arc
							(start 0.3048 -0.2032)
							(mid 0.275042 -0.275042)
							(end 0.2032 -0.3048)
						)
						(arc
							(start -0.2032 -0.3048)
							(mid -0.275042 -0.275042)
							(end -0.3048 -0.2032)
						)
						(arc
							(start -0.3048 0.2032)
							(mid -0.275042 0.275042)
							(end -0.2032 0.3048)
						)
						(arc
							(start 0.2032 0.3048)
							(mid 0.275042 0.275042)
							(end 0.3048 0.2032)
						)
					)
					(width 0)
					(fill yes)
				)
			)
		)
	)
	(footprint ""
		(layer "F.Cu")
		(at 32.6136 -417.0934 90)
		(property "Reference" "U19"
			(at 0 0 90)
			(layer "F.SilkS")
			(hide yes)
			(effects
				(font
					(size 1.27 1.27)
				)
			)
		)
		(property "Value" "P2003EVG-GP"
			(at 0 -11.1252 90)
			(unlocked yes)
			(layer "F.Fab")
			(hide yes)
			(effects
				(font
					(size 1.016 1.016)
					(thickness 0.1524)
				)
			)
		)
		(property "Device Type" "SOIC8H79"
			(at 0 -12.6492 90)
			(unlocked yes)
			(layer "F.Fab")
			(hide yes)
			(effects
				(font
					(size 1.016 1.016)
					(thickness 0.1524)
				)
			)
		)
		(duplicate_pad_numbers_are_jumpers no)
		(fp_line
			(start 2.1336 -1.4224)
			(end -2.7432 -1.4224)
			(stroke
				(width 0.1524)
				(type default)
			)
			(layer "F.SilkS")
		)
		(fp_line
			(start -2.7432 -1.4224)
			(end -2.7432 1.4224)
			(stroke
				(width 0.1524)
				(type default)
			)
			(layer "F.SilkS")
		)
		(fp_line
			(start -2.7432 -0.508)
			(end -2.2352 0)
			(stroke
				(width 0.1524)
				(type default)
			)
			(layer "F.SilkS")
		)
		(fp_line
			(start -2.2352 0)
			(end -2.7432 0.508)
			(stroke
				(width 0.1524)
				(type default)
			)
			(layer "F.SilkS")
		)
		(fp_line
			(start 2.1336 1.4224)
			(end 2.1336 -1.4224)
			(stroke
				(width 0.1524)
				(type default)
			)
			(layer "F.SilkS")
		)
		(fp_line
			(start -2.7432 1.4224)
			(end 2.1336 1.4224)
			(stroke
				(width 0.1524)
				(type default)
			)
			(layer "F.SilkS")
		)
		(fp_line
			(start -2.6162 3.429)
			(end -2.6162 1.4732)
			(stroke
				(width 0.4064)
				(type default)
			)
			(layer "F.SilkS")
		)
		(fp_poly
			(pts
				(xy 2.2098 -1.4224) (xy 2.2098 1.4224) (xy -2.2225 1.4224) (xy -2.2225 -1.4224)
			)
			(stroke
				(width 0)
				(type default)
			)
			(fill yes)
			(layer "F.SilkS")
		)
		(fp_rect
			(start -2.4511 2.9972)
			(end 2.4511 -2.9972)
			(stroke
				(width 0)
				(type default)
			)
			(fill no)
			(layer "F.CrtYd")
		)
		(fp_poly
			(pts
				(xy -2.8194 3.6322) (xy -2.8194 -3.6322) (xy 2.8194 -3.6322) (xy 2.8194 -2.2987) (xy 2.4511 -2.2987)
				(xy 2.4511 -2.9972) (xy -2.4511 -2.9972) (xy -2.4511 2.9972) (xy 2.4511 2.9972) (xy 2.4511 -2.286)
				(xy 2.8194 -2.286) (xy 2.8194 3.6322)
			)
			(stroke
				(width 0)
				(type default)
			)
			(fill no)
			(layer "F.CrtYd")
		)
		(fp_rect
			(start -2.8194 3.6322)
			(end 2.8194 -3.6322)
			(stroke
				(width 0)
				(type default)
			)
			(fill no)
			(layer "F.Fab")
		)
		(pad "1" smd rect
			(at -1.905 2.54 90)
			(size 0.635 1.651)
			(layers "F.Cu" "F.Mask" "F.Paste")
			(net "P12V")
		)
		(pad "2" smd rect
			(at -0.635 2.54 90)
			(size 0.635 1.651)
			(layers "F.Cu" "F.Mask" "F.Paste")
			(net "P12V")
		)
		(pad "3" smd rect
			(at 0.635 2.54 90)
			(size 0.635 1.651)
			(layers "F.Cu" "F.Mask" "F.Paste")
			(net "P12V")
		)
		(pad "4" smd rect
			(at 1.905 2.54 90)
			(size 0.635 1.651)
			(layers "F.Cu" "F.Mask" "F.Paste")
			(net "SW_SSD10_N")
		)
		(pad "5" smd rect
			(at 1.905 -2.54 90)
			(size 0.635 1.651)
			(layers "F.Cu" "F.Mask" "F.Paste")
			(net "P12V_SSD10")
		)
		(pad "6" smd rect
			(at 0.635 -2.54 90)
			(size 0.635 1.651)
			(layers "F.Cu" "F.Mask" "F.Paste")
			(net "P12V_SSD10")
		)
		(pad "7" smd rect
			(at -0.635 -2.54 90)
			(size 0.635 1.651)
			(layers "F.Cu" "F.Mask" "F.Paste")
			(net "P12V_SSD10")
		)
		(pad "8" smd rect
			(at -1.905 -2.54 90)
			(size 0.635 1.651)
			(layers "F.Cu" "F.Mask" "F.Paste")
			(net "P12V_SSD10")
		)
	)
	(footprint ""
		(layer "F.Cu")
		(at 221.0054 -404.9776 -90)
		(property "Reference" "R9784"
			(at 0 0 270)
			(layer "F.SilkS")
			(hide yes)
			(effects
				(font
					(size 1.27 1.27)
				)
			)
		)
		(property "Value" "2K2R5F-GP"
			(at 0 -8.9535 270)
			(unlocked yes)
			(layer "F.Fab")
			(hide yes)
			(effects
				(font
					(size 1.27 1.016)
					(thickness 0.1524)
				)
			)
		)
		(property "Device Type" "R805H24"
			(at 0 -10.6299 270)
			(unlocked yes)
			(layer "F.Fab")
			(hide yes)
			(effects
				(font
					(size 1.27 1.016)
					(thickness 0.1524)
				)
			)
		)
		(duplicate_pad_numbers_are_jumpers no)
		(fp_line
			(start -0.889 1.7018)
			(end 0.889 1.7018)
			(stroke
				(width 0.1524)
				(type default)
			)
			(layer "F.SilkS")
		)
		(fp_line
			(start 0.889 1.7018)
			(end 0.889 -0.508)
			(stroke
				(width 0.1524)
				(type default)
			)
			(layer "F.SilkS")
		)
		(fp_line
			(start -0.889 0.0762)
			(end -0.889 1.7018)
			(stroke
				(width 0.1524)
				(type default)
			)
			(layer "F.SilkS")
		)
		(fp_line
			(start -0.889 -1.7018)
			(end -0.889 0.2794)
			(stroke
				(width 0.1524)
				(type default)
			)
			(layer "F.SilkS")
		)
		(fp_line
			(start 0.889 -1.7018)
			(end 0.889 -0.381)
			(stroke
				(width 0.1524)
				(type default)
			)
			(layer "F.SilkS")
		)
		(fp_line
			(start 0.889 -1.7018)
			(end -0.889 -1.7018)
			(stroke
				(width 0.1524)
				(type default)
			)
			(layer "F.SilkS")
		)
		(fp_poly
			(pts
				(xy 0.9652 -1.778) (xy 0.9652 1.778) (xy -0.9652 1.778) (xy -0.9652 -1.778)
			)
			(stroke
				(width 0)
				(type default)
			)
			(fill no)
			(layer "F.CrtYd")
		)
		(fp_rect
			(start -0.9652 1.778)
			(end 0.9652 -1.778)
			(stroke
				(width 0)
				(type default)
			)
			(fill no)
			(layer "F.Fab")
		)
		(pad "1" smd rect
			(at 0 -0.9652 270)
			(size 1.397 1.143)
			(layers "F.Cu" "F.Mask" "F.Paste")
			(net "P12V_SSD1")
		)
		(pad "2" smd rect
			(at 0 0.9652 270)
			(size 1.397 1.143)
			(layers "F.Cu" "F.Mask" "F.Paste")
			(net "P12V_MOST1_GATE_D")
		)
	)
	(footprint ""
		(layer "F.Cu")
		(at 102.616 -433.324 90)
		(property "Reference" "R9057"
			(at 0 0 90)
			(layer "F.SilkS")
			(hide yes)
			(effects
				(font
					(size 1.27 1.27)
				)
			)
		)
		(property "Value" "27R2F-GP"
			(at 0.064008 -3.993896 90)
			(unlocked yes)
			(layer "F.Fab")
			(hide yes)
			(effects
				(font
					(size 1.016 1.016)
					(thickness 0.1524)
				)
			)
		)
		(property "Device Type" "R402H16"
			(at 0.064008 -5.517896 90)
			(unlocked yes)
			(layer "F.Fab")
			(hide yes)
			(effects
				(font
					(size 1.016 1.016)
					(thickness 0.1524)
				)
			)
		)
		(duplicate_pad_numbers_are_jumpers no)
		(fp_line
			(start 0.508 -0.9398)
			(end -0.508 -0.9398)
			(stroke
				(width 0.1524)
				(type default)
			)
			(layer "F.SilkS")
		)
		(fp_line
			(start -0.508 -0.9398)
			(end -0.508 0.9398)
			(stroke
				(width 0.1524)
				(type default)
			)
			(layer "F.SilkS")
		)
		(fp_rect
			(start -0.508 0.9398)
			(end 0.508 -0.9398)
			(stroke
				(width 0)
				(type default)
			)
			(fill no)
			(layer "F.CrtYd")
		)
		(fp_rect
			(start -0.508 0.9398)
			(end 0.508 -0.9398)
			(stroke
				(width 0)
				(type default)
			)
			(fill no)
			(layer "F.Fab")
		)
		(pad "1" smd custom
			(at 0 -0.4445 90)
			(size 0.1397 0.1397)
			(layers "F.Cu" "F.Mask" "F.Paste")
			(net "PE_CLK_100M_DR0_2_R_P")
			(options
				(clearance outline)
				(anchor circle)
			)
			(primitives
				(gr_poly
					(pts
						(arc
							(start -0.1778 -0.2794)
							(mid -0.249642 -0.249642)
							(end -0.2794 -0.1778)
						)
						(arc
							(start -0.2794 0.1778)
							(mid -0.249642 0.249642)
							(end -0.1778 0.2794)
						)
						(arc
							(start 0.1778 0.2794)
							(mid 0.249642 0.249642)
							(end 0.2794 0.1778)
						)
						(arc
							(start 0.2794 -0.1778)
							(mid 0.249642 -0.249642)
							(end 0.1778 -0.2794)
						)
					)
					(width 0)
					(fill yes)
				)
			)
		)
		(pad "2" smd custom
			(at 0 0.4445 90)
			(size 0.1397 0.1397)
			(layers "F.Cu" "F.Mask" "F.Paste")
			(net "PE_CLK100M_DR0_2_P")
			(options
				(clearance outline)
				(anchor circle)
			)
			(primitives
				(gr_poly
					(pts
						(arc
							(start -0.1778 -0.2794)
							(mid -0.249642 -0.249642)
							(end -0.2794 -0.1778)
						)
						(arc
							(start -0.2794 0.1778)
							(mid -0.249642 0.249642)
							(end -0.1778 0.2794)
						)
						(arc
							(start 0.1778 0.2794)
							(mid 0.249642 0.249642)
							(end 0.2794 0.1778)
						)
						(arc
							(start 0.2794 -0.1778)
							(mid 0.249642 -0.249642)
							(end 0.1778 -0.2794)
						)
					)
					(width 0)
					(fill yes)
				)
			)
		)
	)
	(footprint ""
		(layer "F.Cu")
		(at 49.429924 -449.88226 180)
		(property "Reference" "C9523"
			(at 0 0 180)
			(layer "F.SilkS")
			(hide yes)
			(effects
				(font
					(size 1.27 1.27)
				)
			)
		)
		(property "Value" "SCD1U16V2KX-3GP"
			(at 1.1811 -2.7051 180)
			(unlocked yes)
			(layer "F.Fab")
			(hide yes)
			(effects
				(font
					(size 1.016 1.016)
					(thickness 0.1524)
				)
			)
		)
		(property "Device Type" "C402H22"
			(at 1.1811 -4.2291 180)
			(unlocked yes)
			(layer "F.Fab")
			(hide yes)
			(effects
				(font
					(size 1.016 1.016)
					(thickness 0.1524)
				)
			)
		)
		(duplicate_pad_numbers_are_jumpers no)
		(fp_rect
			(start -0.4318 0.9525)
			(end 0.4318 -0.9525)
			(stroke
				(width 0)
				(type default)
			)
			(fill no)
			(layer "F.CrtYd")
		)
		(fp_rect
			(start -0.4318 0.9525)
			(end 0.4318 -0.9525)
			(stroke
				(width 0)
				(type default)
			)
			(fill no)
			(layer "F.Fab")
		)
		(pad "1" smd custom
			(at 0 -0.4445 180)
			(size 0.1524 0.1524)
			(layers "F.Cu" "F.Mask" "F.Paste")
			(net "P3V3")
			(options
				(clearance outline)
				(anchor circle)
			)
			(primitives
				(gr_poly
					(pts
						(arc
							(start 0.3048 -0.2032)
							(mid 0.275042 -0.275042)
							(end 0.2032 -0.3048)
						)
						(arc
							(start -0.2032 -0.3048)
							(mid -0.275042 -0.275042)
							(end -0.3048 -0.2032)
						)
						(arc
							(start -0.3048 0.2032)
							(mid -0.275042 0.275042)
							(end -0.2032 0.3048)
						)
						(arc
							(start 0.2032 0.3048)
							(mid 0.275042 0.275042)
							(end 0.3048 0.2032)
						)
					)
					(width 0)
					(fill yes)
				)
			)
		)
		(pad "2" smd custom
			(at 0 0.4445 180)
			(size 0.1524 0.1524)
			(layers "F.Cu" "F.Mask" "F.Paste")
			(net "GND")
			(options
				(clearance outline)
				(anchor circle)
			)
			(primitives
				(gr_poly
					(pts
						(arc
							(start 0.3048 -0.2032)
							(mid 0.275042 -0.275042)
							(end 0.2032 -0.3048)
						)
						(arc
							(start -0.2032 -0.3048)
							(mid -0.275042 -0.275042)
							(end -0.3048 -0.2032)
						)
						(arc
							(start -0.3048 0.2032)
							(mid -0.275042 0.275042)
							(end -0.2032 0.3048)
						)
						(arc
							(start 0.2032 0.3048)
							(mid 0.275042 0.275042)
							(end 0.3048 0.2032)
						)
					)
					(width 0)
					(fill yes)
				)
			)
		)
	)
	(footprint ""
		(layer "F.Cu")
		(at 33.999932 -4.500118)
		(property "Reference" "H13"
			(at 0 0 0)
			(layer "F.SilkS")
			(hide yes)
			(effects
				(font
					(size 1.27 1.27)
				)
			)
		)
		(property "Value" "GEN276X162R197X296-6-F-A-GP"
			(at -6.7183 4.1402 0)
			(unlocked yes)
			(layer "F.Fab")
			(hide yes)
			(effects
				(font
					(size 1.016 1.016)
					(thickness 0.1524)
				)
			)
		)
		(property "Device Type" "GEN276X162R197X296-6-F-A"
			(at -6.7183 2.6162 0)
			(unlocked yes)
			(layer "F.Fab")
			(hide yes)
			(effects
				(font
					(size 1.016 1.016)
					(thickness 0.1524)
				)
			)
		)
		(duplicate_pad_numbers_are_jumpers no)
		(fp_poly
			(pts
				(arc
					(start 2.723642 4.777232)
					(mid -0.000169 6.508462)
					(end -2.723896 4.776978)
				)
				(arc
					(start -2.723896 4.776978)
					(mid 0.000173 -5.499012)
					(end 2.723642 4.777232)
				)
			)
			(stroke
				(width 0)
				(type default)
			)
			(fill no)
			(layer "B.CrtYd")
		)
		(fp_poly
			(pts
				(arc
					(start 2.723642 4.777232)
					(mid -0.000169 6.508462)
					(end -2.723896 4.776978)
				)
				(arc
					(start -2.723896 4.776978)
					(mid 0.000173 -5.499012)
					(end 2.723642 4.777232)
				)
			)
			(stroke
				(width 0)
				(type default)
			)
			(fill no)
			(layer "F.CrtYd")
		)
		(fp_poly
			(pts
				(arc
					(start 2.723642 4.777232)
					(mid -0.000169 6.508462)
					(end -2.723896 4.776978)
				)
				(arc
					(start -2.723896 4.776978)
					(mid 0.000173 -5.499012)
					(end 2.723642 4.777232)
				)
			)
			(stroke
				(width 0)
				(type default)
			)
			(fill no)
			(layer "B.Fab")
		)
		(fp_poly
			(pts
				(arc
					(start 2.723642 4.777232)
					(mid -0.000169 6.508462)
					(end -2.723896 4.776978)
				)
				(arc
					(start -2.723896 4.776978)
					(mid 0.000173 -5.499012)
					(end 2.723642 4.777232)
				)
			)
			(stroke
				(width 0)
				(type default)
			)
			(fill no)
			(layer "F.Fab")
		)
		(pad "" np_thru_hole circle
			(at 0 0)
			(size 0.254 0.254)
			(drill 0.0254)
			(layers "*.Cu" "*.Mask")
			(clearance 3.135376)
			(thermal_gap 3.135376)
		)
		(pad "1" thru_hole circle
			(at 2.549906 0)
			(size 0.8636 0.8636)
			(drill 0.508)
			(layers "*.Cu" "*.Mask")
			(remove_unused_layers no)
			(net "GND")
			(clearance 0.8255)
			(thermal_gap 0.8255)
		)
		(pad "2" thru_hole circle
			(at 2.210054 -1.27)
			(size 0.8636 0.8636)
			(drill 0.508)
			(layers "*.Cu" "*.Mask")
			(remove_unused_layers no)
			(net "GND")
			(clearance 0.8255)
			(thermal_gap 0.8255)
		)
		(pad "3" thru_hole circle
			(at 1.27 -2.210054)
			(size 0.8636 0.8636)
			(drill 0.508)
			(layers "*.Cu" "*.Mask")
			(remove_unused_layers no)
			(net "GND")
			(clearance 0.8255)
			(thermal_gap 0.8255)
		)
		(pad "4" thru_hole circle
			(at -1.279906 -2.210054)
			(size 0.8636 0.8636)
			(drill 0.508)
			(layers "*.Cu" "*.Mask")
			(remove_unused_layers no)
			(net "GND")
			(clearance 0.8255)
			(thermal_gap 0.8255)
		)
		(pad "5" thru_hole circle
			(at -2.210054 -1.27)
			(size 0.8636 0.8636)
			(drill 0.508)
			(layers "*.Cu" "*.Mask")
			(remove_unused_layers no)
			(net "GND")
			(clearance 0.8255)
			(thermal_gap 0.8255)
		)
		(pad "6" thru_hole circle
			(at -2.549906 0)
			(size 0.8636 0.8636)
			(drill 0.508)
			(layers "*.Cu" "*.Mask")
			(remove_unused_layers no)
			(net "GND")
			(clearance 0.8255)
			(thermal_gap 0.8255)
		)
		(zone
			(layers "F.Cu" "B.Cu" "In1.Cu" "In2.Cu" "In3.Cu" "In4.Cu" "In5.Cu" "In6.Cu")
			(hatch none 0.5)
			(connect_pads
				(clearance 0)
			)
			(min_thickness 0.25)
			(keepout
				(tracks allowed)
				(vias not_allowed)
				(pads allowed)
				(copperpour not_allowed)
				(footprints allowed)
			)
			(placement
				(enabled no)
				(sheetname "")
			)
			(fill
				(thermal_gap 0.5)
				(thermal_bridge_width 0.5)
				(island_removal_mode 0)
			)
			(polygon
				(pts
					(arc
						(start 38.317932 -4.503166)
						(mid 29.681932 -4.503166)
						(end 38.317932 -4.503166)
					)
				)
			)
		)
		(zone
			(layers "F.Cu" "B.Cu" "In1.Cu" "In2.Cu" "In3.Cu" "In4.Cu" "In5.Cu" "In6.Cu")
			(hatch none 0.5)
			(connect_pads
				(clearance 0)
			)
			(min_thickness 0.25)
			(keepout
				(tracks not_allowed)
				(vias allowed)
				(pads allowed)
				(copperpour not_allowed)
				(footprints allowed)
			)
			(placement
				(enabled no)
				(sheetname "")
			)
			(fill
				(thermal_gap 0.5)
				(thermal_bridge_width 0.5)
				(island_removal_mode 0)
			)
			(polygon
				(pts
					(arc
						(start 36.339272 -2.890774)
						(mid 34.000012 2.008329)
						(end 31.660338 -2.890774)
					)
					(arc
						(start 31.660338 -2.890774)
						(mid 31.906305 -3.33114)
						(end 31.991554 -3.828288)
					)
					(arc
						(start 31.991554 -4.500118)
						(mid 33.999932 -6.508496)
						(end 36.008056 -4.500118)
					)
					(arc
						(start 36.008056 -3.828288)
						(mid 36.093291 -3.331134)
						(end 36.339272 -2.890774)
					)
				)
			)
		)
	)
	(footprint ""
		(layer "F.Cu")
		(at 37.211 -194.3354 180)
		(property "Reference" "PC1217"
			(at 0 0 180)
			(layer "F.SilkS")
			(hide yes)
			(effects
				(font
					(size 1.27 1.27)
				)
			)
		)
		(property "Value" "SCD1U50V3KX-GP"
			(at 0 -2.8194 180)
			(unlocked yes)
			(layer "F.Fab")
			(hide yes)
			(effects
				(font
					(size 1.016 1.016)
					(thickness 0.1524)
				)
			)
		)
		(property "Device Type" "C603H36"
			(at 0 -4.3434 180)
			(unlocked yes)
			(layer "F.Fab")
			(hide yes)
			(effects
				(font
					(size 1.016 1.016)
					(thickness 0.1524)
				)
			)
		)
		(duplicate_pad_numbers_are_jumpers no)
		(fp_line
			(start 0.508 0)
			(end -0.508 0)
			(stroke
				(width 0.2032)
				(type default)
			)
			(layer "F.SilkS")
		)
		(fp_rect
			(start -0.5842 1.3335)
			(end 0.5842 -1.3335)
			(stroke
				(width 0)
				(type default)
			)
			(fill no)
			(layer "F.CrtYd")
		)
		(fp_rect
			(start -0.5842 1.3335)
			(end 0.5842 -1.3335)
			(stroke
				(width 0)
				(type default)
			)
			(fill no)
			(layer "F.Fab")
		)
		(pad "1" smd custom
			(at 0 -0.762 180)
			(size 0.2159 0.2159)
			(layers "F.Cu" "F.Mask" "F.Paste")
			(net "P12V_SSD8")
			(options
				(clearance outline)
				(anchor circle)
			)
			(primitives
				(gr_poly
					(pts
						(arc
							(start -0.3302 -0.4318)
							(mid -0.402042 -0.402042)
							(end -0.4318 -0.3302)
						)
						(arc
							(start -0.4318 0.3302)
							(mid -0.402042 0.402042)
							(end -0.3302 0.4318)
						)
						(arc
							(start 0.3302 0.4318)
							(mid 0.402042 0.402042)
							(end 0.4318 0.3302)
						)
						(arc
							(start 0.4318 -0.3302)
							(mid 0.402042 -0.402042)
							(end 0.3302 -0.4318)
						)
					)
					(width 0)
					(fill yes)
				)
			)
		)
		(pad "2" smd custom
			(at 0 0.762 180)
			(size 0.2159 0.2159)
			(layers "F.Cu" "F.Mask" "F.Paste")
			(net "GND")
			(options
				(clearance outline)
				(anchor circle)
			)
			(primitives
				(gr_poly
					(pts
						(arc
							(start -0.3302 -0.4318)
							(mid -0.402042 -0.402042)
							(end -0.4318 -0.3302)
						)
						(arc
							(start -0.4318 0.3302)
							(mid -0.402042 0.402042)
							(end -0.3302 0.4318)
						)
						(arc
							(start 0.3302 0.4318)
							(mid 0.402042 0.402042)
							(end 0.4318 0.3302)
						)
						(arc
							(start 0.4318 -0.3302)
							(mid 0.402042 -0.402042)
							(end 0.3302 -0.4318)
						)
					)
					(width 0)
					(fill yes)
				)
			)
		)
	)
	(footprint ""
		(layer "F.Cu")
		(at 100.33 -296.545)
		(property "Reference" "R9077"
			(at 0 0 0)
			(layer "F.SilkS")
			(hide yes)
			(effects
				(font
					(size 1.27 1.27)
				)
			)
		)
		(property "Value" "27R2F-GP"
			(at 0.064008 -3.993896 0)
			(unlocked yes)
			(layer "F.Fab")
			(hide yes)
			(effects
				(font
					(size 1.016 1.016)
					(thickness 0.1524)
				)
			)
		)
		(property "Device Type" "R402H16"
			(at 0.064008 -5.517896 0)
			(unlocked yes)
			(layer "F.Fab")
			(hide yes)
			(effects
				(font
					(size 1.016 1.016)
					(thickness 0.1524)
				)
			)
		)
		(duplicate_pad_numbers_are_jumpers no)
		(fp_line
			(start -0.508 -0.9398)
			(end -0.508 0.9398)
			(stroke
				(width 0.1524)
				(type default)
			)
			(layer "F.SilkS")
		)
		(fp_line
			(start 0.508 -0.9398)
			(end -0.508 -0.9398)
			(stroke
				(width 0.1524)
				(type default)
			)
			(layer "F.SilkS")
		)
		(fp_rect
			(start -0.508 0.9398)
			(end 0.508 -0.9398)
			(stroke
				(width 0)
				(type default)
			)
			(fill no)
			(layer "F.CrtYd")
		)
		(fp_rect
			(start -0.508 0.9398)
			(end 0.508 -0.9398)
			(stroke
				(width 0)
				(type default)
			)
			(fill no)
			(layer "F.Fab")
		)
		(pad "1" smd custom
			(at 0 -0.4445)
			(size 0.1397 0.1397)
			(layers "F.Cu" "F.Mask" "F.Paste")
			(net "PE_CLK_100M_DR2_1_R_N")
			(options
				(clearance outline)
				(anchor circle)
			)
			(primitives
				(gr_poly
					(pts
						(arc
							(start -0.1778 -0.2794)
							(mid -0.249642 -0.249642)
							(end -0.2794 -0.1778)
						)
						(arc
							(start -0.2794 0.1778)
							(mid -0.249642 0.249642)
							(end -0.1778 0.2794)
						)
						(arc
							(start 0.1778 0.2794)
							(mid 0.249642 0.249642)
							(end 0.2794 0.1778)
						)
						(arc
							(start 0.2794 -0.1778)
							(mid 0.249642 -0.249642)
							(end 0.1778 -0.2794)
						)
					)
					(width 0)
					(fill yes)
				)
			)
		)
		(pad "2" smd custom
			(at 0 0.4445)
			(size 0.1397 0.1397)
			(layers "F.Cu" "F.Mask" "F.Paste")
			(net "PE_CLK100M_DR2_1_N")
			(options
				(clearance outline)
				(anchor circle)
			)
			(primitives
				(gr_poly
					(pts
						(arc
							(start -0.1778 -0.2794)
							(mid -0.249642 -0.249642)
							(end -0.2794 -0.1778)
						)
						(arc
							(start -0.2794 0.1778)
							(mid -0.249642 0.249642)
							(end -0.1778 0.2794)
						)
						(arc
							(start 0.1778 0.2794)
							(mid 0.249642 0.249642)
							(end 0.2794 0.1778)
						)
						(arc
							(start 0.2794 -0.1778)
							(mid 0.249642 -0.249642)
							(end 0.1778 -0.2794)
						)
					)
					(width 0)
					(fill yes)
				)
			)
		)
	)
	(footprint ""
		(layer "F.Cu")
		(at 49.4665 -445.7065)
		(property "Reference" "R9817"
			(at 0 0 0)
			(layer "F.SilkS")
			(hide yes)
			(effects
				(font
					(size 1.27 1.27)
				)
			)
		)
		(property "Value" "0R2J-2-GP"
			(at 0.064008 -3.993896 0)
			(unlocked yes)
			(layer "F.Fab")
			(hide yes)
			(effects
				(font
					(size 1.016 1.016)
					(thickness 0.1524)
				)
			)
		)
		(property "Device Type" "R402H16"
			(at 0.064008 -5.517896 0)
			(unlocked yes)
			(layer "F.Fab")
			(hide yes)
			(effects
				(font
					(size 1.016 1.016)
					(thickness 0.1524)
				)
			)
		)
		(duplicate_pad_numbers_are_jumpers no)
		(fp_line
			(start -0.508 -0.9398)
			(end -0.508 0.9398)
			(stroke
				(width 0.1524)
				(type default)
			)
			(layer "F.SilkS")
		)
		(fp_line
			(start 0.508 -0.9398)
			(end -0.508 -0.9398)
			(stroke
				(width 0.1524)
				(type default)
			)
			(layer "F.SilkS")
		)
		(fp_rect
			(start -0.508 0.9398)
			(end 0.508 -0.9398)
			(stroke
				(width 0)
				(type default)
			)
			(fill no)
			(layer "F.CrtYd")
		)
		(fp_rect
			(start -0.508 0.9398)
			(end 0.508 -0.9398)
			(stroke
				(width 0)
				(type default)
			)
			(fill no)
			(layer "F.Fab")
		)
		(pad "1" smd custom
			(at 0 -0.4445)
			(size 0.1397 0.1397)
			(layers "F.Cu" "F.Mask" "F.Paste")
			(net "SSD_ACT_DR5_R")
			(options
				(clearance outline)
				(anchor circle)
			)
			(primitives
				(gr_poly
					(pts
						(arc
							(start -0.1778 -0.2794)
							(mid -0.249642 -0.249642)
							(end -0.2794 -0.1778)
						)
						(arc
							(start -0.2794 0.1778)
							(mid -0.249642 0.249642)
							(end -0.1778 0.2794)
						)
						(arc
							(start 0.1778 0.2794)
							(mid 0.249642 0.249642)
							(end 0.2794 0.1778)
						)
						(arc
							(start 0.2794 -0.1778)
							(mid 0.249642 -0.249642)
							(end 0.1778 -0.2794)
						)
					)
					(width 0)
					(fill yes)
				)
			)
		)
		(pad "2" smd custom
			(at 0 0.4445)
			(size 0.1397 0.1397)
			(layers "F.Cu" "F.Mask" "F.Paste")
			(net "SSD_ACT_DR5")
			(options
				(clearance outline)
				(anchor circle)
			)
			(primitives
				(gr_poly
					(pts
						(arc
							(start -0.1778 -0.2794)
							(mid -0.249642 -0.249642)
							(end -0.2794 -0.1778)
						)
						(arc
							(start -0.2794 0.1778)
							(mid -0.249642 0.249642)
							(end -0.1778 0.2794)
						)
						(arc
							(start 0.1778 0.2794)
							(mid 0.249642 0.249642)
							(end 0.2794 0.1778)
						)
						(arc
							(start 0.2794 -0.1778)
							(mid 0.249642 -0.249642)
							(end 0.1778 -0.2794)
						)
					)
					(width 0)
					(fill yes)
				)
			)
		)
	)
	(footprint ""
		(layer "F.Cu")
		(at 84.455 -424.942 -90)
		(property "Reference" "R9033"
			(at 0 0 270)
			(layer "F.SilkS")
			(hide yes)
			(effects
				(font
					(size 1.27 1.27)
				)
			)
		)
		(property "Value" "4K7R2F-GP"
			(at 0.064008 -3.993896 270)
			(unlocked yes)
			(layer "F.Fab")
			(hide yes)
			(effects
				(font
					(size 1.016 1.016)
					(thickness 0.1524)
				)
			)
		)
		(property "Device Type" "R402H16"
			(at 0.064008 -5.517896 270)
			(unlocked yes)
			(layer "F.Fab")
			(hide yes)
			(effects
				(font
					(size 1.016 1.016)
					(thickness 0.1524)
				)
			)
		)
		(duplicate_pad_numbers_are_jumpers no)
		(fp_line
			(start -0.508 -0.9398)
			(end -0.508 0.9398)
			(stroke
				(width 0.1524)
				(type default)
			)
			(layer "F.SilkS")
		)
		(fp_line
			(start 0.508 -0.9398)
			(end -0.508 -0.9398)
			(stroke
				(width 0.1524)
				(type default)
			)
			(layer "F.SilkS")
		)
		(fp_rect
			(start -0.508 0.9398)
			(end 0.508 -0.9398)
			(stroke
				(width 0)
				(type default)
			)
			(fill no)
			(layer "F.CrtYd")
		)
		(fp_rect
			(start -0.508 0.9398)
			(end 0.508 -0.9398)
			(stroke
				(width 0)
				(type default)
			)
			(fill no)
			(layer "F.Fab")
		)
		(pad "1" smd custom
			(at 0 -0.4445 270)
			(size 0.1397 0.1397)
			(layers "F.Cu" "F.Mask" "F.Paste")
			(net "CLK_BUF_EU1_SMB_A1_TRI")
			(options
				(clearance outline)
				(anchor circle)
			)
			(primitives
				(gr_poly
					(pts
						(arc
							(start -0.1778 -0.2794)
							(mid -0.249642 -0.249642)
							(end -0.2794 -0.1778)
						)
						(arc
							(start -0.2794 0.1778)
							(mid -0.249642 0.249642)
							(end -0.1778 0.2794)
						)
						(arc
							(start 0.1778 0.2794)
							(mid 0.249642 0.249642)
							(end 0.2794 0.1778)
						)
						(arc
							(start 0.2794 -0.1778)
							(mid 0.249642 -0.249642)
							(end 0.1778 -0.2794)
						)
					)
					(width 0)
					(fill yes)
				)
			)
		)
		(pad "2" smd custom
			(at 0 0.4445 270)
			(size 0.1397 0.1397)
			(layers "F.Cu" "F.Mask" "F.Paste")
			(net "GND")
			(options
				(clearance outline)
				(anchor circle)
			)
			(primitives
				(gr_poly
					(pts
						(arc
							(start -0.1778 -0.2794)
							(mid -0.249642 -0.249642)
							(end -0.2794 -0.1778)
						)
						(arc
							(start -0.2794 0.1778)
							(mid -0.249642 0.249642)
							(end -0.1778 0.2794)
						)
						(arc
							(start 0.1778 0.2794)
							(mid 0.249642 0.249642)
							(end 0.2794 0.1778)
						)
						(arc
							(start 0.2794 -0.1778)
							(mid 0.249642 -0.249642)
							(end 0.1778 -0.2794)
						)
					)
					(width 0)
					(fill yes)
				)
			)
		)
	)
	(footprint ""
		(layer "F.Cu")
		(at 73.152 -444.246)
		(property "Reference" "C346"
			(at 0 0 0)
			(layer "F.SilkS")
			(hide yes)
			(effects
				(font
					(size 1.27 1.27)
				)
			)
		)
		(property "Value" "SC1U16V3KX-5GP"
			(at 0 -2.8194 0)
			(unlocked yes)
			(layer "F.Fab")
			(hide yes)
			(effects
				(font
					(size 1.016 1.016)
					(thickness 0.1524)
				)
			)
		)
		(property "Device Type" "C603H36"
			(at 0 -4.3434 0)
			(unlocked yes)
			(layer "F.Fab")
			(hide yes)
			(effects
				(font
					(size 1.016 1.016)
					(thickness 0.1524)
				)
			)
		)
		(duplicate_pad_numbers_are_jumpers no)
		(fp_line
			(start 0.508 0)
			(end -0.508 0)
			(stroke
				(width 0.2032)
				(type default)
			)
			(layer "F.SilkS")
		)
		(fp_rect
			(start -0.5842 1.3335)
			(end 0.5842 -1.3335)
			(stroke
				(width 0)
				(type default)
			)
			(fill no)
			(layer "F.CrtYd")
		)
		(fp_rect
			(start -0.5842 1.3335)
			(end 0.5842 -1.3335)
			(stroke
				(width 0)
				(type default)
			)
			(fill no)
			(layer "F.Fab")
		)
		(pad "1" smd custom
			(at 0 -0.762)
			(size 0.2159 0.2159)
			(layers "F.Cu" "F.Mask" "F.Paste")
			(net "P3V3")
			(options
				(clearance outline)
				(anchor circle)
			)
			(primitives
				(gr_poly
					(pts
						(arc
							(start -0.3302 -0.4318)
							(mid -0.402042 -0.402042)
							(end -0.4318 -0.3302)
						)
						(arc
							(start -0.4318 0.3302)
							(mid -0.402042 0.402042)
							(end -0.3302 0.4318)
						)
						(arc
							(start 0.3302 0.4318)
							(mid 0.402042 0.402042)
							(end 0.4318 0.3302)
						)
						(arc
							(start 0.4318 -0.3302)
							(mid 0.402042 -0.402042)
							(end 0.3302 -0.4318)
						)
					)
					(width 0)
					(fill yes)
				)
			)
		)
		(pad "2" smd custom
			(at 0 0.762)
			(size 0.2159 0.2159)
			(layers "F.Cu" "F.Mask" "F.Paste")
			(net "GND")
			(options
				(clearance outline)
				(anchor circle)
			)
			(primitives
				(gr_poly
					(pts
						(arc
							(start -0.3302 -0.4318)
							(mid -0.402042 -0.402042)
							(end -0.4318 -0.3302)
						)
						(arc
							(start -0.4318 0.3302)
							(mid -0.402042 0.402042)
							(end -0.3302 0.4318)
						)
						(arc
							(start 0.3302 0.4318)
							(mid 0.402042 0.402042)
							(end 0.4318 0.3302)
						)
						(arc
							(start 0.4318 -0.3302)
							(mid 0.402042 -0.402042)
							(end 0.3302 -0.4318)
						)
					)
					(width 0)
					(fill yes)
				)
			)
		)
	)
	(footprint ""
		(layer "F.Cu")
		(at 15.494 -491.363)
		(property "Reference" "R556"
			(at 0 0 0)
			(layer "F.SilkS")
			(hide yes)
			(effects
				(font
					(size 1.27 1.27)
				)
			)
		)
		(property "Value" "200KR2F-L-GP"
			(at 0.064008 -3.993896 0)
			(unlocked yes)
			(layer "F.Fab")
			(hide yes)
			(effects
				(font
					(size 1.016 1.016)
					(thickness 0.1524)
				)
			)
		)
		(property "Device Type" "R402H16"
			(at 0.064008 -5.517896 0)
			(unlocked yes)
			(layer "F.Fab")
			(hide yes)
			(effects
				(font
					(size 1.016 1.016)
					(thickness 0.1524)
				)
			)
		)
		(duplicate_pad_numbers_are_jumpers no)
		(fp_line
			(start -0.508 -0.9398)
			(end -0.508 0.9398)
			(stroke
				(width 0.1524)
				(type default)
			)
			(layer "F.SilkS")
		)
		(fp_line
			(start 0.508 -0.9398)
			(end -0.508 -0.9398)
			(stroke
				(width 0.1524)
				(type default)
			)
			(layer "F.SilkS")
		)
		(fp_rect
			(start -0.508 0.9398)
			(end 0.508 -0.9398)
			(stroke
				(width 0)
				(type default)
			)
			(fill no)
			(layer "F.CrtYd")
		)
		(fp_rect
			(start -0.508 0.9398)
			(end 0.508 -0.9398)
			(stroke
				(width 0)
				(type default)
			)
			(fill no)
			(layer "F.Fab")
		)
		(pad "1" smd custom
			(at 0 -0.4445)
			(size 0.1397 0.1397)
			(layers "F.Cu" "F.Mask" "F.Paste")
			(net "SW_SSD5_R")
			(options
				(clearance outline)
				(anchor circle)
			)
			(primitives
				(gr_poly
					(pts
						(arc
							(start -0.1778 -0.2794)
							(mid -0.249642 -0.249642)
							(end -0.2794 -0.1778)
						)
						(arc
							(start -0.2794 0.1778)
							(mid -0.249642 0.249642)
							(end -0.1778 0.2794)
						)
						(arc
							(start 0.1778 0.2794)
							(mid 0.249642 0.249642)
							(end 0.2794 0.1778)
						)
						(arc
							(start 0.2794 -0.1778)
							(mid 0.249642 -0.249642)
							(end 0.1778 -0.2794)
						)
					)
					(width 0)
					(fill yes)
				)
			)
		)
		(pad "2" smd custom
			(at 0 0.4445)
			(size 0.1397 0.1397)
			(layers "F.Cu" "F.Mask" "F.Paste")
			(net "SW_SSD5_N")
			(options
				(clearance outline)
				(anchor circle)
			)
			(primitives
				(gr_poly
					(pts
						(arc
							(start -0.1778 -0.2794)
							(mid -0.249642 -0.249642)
							(end -0.2794 -0.1778)
						)
						(arc
							(start -0.2794 0.1778)
							(mid -0.249642 0.249642)
							(end -0.1778 0.2794)
						)
						(arc
							(start 0.1778 0.2794)
							(mid 0.249642 0.249642)
							(end 0.2794 0.1778)
						)
						(arc
							(start 0.2794 -0.1778)
							(mid 0.249642 -0.249642)
							(end 0.1778 -0.2794)
						)
					)
					(width 0)
					(fill yes)
				)
			)
		)
	)
	(footprint ""
		(layer "F.Cu")
		(at 82.931 -104.902 -90)
		(property "Reference" "PR9064"
			(at 0 0 270)
			(layer "F.SilkS")
			(hide yes)
			(effects
				(font
					(size 1.27 1.27)
				)
			)
		)
		(property "Value" "1K4R2F-1-GP"
			(at 0.064008 -3.993896 270)
			(unlocked yes)
			(layer "F.Fab")
			(hide yes)
			(effects
				(font
					(size 1.016 1.016)
					(thickness 0.1524)
				)
			)
		)
		(property "Device Type" "R402H16"
			(at 0.064008 -5.517896 270)
			(unlocked yes)
			(layer "F.Fab")
			(hide yes)
			(effects
				(font
					(size 1.016 1.016)
					(thickness 0.1524)
				)
			)
		)
		(duplicate_pad_numbers_are_jumpers no)
		(fp_line
			(start -0.508 -0.9398)
			(end -0.508 0.9398)
			(stroke
				(width 0.1524)
				(type default)
			)
			(layer "F.SilkS")
		)
		(fp_line
			(start 0.508 -0.9398)
			(end -0.508 -0.9398)
			(stroke
				(width 0.1524)
				(type default)
			)
			(layer "F.SilkS")
		)
		(fp_rect
			(start -0.508 0.9398)
			(end 0.508 -0.9398)
			(stroke
				(width 0)
				(type default)
			)
			(fill no)
			(layer "F.CrtYd")
		)
		(fp_rect
			(start -0.508 0.9398)
			(end 0.508 -0.9398)
			(stroke
				(width 0)
				(type default)
			)
			(fill no)
			(layer "F.Fab")
		)
		(pad "1" smd custom
			(at 0 -0.4445 270)
			(size 0.1397 0.1397)
			(layers "F.Cu" "F.Mask" "F.Paste")
			(net "CLK_BUF_EU4_HIBW_BYPM_LOBW#")
			(options
				(clearance outline)
				(anchor circle)
			)
			(primitives
				(gr_poly
					(pts
						(arc
							(start -0.1778 -0.2794)
							(mid -0.249642 -0.249642)
							(end -0.2794 -0.1778)
						)
						(arc
							(start -0.2794 0.1778)
							(mid -0.249642 0.249642)
							(end -0.1778 0.2794)
						)
						(arc
							(start 0.1778 0.2794)
							(mid 0.249642 0.249642)
							(end 0.2794 0.1778)
						)
						(arc
							(start 0.2794 -0.1778)
							(mid 0.249642 -0.249642)
							(end 0.1778 -0.2794)
						)
					)
					(width 0)
					(fill yes)
				)
			)
		)
		(pad "2" smd custom
			(at 0 0.4445 270)
			(size 0.1397 0.1397)
			(layers "F.Cu" "F.Mask" "F.Paste")
			(net "GND")
			(options
				(clearance outline)
				(anchor circle)
			)
			(primitives
				(gr_poly
					(pts
						(arc
							(start -0.1778 -0.2794)
							(mid -0.249642 -0.249642)
							(end -0.2794 -0.1778)
						)
						(arc
							(start -0.2794 0.1778)
							(mid -0.249642 0.249642)
							(end -0.1778 0.2794)
						)
						(arc
							(start 0.1778 0.2794)
							(mid 0.249642 0.249642)
							(end 0.2794 0.1778)
						)
						(arc
							(start 0.2794 -0.1778)
							(mid 0.249642 -0.249642)
							(end 0.1778 -0.2794)
						)
					)
					(width 0)
					(fill yes)
				)
			)
		)
	)
	(footprint ""
		(layer "F.Cu")
		(at 233.807 -344.801952 180)
		(property "Reference" "Q33"
			(at 0 0 180)
			(layer "F.SilkS")
			(hide yes)
			(effects
				(font
					(size 1.27 1.27)
				)
			)
		)
		(property "Value" "2N7002A-7-GP"
			(at 0.127 -8.9662 180)
			(unlocked yes)
			(layer "F.Fab")
			(hide yes)
			(effects
				(font
					(size 1.016 1.016)
					(thickness 0.1524)
				)
			)
		)
		(property "Device Type" "SOT23DGS2D4H48"
			(at 0.127 -10.4902 180)
			(unlocked yes)
			(layer "F.Fab")
			(hide yes)
			(effects
				(font
					(size 1.016 1.016)
					(thickness 0.1524)
				)
			)
		)
		(duplicate_pad_numbers_are_jumpers no)
		(fp_line
			(start 1.651 1.778)
			(end 1.651 -1.778)
			(stroke
				(width 0.1524)
				(type default)
			)
			(layer "F.SilkS")
		)
		(fp_line
			(start 1.651 -1.778)
			(end -1.651 -1.778)
			(stroke
				(width 0.1524)
				(type default)
			)
			(layer "F.SilkS")
		)
		(fp_line
			(start -1.651 1.778)
			(end 1.651 1.778)
			(stroke
				(width 0.1524)
				(type default)
			)
			(layer "F.SilkS")
		)
		(fp_line
			(start -1.651 -1.778)
			(end -1.651 1.778)
			(stroke
				(width 0.1524)
				(type default)
			)
			(layer "F.SilkS")
		)
		(fp_poly
			(pts
				(xy -1.778 1.8796) (xy -1.778 -1.8796) (xy 1.778 -1.8796) (xy 1.778 1.8796)
			)
			(stroke
				(width 0)
				(type default)
			)
			(fill no)
			(layer "F.CrtYd")
		)
		(fp_poly
			(pts
				(xy -1.778 1.8796) (xy -1.778 -1.8796) (xy 1.778 -1.8796) (xy 1.778 1.8796)
			)
			(stroke
				(width 0)
				(type default)
			)
			(fill no)
			(layer "F.Fab")
		)
		(pad "D" smd custom
			(at 0 -0.9525 180)
			(size 0.1905 0.1905)
			(layers "F.Cu" "F.Mask" "F.Paste")
			(net "SSD_ACT_DR1_MOS_N")
			(options
				(clearance outline)
				(anchor circle)
			)
			(primitives
				(gr_poly
					(pts
						(arc
							(start -0.1778 0.5715)
							(mid -0.321484 0.511984)
							(end -0.381 0.3683)
						)
						(arc
							(start -0.381 -0.3683)
							(mid -0.321484 -0.511984)
							(end -0.1778 -0.5715)
						)
						(arc
							(start 0.1778 -0.5715)
							(mid 0.321484 -0.511984)
							(end 0.381 -0.3683)
						)
						(arc
							(start 0.381 0.3683)
							(mid 0.321484 0.511984)
							(end 0.1778 0.5715)
						)
					)
					(width 0)
					(fill yes)
				)
			)
		)
		(pad "G" smd custom
			(at -0.98425 0.9525 180)
			(size 0.1905 0.1905)
			(layers "F.Cu" "F.Mask" "F.Paste")
			(net "ATTN_LED_DR1_AND_R")
			(options
				(clearance outline)
				(anchor circle)
			)
			(primitives
				(gr_poly
					(pts
						(arc
							(start -0.1778 0.5715)
							(mid -0.321484 0.511984)
							(end -0.381 0.3683)
						)
						(arc
							(start -0.381 -0.3683)
							(mid -0.321484 -0.511984)
							(end -0.1778 -0.5715)
						)
						(arc
							(start 0.1778 -0.5715)
							(mid 0.321484 -0.511984)
							(end 0.381 -0.3683)
						)
						(arc
							(start 0.381 0.3683)
							(mid 0.321484 0.511984)
							(end 0.1778 0.5715)
						)
					)
					(width 0)
					(fill yes)
				)
			)
		)
		(pad "S" smd custom
			(at 0.98425 0.9525 180)
			(size 0.1905 0.1905)
			(layers "F.Cu" "F.Mask" "F.Paste")
			(net "SSD_ACT_DR1_R")
			(options
				(clearance outline)
				(anchor circle)
			)
			(primitives
				(gr_poly
					(pts
						(arc
							(start -0.1778 0.5715)
							(mid -0.321484 0.511984)
							(end -0.381 0.3683)
						)
						(arc
							(start -0.381 -0.3683)
							(mid -0.321484 -0.511984)
							(end -0.1778 -0.5715)
						)
						(arc
							(start 0.1778 -0.5715)
							(mid 0.321484 -0.511984)
							(end 0.381 -0.3683)
						)
						(arc
							(start 0.381 0.3683)
							(mid 0.321484 0.511984)
							(end 0.1778 0.5715)
						)
					)
					(width 0)
					(fill yes)
				)
			)
		)
	)
	(footprint ""
		(layer "F.Cu")
		(at 96.0374 -21.9456)
		(property "Reference" "R390"
			(at 0 0 0)
			(layer "F.SilkS")
			(hide yes)
			(effects
				(font
					(size 1.27 1.27)
				)
			)
		)
		(property "Value" "2KR2F-3-GP"
			(at 0.064008 -3.993896 0)
			(unlocked yes)
			(layer "F.Fab")
			(hide yes)
			(effects
				(font
					(size 1.016 1.016)
					(thickness 0.1524)
				)
			)
		)
		(property "Device Type" "R402H16"
			(at 0.064008 -5.517896 0)
			(unlocked yes)
			(layer "F.Fab")
			(hide yes)
			(effects
				(font
					(size 1.016 1.016)
					(thickness 0.1524)
				)
			)
		)
		(duplicate_pad_numbers_are_jumpers no)
		(fp_line
			(start -0.508 -0.9398)
			(end -0.508 0.9398)
			(stroke
				(width 0.1524)
				(type default)
			)
			(layer "F.SilkS")
		)
		(fp_line
			(start 0.508 -0.9398)
			(end -0.508 -0.9398)
			(stroke
				(width 0.1524)
				(type default)
			)
			(layer "F.SilkS")
		)
		(fp_rect
			(start -0.508 0.9398)
			(end 0.508 -0.9398)
			(stroke
				(width 0)
				(type default)
			)
			(fill no)
			(layer "F.CrtYd")
		)
		(fp_rect
			(start -0.508 0.9398)
			(end 0.508 -0.9398)
			(stroke
				(width 0)
				(type default)
			)
			(fill no)
			(layer "F.Fab")
		)
		(pad "1" smd custom
			(at 0 -0.4445)
			(size 0.1397 0.1397)
			(layers "F.Cu" "F.Mask" "F.Paste")
			(net "P12V_SSD14_SENSE")
			(options
				(clearance outline)
				(anchor circle)
			)
			(primitives
				(gr_poly
					(pts
						(arc
							(start -0.1778 -0.2794)
							(mid -0.249642 -0.249642)
							(end -0.2794 -0.1778)
						)
						(arc
							(start -0.2794 0.1778)
							(mid -0.249642 0.249642)
							(end -0.1778 0.2794)
						)
						(arc
							(start 0.1778 0.2794)
							(mid 0.249642 0.249642)
							(end 0.2794 0.1778)
						)
						(arc
							(start 0.2794 -0.1778)
							(mid 0.249642 -0.249642)
							(end 0.1778 -0.2794)
						)
					)
					(width 0)
					(fill yes)
				)
			)
		)
		(pad "2" smd custom
			(at 0 0.4445)
			(size 0.1397 0.1397)
			(layers "F.Cu" "F.Mask" "F.Paste")
			(net "GND")
			(options
				(clearance outline)
				(anchor circle)
			)
			(primitives
				(gr_poly
					(pts
						(arc
							(start -0.1778 -0.2794)
							(mid -0.249642 -0.249642)
							(end -0.2794 -0.1778)
						)
						(arc
							(start -0.2794 0.1778)
							(mid -0.249642 0.249642)
							(end -0.1778 0.2794)
						)
						(arc
							(start 0.1778 0.2794)
							(mid 0.249642 0.249642)
							(end 0.2794 0.1778)
						)
						(arc
							(start 0.2794 -0.1778)
							(mid 0.249642 -0.249642)
							(end 0.1778 -0.2794)
						)
					)
					(width 0)
					(fill yes)
				)
			)
		)
	)
	(footprint ""
		(layer "F.Cu")
		(at 97.409 -195.834 -90)
		(property "Reference" "R9496"
			(at 0 0 270)
			(layer "F.SilkS")
			(hide yes)
			(effects
				(font
					(size 1.27 1.27)
				)
			)
		)
		(property "Value" "4K7R2J-2-GP"
			(at 0.064008 -3.993896 270)
			(unlocked yes)
			(layer "F.Fab")
			(hide yes)
			(effects
				(font
					(size 1.016 1.016)
					(thickness 0.1524)
				)
			)
		)
		(property "Device Type" "R402H16"
			(at 0.064008 -5.517896 270)
			(unlocked yes)
			(layer "F.Fab")
			(hide yes)
			(effects
				(font
					(size 1.016 1.016)
					(thickness 0.1524)
				)
			)
		)
		(duplicate_pad_numbers_are_jumpers no)
		(fp_line
			(start -0.508 -0.9398)
			(end -0.508 0.9398)
			(stroke
				(width 0.1524)
				(type default)
			)
			(layer "F.SilkS")
		)
		(fp_line
			(start 0.508 -0.9398)
			(end -0.508 -0.9398)
			(stroke
				(width 0.1524)
				(type default)
			)
			(layer "F.SilkS")
		)
		(fp_rect
			(start -0.508 0.9398)
			(end 0.508 -0.9398)
			(stroke
				(width 0)
				(type default)
			)
			(fill no)
			(layer "F.CrtYd")
		)
		(fp_rect
			(start -0.508 0.9398)
			(end 0.508 -0.9398)
			(stroke
				(width 0)
				(type default)
			)
			(fill no)
			(layer "F.Fab")
		)
		(pad "1" smd custom
			(at 0 -0.4445 270)
			(size 0.1397 0.1397)
			(layers "F.Cu" "F.Mask" "F.Paste")
			(net "P3V3")
			(options
				(clearance outline)
				(anchor circle)
			)
			(primitives
				(gr_poly
					(pts
						(arc
							(start -0.1778 -0.2794)
							(mid -0.249642 -0.249642)
							(end -0.2794 -0.1778)
						)
						(arc
							(start -0.2794 0.1778)
							(mid -0.249642 0.249642)
							(end -0.1778 0.2794)
						)
						(arc
							(start 0.1778 0.2794)
							(mid 0.249642 0.249642)
							(end 0.2794 0.1778)
						)
						(arc
							(start 0.2794 -0.1778)
							(mid 0.249642 -0.249642)
							(end 0.1778 -0.2794)
						)
					)
					(width 0)
					(fill yes)
				)
			)
		)
		(pad "2" smd custom
			(at 0 0.4445 270)
			(size 0.1397 0.1397)
			(layers "F.Cu" "F.Mask" "F.Paste")
			(net "SSD4_CLK0_OE_N")
			(options
				(clearance outline)
				(anchor circle)
			)
			(primitives
				(gr_poly
					(pts
						(arc
							(start -0.1778 -0.2794)
							(mid -0.249642 -0.249642)
							(end -0.2794 -0.1778)
						)
						(arc
							(start -0.2794 0.1778)
							(mid -0.249642 0.249642)
							(end -0.1778 0.2794)
						)
						(arc
							(start 0.1778 0.2794)
							(mid 0.249642 0.249642)
							(end 0.2794 0.1778)
						)
						(arc
							(start 0.2794 -0.1778)
							(mid 0.249642 -0.249642)
							(end 0.1778 -0.2794)
						)
					)
					(width 0)
					(fill yes)
				)
			)
		)
	)
	(footprint ""
		(layer "F.Cu")
		(at 73.0504 -366.522)
		(property "Reference" "SR982"
			(at 0 0 0)
			(layer "F.SilkS")
			(hide yes)
			(effects
				(font
					(size 1.27 1.27)
				)
			)
		)
		(property "Value" "2KR2F-3-GP"
			(at 0.064008 -3.993896 0)
			(unlocked yes)
			(layer "F.Fab")
			(hide yes)
			(effects
				(font
					(size 1.016 1.016)
					(thickness 0.1524)
				)
			)
		)
		(property "Device Type" "R402H16"
			(at 0.064008 -5.517896 0)
			(unlocked yes)
			(layer "F.Fab")
			(hide yes)
			(effects
				(font
					(size 1.016 1.016)
					(thickness 0.1524)
				)
			)
		)
		(duplicate_pad_numbers_are_jumpers no)
		(fp_line
			(start -0.508 -0.9398)
			(end -0.508 0.9398)
			(stroke
				(width 0.1524)
				(type default)
			)
			(layer "F.SilkS")
		)
		(fp_line
			(start 0.508 -0.9398)
			(end -0.508 -0.9398)
			(stroke
				(width 0.1524)
				(type default)
			)
			(layer "F.SilkS")
		)
		(fp_rect
			(start -0.508 0.9398)
			(end 0.508 -0.9398)
			(stroke
				(width 0)
				(type default)
			)
			(fill no)
			(layer "F.CrtYd")
		)
		(fp_rect
			(start -0.508 0.9398)
			(end 0.508 -0.9398)
			(stroke
				(width 0)
				(type default)
			)
			(fill no)
			(layer "F.Fab")
		)
		(pad "1" smd custom
			(at 0 -0.4445)
			(size 0.1397 0.1397)
			(layers "F.Cu" "F.Mask" "F.Paste")
			(net "P3V3")
			(options
				(clearance outline)
				(anchor circle)
			)
			(primitives
				(gr_poly
					(pts
						(arc
							(start -0.1778 -0.2794)
							(mid -0.249642 -0.249642)
							(end -0.2794 -0.1778)
						)
						(arc
							(start -0.2794 0.1778)
							(mid -0.249642 0.249642)
							(end -0.1778 0.2794)
						)
						(arc
							(start 0.1778 0.2794)
							(mid 0.249642 0.249642)
							(end 0.2794 0.1778)
						)
						(arc
							(start 0.2794 -0.1778)
							(mid 0.249642 -0.249642)
							(end 0.1778 -0.2794)
						)
					)
					(width 0)
					(fill yes)
				)
			)
		)
		(pad "2" smd custom
			(at 0 0.4445)
			(size 0.1397 0.1397)
			(layers "F.Cu" "F.Mask" "F.Paste")
			(net "SDA_DR6")
			(options
				(clearance outline)
				(anchor circle)
			)
			(primitives
				(gr_poly
					(pts
						(arc
							(start -0.1778 -0.2794)
							(mid -0.249642 -0.249642)
							(end -0.2794 -0.1778)
						)
						(arc
							(start -0.2794 0.1778)
							(mid -0.249642 0.249642)
							(end -0.1778 0.2794)
						)
						(arc
							(start 0.1778 0.2794)
							(mid 0.249642 0.249642)
							(end 0.2794 0.1778)
						)
						(arc
							(start 0.2794 -0.1778)
							(mid 0.249642 -0.249642)
							(end 0.1778 -0.2794)
						)
					)
					(width 0)
					(fill yes)
				)
			)
		)
	)
	(footprint ""
		(layer "F.Cu")
		(at 20.3835 -60.88761 -90)
		(property "Reference" "SR1150"
			(at 0 0 270)
			(layer "F.SilkS")
			(hide yes)
			(effects
				(font
					(size 1.27 1.27)
				)
			)
		)
		(property "Value" "4K7R2J-2-GP"
			(at 0.064008 -3.993896 270)
			(unlocked yes)
			(layer "F.Fab")
			(hide yes)
			(effects
				(font
					(size 1.016 1.016)
					(thickness 0.1524)
				)
			)
		)
		(property "Device Type" "R402H16"
			(at 0.064008 -5.517896 270)
			(unlocked yes)
			(layer "F.Fab")
			(hide yes)
			(effects
				(font
					(size 1.016 1.016)
					(thickness 0.1524)
				)
			)
		)
		(duplicate_pad_numbers_are_jumpers no)
		(fp_line
			(start -0.508 -0.9398)
			(end -0.508 0.9398)
			(stroke
				(width 0.1524)
				(type default)
			)
			(layer "F.SilkS")
		)
		(fp_line
			(start 0.508 -0.9398)
			(end -0.508 -0.9398)
			(stroke
				(width 0.1524)
				(type default)
			)
			(layer "F.SilkS")
		)
		(fp_rect
			(start -0.508 0.9398)
			(end 0.508 -0.9398)
			(stroke
				(width 0)
				(type default)
			)
			(fill no)
			(layer "F.CrtYd")
		)
		(fp_rect
			(start -0.508 0.9398)
			(end 0.508 -0.9398)
			(stroke
				(width 0)
				(type default)
			)
			(fill no)
			(layer "F.Fab")
		)
		(pad "1" smd custom
			(at 0 -0.4445 270)
			(size 0.1397 0.1397)
			(layers "F.Cu" "F.Mask" "F.Paste")
			(net "P3V3")
			(options
				(clearance outline)
				(anchor circle)
			)
			(primitives
				(gr_poly
					(pts
						(arc
							(start -0.1778 -0.2794)
							(mid -0.249642 -0.249642)
							(end -0.2794 -0.1778)
						)
						(arc
							(start -0.2794 0.1778)
							(mid -0.249642 0.249642)
							(end -0.1778 0.2794)
						)
						(arc
							(start 0.1778 0.2794)
							(mid 0.249642 0.249642)
							(end 0.2794 0.1778)
						)
						(arc
							(start 0.2794 -0.1778)
							(mid 0.249642 -0.249642)
							(end 0.1778 -0.2794)
						)
					)
					(width 0)
					(fill yes)
				)
			)
		)
		(pad "2" smd custom
			(at 0 0.4445 270)
			(size 0.1397 0.1397)
			(layers "F.Cu" "F.Mask" "F.Paste")
			(net "SSD_ACT_DR14")
			(options
				(clearance outline)
				(anchor circle)
			)
			(primitives
				(gr_poly
					(pts
						(arc
							(start -0.1778 -0.2794)
							(mid -0.249642 -0.249642)
							(end -0.2794 -0.1778)
						)
						(arc
							(start -0.2794 0.1778)
							(mid -0.249642 0.249642)
							(end -0.1778 0.2794)
						)
						(arc
							(start 0.1778 0.2794)
							(mid 0.249642 0.249642)
							(end 0.2794 0.1778)
						)
						(arc
							(start 0.2794 -0.1778)
							(mid 0.249642 -0.249642)
							(end 0.1778 -0.2794)
						)
					)
					(width 0)
					(fill yes)
				)
			)
		)
	)
	(footprint ""
		(layer "F.Cu")
		(at 82.931 -311.531 90)
		(property "Reference" "R9352"
			(at 0 0 90)
			(layer "F.SilkS")
			(hide yes)
			(effects
				(font
					(size 1.27 1.27)
				)
			)
		)
		(property "Value" "2D2R2F-GP"
			(at 0.064008 -3.993896 90)
			(unlocked yes)
			(layer "F.Fab")
			(hide yes)
			(effects
				(font
					(size 1.016 1.016)
					(thickness 0.1524)
				)
			)
		)
		(property "Device Type" "R402H16"
			(at 0.064008 -5.517896 90)
			(unlocked yes)
			(layer "F.Fab")
			(hide yes)
			(effects
				(font
					(size 1.016 1.016)
					(thickness 0.1524)
				)
			)
		)
		(duplicate_pad_numbers_are_jumpers no)
		(fp_line
			(start 0.508 -0.9398)
			(end -0.508 -0.9398)
			(stroke
				(width 0.1524)
				(type default)
			)
			(layer "F.SilkS")
		)
		(fp_line
			(start -0.508 -0.9398)
			(end -0.508 0.9398)
			(stroke
				(width 0.1524)
				(type default)
			)
			(layer "F.SilkS")
		)
		(fp_rect
			(start -0.508 0.9398)
			(end 0.508 -0.9398)
			(stroke
				(width 0)
				(type default)
			)
			(fill no)
			(layer "F.CrtYd")
		)
		(fp_rect
			(start -0.508 0.9398)
			(end 0.508 -0.9398)
			(stroke
				(width 0)
				(type default)
			)
			(fill no)
			(layer "F.Fab")
		)
		(pad "1" smd custom
			(at 0 -0.4445 90)
			(size 0.1397 0.1397)
			(layers "F.Cu" "F.Mask" "F.Paste")
			(net "VDD_DIFF_2")
			(options
				(clearance outline)
				(anchor circle)
			)
			(primitives
				(gr_poly
					(pts
						(arc
							(start -0.1778 -0.2794)
							(mid -0.249642 -0.249642)
							(end -0.2794 -0.1778)
						)
						(arc
							(start -0.2794 0.1778)
							(mid -0.249642 0.249642)
							(end -0.1778 0.2794)
						)
						(arc
							(start 0.1778 0.2794)
							(mid 0.249642 0.249642)
							(end 0.2794 0.1778)
						)
						(arc
							(start 0.2794 -0.1778)
							(mid 0.249642 -0.249642)
							(end 0.1778 -0.2794)
						)
					)
					(width 0)
					(fill yes)
				)
			)
		)
		(pad "2" smd custom
			(at 0 0.4445 90)
			(size 0.1397 0.1397)
			(layers "F.Cu" "F.Mask" "F.Paste")
			(net "VDDA_2")
			(options
				(clearance outline)
				(anchor circle)
			)
			(primitives
				(gr_poly
					(pts
						(arc
							(start -0.1778 -0.2794)
							(mid -0.249642 -0.249642)
							(end -0.2794 -0.1778)
						)
						(arc
							(start -0.2794 0.1778)
							(mid -0.249642 0.249642)
							(end -0.1778 0.2794)
						)
						(arc
							(start 0.1778 0.2794)
							(mid 0.249642 0.249642)
							(end 0.2794 0.1778)
						)
						(arc
							(start 0.2794 -0.1778)
							(mid 0.249642 -0.249642)
							(end 0.1778 -0.2794)
						)
					)
					(width 0)
					(fill yes)
				)
			)
		)
	)
	(footprint ""
		(layer "F.Cu")
		(at 5.500116 -488.40009)
		(property "Reference" "H1"
			(at 0 0 0)
			(layer "F.SilkS")
			(hide yes)
			(effects
				(font
					(size 1.27 1.27)
				)
			)
		)
		(property "Value" "GEN276X162R197X296-6-F-A-GP"
			(at -6.7183 4.1402 0)
			(unlocked yes)
			(layer "F.Fab")
			(hide yes)
			(effects
				(font
					(size 1.016 1.016)
					(thickness 0.1524)
				)
			)
		)
		(property "Device Type" "GEN276X162R197X296-6-F-A"
			(at -6.7183 2.6162 0)
			(unlocked yes)
			(layer "F.Fab")
			(hide yes)
			(effects
				(font
					(size 1.016 1.016)
					(thickness 0.1524)
				)
			)
		)
		(duplicate_pad_numbers_are_jumpers no)
		(fp_poly
			(pts
				(arc
					(start 2.723642 4.777232)
					(mid -0.000169 6.508462)
					(end -2.723896 4.776978)
				)
				(arc
					(start -2.723896 4.776978)
					(mid 0.000173 -5.499012)
					(end 2.723642 4.777232)
				)
			)
			(stroke
				(width 0)
				(type default)
			)
			(fill no)
			(layer "B.CrtYd")
		)
		(fp_poly
			(pts
				(arc
					(start 2.723642 4.777232)
					(mid -0.000169 6.508462)
					(end -2.723896 4.776978)
				)
				(arc
					(start -2.723896 4.776978)
					(mid 0.000173 -5.499012)
					(end 2.723642 4.777232)
				)
			)
			(stroke
				(width 0)
				(type default)
			)
			(fill no)
			(layer "F.CrtYd")
		)
		(fp_poly
			(pts
				(arc
					(start 2.723642 4.777232)
					(mid -0.000169 6.508462)
					(end -2.723896 4.776978)
				)
				(arc
					(start -2.723896 4.776978)
					(mid 0.000173 -5.499012)
					(end 2.723642 4.777232)
				)
			)
			(stroke
				(width 0)
				(type default)
			)
			(fill no)
			(layer "B.Fab")
		)
		(fp_poly
			(pts
				(arc
					(start 2.723642 4.777232)
					(mid -0.000169 6.508462)
					(end -2.723896 4.776978)
				)
				(arc
					(start -2.723896 4.776978)
					(mid 0.000173 -5.499012)
					(end 2.723642 4.777232)
				)
			)
			(stroke
				(width 0)
				(type default)
			)
			(fill no)
			(layer "F.Fab")
		)
		(pad "" np_thru_hole circle
			(at 0 0)
			(size 0.254 0.254)
			(drill 0.0254)
			(layers "*.Cu" "*.Mask")
			(clearance 3.135376)
			(thermal_gap 3.135376)
		)
		(pad "1" thru_hole circle
			(at 2.549906 0)
			(size 0.8636 0.8636)
			(drill 0.508)
			(layers "*.Cu" "*.Mask")
			(remove_unused_layers no)
			(net "GND")
			(clearance 0.8255)
			(thermal_gap 0.8255)
		)
		(pad "2" thru_hole circle
			(at 2.210054 -1.27)
			(size 0.8636 0.8636)
			(drill 0.508)
			(layers "*.Cu" "*.Mask")
			(remove_unused_layers no)
			(net "GND")
			(clearance 0.8255)
			(thermal_gap 0.8255)
		)
		(pad "3" thru_hole circle
			(at 1.27 -2.210054)
			(size 0.8636 0.8636)
			(drill 0.508)
			(layers "*.Cu" "*.Mask")
			(remove_unused_layers no)
			(net "GND")
			(clearance 0.8255)
			(thermal_gap 0.8255)
		)
		(pad "4" thru_hole circle
			(at -1.279906 -2.210054)
			(size 0.8636 0.8636)
			(drill 0.508)
			(layers "*.Cu" "*.Mask")
			(remove_unused_layers no)
			(net "GND")
			(clearance 0.8255)
			(thermal_gap 0.8255)
		)
		(pad "5" thru_hole circle
			(at -2.210054 -1.27)
			(size 0.8636 0.8636)
			(drill 0.508)
			(layers "*.Cu" "*.Mask")
			(remove_unused_layers no)
			(net "GND")
			(clearance 0.8255)
			(thermal_gap 0.8255)
		)
		(pad "6" thru_hole circle
			(at -2.549906 0)
			(size 0.8636 0.8636)
			(drill 0.508)
			(layers "*.Cu" "*.Mask")
			(remove_unused_layers no)
			(net "GND")
			(clearance 0.8255)
			(thermal_gap 0.8255)
		)
		(zone
			(layers "F.Cu" "B.Cu" "In1.Cu" "In2.Cu" "In3.Cu" "In4.Cu" "In5.Cu" "In6.Cu")
			(hatch none 0.5)
			(connect_pads
				(clearance 0)
			)
			(min_thickness 0.25)
			(keepout
				(tracks allowed)
				(vias not_allowed)
				(pads allowed)
				(copperpour not_allowed)
				(footprints allowed)
			)
			(placement
				(enabled no)
				(sheetname "")
			)
			(fill
				(thermal_gap 0.5)
				(thermal_bridge_width 0.5)
				(island_removal_mode 0)
			)
			(polygon
				(pts
					(arc
						(start 9.818116 -488.403138)
						(mid 1.182116 -488.403138)
						(end 9.818116 -488.403138)
					)
				)
			)
		)
		(zone
			(layers "F.Cu" "B.Cu" "In1.Cu" "In2.Cu" "In3.Cu" "In4.Cu" "In5.Cu" "In6.Cu")
			(hatch none 0.5)
			(connect_pads
				(clearance 0)
			)
			(min_thickness 0.25)
			(keepout
				(tracks not_allowed)
				(vias allowed)
				(pads allowed)
				(copperpour not_allowed)
				(footprints allowed)
			)
			(placement
				(enabled no)
				(sheetname "")
			)
			(fill
				(thermal_gap 0.5)
				(thermal_bridge_width 0.5)
				(island_removal_mode 0)
			)
			(polygon
				(pts
					(arc
						(start 7.839456 -486.790746)
						(mid 5.500196 -481.891643)
						(end 3.160522 -486.790746)
					)
					(arc
						(start 3.160522 -486.790746)
						(mid 3.406489 -487.231112)
						(end 3.491738 -487.72826)
					)
					(arc
						(start 3.491738 -488.40009)
						(mid 5.500116 -490.408468)
						(end 7.50824 -488.40009)
					)
					(arc
						(start 7.50824 -487.72826)
						(mid 7.593475 -487.231106)
						(end 7.839456 -486.790746)
					)
				)
			)
		)
	)
	(footprint ""
		(layer "F.Cu")
		(at 207.391 -94.234 180)
		(property "Reference" "R9506"
			(at 0 0 180)
			(layer "F.SilkS")
			(hide yes)
			(effects
				(font
					(size 1.27 1.27)
				)
			)
		)
		(property "Value" "4K7R2J-2-GP"
			(at 0.064008 -3.993896 180)
			(unlocked yes)
			(layer "F.Fab")
			(hide yes)
			(effects
				(font
					(size 1.016 1.016)
					(thickness 0.1524)
				)
			)
		)
		(property "Device Type" "R402H16"
			(at 0.064008 -5.517896 180)
			(unlocked yes)
			(layer "F.Fab")
			(hide yes)
			(effects
				(font
					(size 1.016 1.016)
					(thickness 0.1524)
				)
			)
		)
		(duplicate_pad_numbers_are_jumpers no)
		(fp_line
			(start 0.508 -0.9398)
			(end -0.508 -0.9398)
			(stroke
				(width 0.1524)
				(type default)
			)
			(layer "F.SilkS")
		)
		(fp_line
			(start -0.508 -0.9398)
			(end -0.508 0.9398)
			(stroke
				(width 0.1524)
				(type default)
			)
			(layer "F.SilkS")
		)
		(fp_rect
			(start -0.508 0.9398)
			(end 0.508 -0.9398)
			(stroke
				(width 0)
				(type default)
			)
			(fill no)
			(layer "F.CrtYd")
		)
		(fp_rect
			(start -0.508 0.9398)
			(end 0.508 -0.9398)
			(stroke
				(width 0)
				(type default)
			)
			(fill no)
			(layer "F.Fab")
		)
		(pad "1" smd custom
			(at 0 -0.4445 180)
			(size 0.1397 0.1397)
			(layers "F.Cu" "F.Mask" "F.Paste")
			(net "P3V3")
			(options
				(clearance outline)
				(anchor circle)
			)
			(primitives
				(gr_poly
					(pts
						(arc
							(start -0.1778 -0.2794)
							(mid -0.249642 -0.249642)
							(end -0.2794 -0.1778)
						)
						(arc
							(start -0.2794 0.1778)
							(mid -0.249642 0.249642)
							(end -0.1778 0.2794)
						)
						(arc
							(start 0.1778 0.2794)
							(mid 0.249642 0.249642)
							(end 0.2794 0.1778)
						)
						(arc
							(start 0.2794 -0.1778)
							(mid 0.249642 -0.249642)
							(end 0.1778 -0.2794)
						)
					)
					(width 0)
					(fill yes)
				)
			)
		)
		(pad "2" smd custom
			(at 0 0.4445 180)
			(size 0.1397 0.1397)
			(layers "F.Cu" "F.Mask" "F.Paste")
			(net "SSD4_PWREN")
			(options
				(clearance outline)
				(anchor circle)
			)
			(primitives
				(gr_poly
					(pts
						(arc
							(start -0.1778 -0.2794)
							(mid -0.249642 -0.249642)
							(end -0.2794 -0.1778)
						)
						(arc
							(start -0.2794 0.1778)
							(mid -0.249642 0.249642)
							(end -0.1778 0.2794)
						)
						(arc
							(start 0.1778 0.2794)
							(mid 0.249642 0.249642)
							(end 0.2794 0.1778)
						)
						(arc
							(start 0.2794 -0.1778)
							(mid 0.249642 -0.249642)
							(end 0.1778 -0.2794)
						)
					)
					(width 0)
					(fill yes)
				)
			)
		)
	)
	(footprint ""
		(layer "F.Cu")
		(at 8.90905 -500.44985 90)
		(property "Reference" "R9813"
			(at 0 0 90)
			(layer "F.SilkS")
			(hide yes)
			(effects
				(font
					(size 1.27 1.27)
				)
			)
		)
		(property "Value" "1KR2J-1-GP"
			(at 0.064008 -3.993896 90)
			(unlocked yes)
			(layer "F.Fab")
			(hide yes)
			(effects
				(font
					(size 1.016 1.016)
					(thickness 0.1524)
				)
			)
		)
		(property "Device Type" "R402H16"
			(at 0.064008 -5.517896 90)
			(unlocked yes)
			(layer "F.Fab")
			(hide yes)
			(effects
				(font
					(size 1.016 1.016)
					(thickness 0.1524)
				)
			)
		)
		(duplicate_pad_numbers_are_jumpers no)
		(fp_line
			(start 0.508 -0.9398)
			(end -0.508 -0.9398)
			(stroke
				(width 0.1524)
				(type default)
			)
			(layer "F.SilkS")
		)
		(fp_line
			(start -0.508 -0.9398)
			(end -0.508 0.9398)
			(stroke
				(width 0.1524)
				(type default)
			)
			(layer "F.SilkS")
		)
		(fp_rect
			(start -0.508 0.9398)
			(end 0.508 -0.9398)
			(stroke
				(width 0)
				(type default)
			)
			(fill no)
			(layer "F.CrtYd")
		)
		(fp_rect
			(start -0.508 0.9398)
			(end 0.508 -0.9398)
			(stroke
				(width 0)
				(type default)
			)
			(fill no)
			(layer "F.Fab")
		)
		(pad "1" smd custom
			(at 0 -0.4445 90)
			(size 0.1397 0.1397)
			(layers "F.Cu" "F.Mask" "F.Paste")
			(net "SSD5_PWREN")
			(options
				(clearance outline)
				(anchor circle)
			)
			(primitives
				(gr_poly
					(pts
						(arc
							(start -0.1778 -0.2794)
							(mid -0.249642 -0.249642)
							(end -0.2794 -0.1778)
						)
						(arc
							(start -0.2794 0.1778)
							(mid -0.249642 0.249642)
							(end -0.1778 0.2794)
						)
						(arc
							(start 0.1778 0.2794)
							(mid 0.249642 0.249642)
							(end 0.2794 0.1778)
						)
						(arc
							(start 0.2794 -0.1778)
							(mid 0.249642 -0.249642)
							(end 0.1778 -0.2794)
						)
					)
					(width 0)
					(fill yes)
				)
			)
		)
		(pad "2" smd custom
			(at 0 0.4445 90)
			(size 0.1397 0.1397)
			(layers "F.Cu" "F.Mask" "F.Paste")
			(net "SSD5_PWREN_R")
			(options
				(clearance outline)
				(anchor circle)
			)
			(primitives
				(gr_poly
					(pts
						(arc
							(start -0.1778 -0.2794)
							(mid -0.249642 -0.249642)
							(end -0.2794 -0.1778)
						)
						(arc
							(start -0.2794 0.1778)
							(mid -0.249642 0.249642)
							(end -0.1778 0.2794)
						)
						(arc
							(start 0.1778 0.2794)
							(mid 0.249642 0.249642)
							(end 0.2794 0.1778)
						)
						(arc
							(start 0.2794 -0.1778)
							(mid 0.249642 -0.249642)
							(end 0.1778 -0.2794)
						)
					)
					(width 0)
					(fill yes)
				)
			)
		)
	)
	(footprint ""
		(layer "F.Cu")
		(at 25.7302 -307.7972 90)
		(property "Reference" "R9850"
			(at 0 0 90)
			(layer "F.SilkS")
			(hide yes)
			(effects
				(font
					(size 1.27 1.27)
				)
			)
		)
		(property "Value" "2K2R5F-GP"
			(at 0 -8.9535 90)
			(unlocked yes)
			(layer "F.Fab")
			(hide yes)
			(effects
				(font
					(size 1.27 1.016)
					(thickness 0.1524)
				)
			)
		)
		(property "Device Type" "R805H24"
			(at 0 -10.6299 90)
			(unlocked yes)
			(layer "F.Fab")
			(hide yes)
			(effects
				(font
					(size 1.27 1.016)
					(thickness 0.1524)
				)
			)
		)
		(duplicate_pad_numbers_are_jumpers no)
		(fp_line
			(start 0.889 -1.7018)
			(end -0.889 -1.7018)
			(stroke
				(width 0.1524)
				(type default)
			)
			(layer "F.SilkS")
		)
		(fp_line
			(start 0.889 -1.7018)
			(end 0.889 -0.381)
			(stroke
				(width 0.1524)
				(type default)
			)
			(layer "F.SilkS")
		)
		(fp_line
			(start -0.889 -1.7018)
			(end -0.889 0.2794)
			(stroke
				(width 0.1524)
				(type default)
			)
			(layer "F.SilkS")
		)
		(fp_line
			(start -0.889 0.0762)
			(end -0.889 1.7018)
			(stroke
				(width 0.1524)
				(type default)
			)
			(layer "F.SilkS")
		)
		(fp_line
			(start 0.889 1.7018)
			(end 0.889 -0.508)
			(stroke
				(width 0.1524)
				(type default)
			)
			(layer "F.SilkS")
		)
		(fp_line
			(start -0.889 1.7018)
			(end 0.889 1.7018)
			(stroke
				(width 0.1524)
				(type default)
			)
			(layer "F.SilkS")
		)
		(fp_poly
			(pts
				(xy 0.9652 -1.778) (xy 0.9652 1.778) (xy -0.9652 1.778) (xy -0.9652 -1.778)
			)
			(stroke
				(width 0)
				(type default)
			)
			(fill no)
			(layer "F.CrtYd")
		)
		(fp_rect
			(start -0.9652 1.778)
			(end 0.9652 -1.778)
			(stroke
				(width 0)
				(type default)
			)
			(fill no)
			(layer "F.Fab")
		)
		(pad "1" smd rect
			(at 0 -0.9652 90)
			(size 1.397 1.143)
			(layers "F.Cu" "F.Mask" "F.Paste")
			(net "P12V_SSD11")
		)
		(pad "2" smd rect
			(at 0 0.9652 90)
			(size 1.397 1.143)
			(layers "F.Cu" "F.Mask" "F.Paste")
			(net "P12V_MOST11_GATE_D")
		)
	)
	(footprint ""
		(layer "F.Cu")
		(at 228.9302 -402.4884)
		(property "Reference" "R9248"
			(at 0 0 0)
			(layer "F.SilkS")
			(hide yes)
			(effects
				(font
					(size 1.27 1.27)
				)
			)
		)
		(property "Value" "2R2010F-GP"
			(at 0.0762 -4.5466 0)
			(unlocked yes)
			(layer "F.Fab")
			(hide yes)
			(effects
				(font
					(size 1.016 1.016)
					(thickness 0.1524)
				)
			)
		)
		(property "Device Type" "R2010H26"
			(at 0.0762 -6.1468 0)
			(unlocked yes)
			(layer "F.Fab")
			(hide yes)
			(effects
				(font
					(size 1.016 1.016)
					(thickness 0.1524)
				)
			)
		)
		(duplicate_pad_numbers_are_jumpers no)
		(fp_line
			(start -3.302 -1.651)
			(end -3.302 1.651)
			(stroke
				(width 0.1524)
				(type default)
			)
			(layer "F.SilkS")
		)
		(fp_line
			(start -3.302 1.651)
			(end 3.302 1.651)
			(stroke
				(width 0.1524)
				(type default)
			)
			(layer "F.SilkS")
		)
		(fp_line
			(start 3.302 -1.651)
			(end -3.302 -1.651)
			(stroke
				(width 0.1524)
				(type default)
			)
			(layer "F.SilkS")
		)
		(fp_line
			(start 3.302 1.651)
			(end 3.302 -1.651)
			(stroke
				(width 0.1524)
				(type default)
			)
			(layer "F.SilkS")
		)
		(fp_rect
			(start -3.3782 1.7272)
			(end 3.3782 -1.7272)
			(stroke
				(width 0)
				(type default)
			)
			(fill no)
			(layer "F.CrtYd")
		)
		(fp_poly
			(pts
				(xy 3.3782 -1.7272) (xy -3.3782 -1.7272) (xy -3.3782 1.7272) (xy 3.3782 1.7272)
			)
			(stroke
				(width 0)
				(type default)
			)
			(fill no)
			(layer "F.Fab")
		)
		(pad "1" smd rect
			(at -2.3495 0)
			(size 1.143 2.794)
			(layers "F.Cu" "F.Mask" "F.Paste")
			(net "P12V_SSD1")
		)
		(pad "2" smd rect
			(at 2.3495 0)
			(size 1.143 2.794)
			(layers "F.Cu" "F.Mask" "F.Paste")
			(net "12V_PRECH_SSD1")
		)
	)
	(footprint ""
		(layer "F.Cu")
		(at 46.569884 -450.723 -90)
		(property "Reference" "R9815"
			(at 0 0 270)
			(layer "F.SilkS")
			(hide yes)
			(effects
				(font
					(size 1.27 1.27)
				)
			)
		)
		(property "Value" "0R2J-2-GP"
			(at 0.064008 -3.993896 270)
			(unlocked yes)
			(layer "F.Fab")
			(hide yes)
			(effects
				(font
					(size 1.016 1.016)
					(thickness 0.1524)
				)
			)
		)
		(property "Device Type" "R402H16"
			(at 0.064008 -5.517896 270)
			(unlocked yes)
			(layer "F.Fab")
			(hide yes)
			(effects
				(font
					(size 1.016 1.016)
					(thickness 0.1524)
				)
			)
		)
		(duplicate_pad_numbers_are_jumpers no)
		(fp_line
			(start -0.508 -0.9398)
			(end -0.508 0.9398)
			(stroke
				(width 0.1524)
				(type default)
			)
			(layer "F.SilkS")
		)
		(fp_line
			(start 0.508 -0.9398)
			(end -0.508 -0.9398)
			(stroke
				(width 0.1524)
				(type default)
			)
			(layer "F.SilkS")
		)
		(fp_rect
			(start -0.508 0.9398)
			(end 0.508 -0.9398)
			(stroke
				(width 0)
				(type default)
			)
			(fill no)
			(layer "F.CrtYd")
		)
		(fp_rect
			(start -0.508 0.9398)
			(end 0.508 -0.9398)
			(stroke
				(width 0)
				(type default)
			)
			(fill no)
			(layer "F.Fab")
		)
		(pad "1" smd custom
			(at 0 -0.4445 270)
			(size 0.1397 0.1397)
			(layers "F.Cu" "F.Mask" "F.Paste")
			(net "ATTN_LED_DR5_AND")
			(options
				(clearance outline)
				(anchor circle)
			)
			(primitives
				(gr_poly
					(pts
						(arc
							(start -0.1778 -0.2794)
							(mid -0.249642 -0.249642)
							(end -0.2794 -0.1778)
						)
						(arc
							(start -0.2794 0.1778)
							(mid -0.249642 0.249642)
							(end -0.1778 0.2794)
						)
						(arc
							(start 0.1778 0.2794)
							(mid 0.249642 0.249642)
							(end 0.2794 0.1778)
						)
						(arc
							(start 0.2794 -0.1778)
							(mid 0.249642 -0.249642)
							(end 0.1778 -0.2794)
						)
					)
					(width 0)
					(fill yes)
				)
			)
		)
		(pad "2" smd custom
			(at 0 0.4445 270)
			(size 0.1397 0.1397)
			(layers "F.Cu" "F.Mask" "F.Paste")
			(net "ATTN_LED_DR5_AND_R")
			(options
				(clearance outline)
				(anchor circle)
			)
			(primitives
				(gr_poly
					(pts
						(arc
							(start -0.1778 -0.2794)
							(mid -0.249642 -0.249642)
							(end -0.2794 -0.1778)
						)
						(arc
							(start -0.2794 0.1778)
							(mid -0.249642 0.249642)
							(end -0.1778 0.2794)
						)
						(arc
							(start 0.1778 0.2794)
							(mid 0.249642 0.249642)
							(end 0.2794 0.1778)
						)
						(arc
							(start 0.2794 -0.1778)
							(mid 0.249642 -0.249642)
							(end 0.1778 -0.2794)
						)
					)
					(width 0)
					(fill yes)
				)
			)
		)
	)
	(footprint ""
		(layer "F.Cu")
		(at 219.71 -194.5386 180)
		(property "Reference" "PC1227"
			(at 0 0 180)
			(layer "F.SilkS")
			(hide yes)
			(effects
				(font
					(size 1.27 1.27)
				)
			)
		)
		(property "Value" "SCD1U50V3KX-GP"
			(at 0 -2.8194 180)
			(unlocked yes)
			(layer "F.Fab")
			(hide yes)
			(effects
				(font
					(size 1.016 1.016)
					(thickness 0.1524)
				)
			)
		)
		(property "Device Type" "C603H36"
			(at 0 -4.3434 180)
			(unlocked yes)
			(layer "F.Fab")
			(hide yes)
			(effects
				(font
					(size 1.016 1.016)
					(thickness 0.1524)
				)
			)
		)
		(duplicate_pad_numbers_are_jumpers no)
		(fp_line
			(start 0.508 0)
			(end -0.508 0)
			(stroke
				(width 0.2032)
				(type default)
			)
			(layer "F.SilkS")
		)
		(fp_rect
			(start -0.5842 1.3335)
			(end 0.5842 -1.3335)
			(stroke
				(width 0)
				(type default)
			)
			(fill no)
			(layer "F.CrtYd")
		)
		(fp_rect
			(start -0.5842 1.3335)
			(end 0.5842 -1.3335)
			(stroke
				(width 0)
				(type default)
			)
			(fill no)
			(layer "F.Fab")
		)
		(pad "1" smd custom
			(at 0 -0.762 180)
			(size 0.2159 0.2159)
			(layers "F.Cu" "F.Mask" "F.Paste")
			(net "P12V_SSD3")
			(options
				(clearance outline)
				(anchor circle)
			)
			(primitives
				(gr_poly
					(pts
						(arc
							(start -0.3302 -0.4318)
							(mid -0.402042 -0.402042)
							(end -0.4318 -0.3302)
						)
						(arc
							(start -0.4318 0.3302)
							(mid -0.402042 0.402042)
							(end -0.3302 0.4318)
						)
						(arc
							(start 0.3302 0.4318)
							(mid 0.402042 0.402042)
							(end 0.4318 0.3302)
						)
						(arc
							(start 0.4318 -0.3302)
							(mid 0.402042 -0.402042)
							(end 0.3302 -0.4318)
						)
					)
					(width 0)
					(fill yes)
				)
			)
		)
		(pad "2" smd custom
			(at 0 0.762 180)
			(size 0.2159 0.2159)
			(layers "F.Cu" "F.Mask" "F.Paste")
			(net "GND")
			(options
				(clearance outline)
				(anchor circle)
			)
			(primitives
				(gr_poly
					(pts
						(arc
							(start -0.3302 -0.4318)
							(mid -0.402042 -0.402042)
							(end -0.4318 -0.3302)
						)
						(arc
							(start -0.4318 0.3302)
							(mid -0.402042 0.402042)
							(end -0.3302 0.4318)
						)
						(arc
							(start 0.3302 0.4318)
							(mid 0.402042 0.402042)
							(end 0.4318 0.3302)
						)
						(arc
							(start 0.4318 -0.3302)
							(mid 0.402042 -0.402042)
							(end 0.3302 -0.4318)
						)
					)
					(width 0)
					(fill yes)
				)
			)
		)
	)
	(footprint ""
		(layer "F.Cu")
		(at 28.8671 -94.5261 180)
		(property "Reference" "R9840"
			(at 0 0 180)
			(layer "F.SilkS")
			(hide yes)
			(effects
				(font
					(size 1.27 1.27)
				)
			)
		)
		(property "Value" "47KR2J-2-GP"
			(at 0.064008 -3.993896 180)
			(unlocked yes)
			(layer "F.Fab")
			(hide yes)
			(effects
				(font
					(size 1.016 1.016)
					(thickness 0.1524)
				)
			)
		)
		(property "Device Type" "R402H16"
			(at 0.064008 -5.517896 180)
			(unlocked yes)
			(layer "F.Fab")
			(hide yes)
			(effects
				(font
					(size 1.016 1.016)
					(thickness 0.1524)
				)
			)
		)
		(duplicate_pad_numbers_are_jumpers no)
		(fp_line
			(start 0.508 -0.9398)
			(end -0.508 -0.9398)
			(stroke
				(width 0.1524)
				(type default)
			)
			(layer "F.SilkS")
		)
		(fp_line
			(start -0.508 -0.9398)
			(end -0.508 0.9398)
			(stroke
				(width 0.1524)
				(type default)
			)
			(layer "F.SilkS")
		)
		(fp_rect
			(start -0.508 0.9398)
			(end 0.508 -0.9398)
			(stroke
				(width 0)
				(type default)
			)
			(fill no)
			(layer "F.CrtYd")
		)
		(fp_rect
			(start -0.508 0.9398)
			(end 0.508 -0.9398)
			(stroke
				(width 0)
				(type default)
			)
			(fill no)
			(layer "F.Fab")
		)
		(pad "1" smd custom
			(at 0 -0.4445 180)
			(size 0.1397 0.1397)
			(layers "F.Cu" "F.Mask" "F.Paste")
			(net "P12V")
			(options
				(clearance outline)
				(anchor circle)
			)
			(primitives
				(gr_poly
					(pts
						(arc
							(start -0.1778 -0.2794)
							(mid -0.249642 -0.249642)
							(end -0.2794 -0.1778)
						)
						(arc
							(start -0.2794 0.1778)
							(mid -0.249642 0.249642)
							(end -0.1778 0.2794)
						)
						(arc
							(start 0.1778 0.2794)
							(mid 0.249642 0.249642)
							(end 0.2794 0.1778)
						)
						(arc
							(start 0.2794 -0.1778)
							(mid 0.249642 -0.249642)
							(end 0.1778 -0.2794)
						)
					)
					(width 0)
					(fill yes)
				)
			)
		)
		(pad "2" smd custom
			(at 0 0.4445 180)
			(size 0.1397 0.1397)
			(layers "F.Cu" "F.Mask" "F.Paste")
			(net "P12V_MOST9_GATE")
			(options
				(clearance outline)
				(anchor circle)
			)
			(primitives
				(gr_poly
					(pts
						(arc
							(start -0.1778 -0.2794)
							(mid -0.249642 -0.249642)
							(end -0.2794 -0.1778)
						)
						(arc
							(start -0.2794 0.1778)
							(mid -0.249642 0.249642)
							(end -0.1778 0.2794)
						)
						(arc
							(start 0.1778 0.2794)
							(mid 0.249642 0.249642)
							(end 0.2794 0.1778)
						)
						(arc
							(start 0.2794 -0.1778)
							(mid 0.249642 -0.249642)
							(end 0.1778 -0.2794)
						)
					)
					(width 0)
					(fill yes)
				)
			)
		)
	)
	(footprint ""
		(layer "F.Cu")
		(at 87.63 -418.338 180)
		(property "Reference" "R9608"
			(at 0 0 180)
			(layer "F.SilkS")
			(hide yes)
			(effects
				(font
					(size 1.27 1.27)
				)
			)
		)
		(property "Value" "10R2F-L-GP"
			(at 0.064008 -3.993896 180)
			(unlocked yes)
			(layer "F.Fab")
			(hide yes)
			(effects
				(font
					(size 1.016 1.016)
					(thickness 0.1524)
				)
			)
		)
		(property "Device Type" "R402H14"
			(at 0.064008 -5.517896 180)
			(unlocked yes)
			(layer "F.Fab")
			(hide yes)
			(effects
				(font
					(size 1.016 1.016)
					(thickness 0.1524)
				)
			)
		)
		(duplicate_pad_numbers_are_jumpers no)
		(fp_line
			(start 0.508 -0.9398)
			(end -0.508 -0.9398)
			(stroke
				(width 0.1524)
				(type default)
			)
			(layer "F.SilkS")
		)
		(fp_line
			(start -0.508 -0.9398)
			(end -0.508 0.9398)
			(stroke
				(width 0.1524)
				(type default)
			)
			(layer "F.SilkS")
		)
		(fp_rect
			(start -0.508 0.9398)
			(end 0.508 -0.9398)
			(stroke
				(width 0)
				(type default)
			)
			(fill no)
			(layer "F.CrtYd")
		)
		(fp_rect
			(start -0.508 0.9398)
			(end 0.508 -0.9398)
			(stroke
				(width 0)
				(type default)
			)
			(fill no)
			(layer "F.Fab")
		)
		(pad "1" smd custom
			(at 0 -0.4445 180)
			(size 0.1397 0.1397)
			(layers "F.Cu" "F.Mask" "F.Paste")
			(net "SSD_PRSNT_NET10")
			(options
				(clearance outline)
				(anchor circle)
			)
			(primitives
				(gr_poly
					(pts
						(arc
							(start -0.1778 -0.2794)
							(mid -0.249642 -0.249642)
							(end -0.2794 -0.1778)
						)
						(arc
							(start -0.2794 0.1778)
							(mid -0.249642 0.249642)
							(end -0.1778 0.2794)
						)
						(arc
							(start 0.1778 0.2794)
							(mid 0.249642 0.249642)
							(end 0.2794 0.1778)
						)
						(arc
							(start 0.2794 -0.1778)
							(mid 0.249642 -0.249642)
							(end 0.1778 -0.2794)
						)
					)
					(width 0)
					(fill yes)
				)
			)
		)
		(pad "2" smd custom
			(at 0 0.4445 180)
			(size 0.1397 0.1397)
			(layers "F.Cu" "F.Mask" "F.Paste")
			(net "SSD_PRSNT10")
			(options
				(clearance outline)
				(anchor circle)
			)
			(primitives
				(gr_poly
					(pts
						(arc
							(start -0.1778 -0.2794)
							(mid -0.249642 -0.249642)
							(end -0.2794 -0.1778)
						)
						(arc
							(start -0.2794 0.1778)
							(mid -0.249642 0.249642)
							(end -0.1778 0.2794)
						)
						(arc
							(start 0.1778 0.2794)
							(mid 0.249642 0.249642)
							(end 0.2794 0.1778)
						)
						(arc
							(start 0.2794 -0.1778)
							(mid 0.249642 -0.249642)
							(end 0.1778 -0.2794)
						)
					)
					(width 0)
					(fill yes)
				)
			)
		)
	)
	(footprint ""
		(layer "F.Cu")
		(at 208.534 -300.228)
		(property "Reference" "R9762"
			(at 0 0 0)
			(layer "F.SilkS")
			(hide yes)
			(effects
				(font
					(size 1.27 1.27)
				)
			)
		)
		(property "Value" "4K7R2J-2-GP"
			(at 0.064008 -3.993896 0)
			(unlocked yes)
			(layer "F.Fab")
			(hide yes)
			(effects
				(font
					(size 1.016 1.016)
					(thickness 0.1524)
				)
			)
		)
		(property "Device Type" "R402H16"
			(at 0.064008 -5.517896 0)
			(unlocked yes)
			(layer "F.Fab")
			(hide yes)
			(effects
				(font
					(size 1.016 1.016)
					(thickness 0.1524)
				)
			)
		)
		(duplicate_pad_numbers_are_jumpers no)
		(fp_line
			(start -0.508 -0.9398)
			(end -0.508 0.9398)
			(stroke
				(width 0.1524)
				(type default)
			)
			(layer "F.SilkS")
		)
		(fp_line
			(start 0.508 -0.9398)
			(end -0.508 -0.9398)
			(stroke
				(width 0.1524)
				(type default)
			)
			(layer "F.SilkS")
		)
		(fp_rect
			(start -0.508 0.9398)
			(end 0.508 -0.9398)
			(stroke
				(width 0)
				(type default)
			)
			(fill no)
			(layer "F.CrtYd")
		)
		(fp_rect
			(start -0.508 0.9398)
			(end 0.508 -0.9398)
			(stroke
				(width 0)
				(type default)
			)
			(fill no)
			(layer "F.Fab")
		)
		(pad "1" smd custom
			(at 0 -0.4445)
			(size 0.1397 0.1397)
			(layers "F.Cu" "F.Mask" "F.Paste")
			(net "SSD2_PWREN")
			(options
				(clearance outline)
				(anchor circle)
			)
			(primitives
				(gr_poly
					(pts
						(arc
							(start -0.1778 -0.2794)
							(mid -0.249642 -0.249642)
							(end -0.2794 -0.1778)
						)
						(arc
							(start -0.2794 0.1778)
							(mid -0.249642 0.249642)
							(end -0.1778 0.2794)
						)
						(arc
							(start 0.1778 0.2794)
							(mid 0.249642 0.249642)
							(end 0.2794 0.1778)
						)
						(arc
							(start 0.2794 -0.1778)
							(mid 0.249642 -0.249642)
							(end 0.1778 -0.2794)
						)
					)
					(width 0)
					(fill yes)
				)
			)
		)
		(pad "2" smd custom
			(at 0 0.4445)
			(size 0.1397 0.1397)
			(layers "F.Cu" "F.Mask" "F.Paste")
			(net "GND")
			(options
				(clearance outline)
				(anchor circle)
			)
			(primitives
				(gr_poly
					(pts
						(arc
							(start -0.1778 -0.2794)
							(mid -0.249642 -0.249642)
							(end -0.2794 -0.1778)
						)
						(arc
							(start -0.2794 0.1778)
							(mid -0.249642 0.249642)
							(end -0.1778 0.2794)
						)
						(arc
							(start 0.1778 0.2794)
							(mid 0.249642 0.249642)
							(end 0.2794 0.1778)
						)
						(arc
							(start 0.2794 -0.1778)
							(mid 0.249642 -0.249642)
							(end 0.1778 -0.2794)
						)
					)
					(width 0)
					(fill yes)
				)
			)
		)
	)
	(footprint ""
		(layer "F.Cu")
		(at 45.632116 -346.071952 -90)
		(property "Reference" "R9823"
			(at 0 0 270)
			(layer "F.SilkS")
			(hide yes)
			(effects
				(font
					(size 1.27 1.27)
				)
			)
		)
		(property "Value" "0R2J-2-GP"
			(at 0.064008 -3.993896 270)
			(unlocked yes)
			(layer "F.Fab")
			(hide yes)
			(effects
				(font
					(size 1.016 1.016)
					(thickness 0.1524)
				)
			)
		)
		(property "Device Type" "R402H16"
			(at 0.064008 -5.517896 270)
			(unlocked yes)
			(layer "F.Fab")
			(hide yes)
			(effects
				(font
					(size 1.016 1.016)
					(thickness 0.1524)
				)
			)
		)
		(duplicate_pad_numbers_are_jumpers no)
		(fp_line
			(start -0.508 -0.9398)
			(end -0.508 0.9398)
			(stroke
				(width 0.1524)
				(type default)
			)
			(layer "F.SilkS")
		)
		(fp_line
			(start 0.508 -0.9398)
			(end -0.508 -0.9398)
			(stroke
				(width 0.1524)
				(type default)
			)
			(layer "F.SilkS")
		)
		(fp_rect
			(start -0.508 0.9398)
			(end 0.508 -0.9398)
			(stroke
				(width 0)
				(type default)
			)
			(fill no)
			(layer "F.CrtYd")
		)
		(fp_rect
			(start -0.508 0.9398)
			(end 0.508 -0.9398)
			(stroke
				(width 0)
				(type default)
			)
			(fill no)
			(layer "F.Fab")
		)
		(pad "1" smd custom
			(at 0 -0.4445 270)
			(size 0.1397 0.1397)
			(layers "F.Cu" "F.Mask" "F.Paste")
			(net "SSD_ACT_DR6_R")
			(options
				(clearance outline)
				(anchor circle)
			)
			(primitives
				(gr_poly
					(pts
						(arc
							(start -0.1778 -0.2794)
							(mid -0.249642 -0.249642)
							(end -0.2794 -0.1778)
						)
						(arc
							(start -0.2794 0.1778)
							(mid -0.249642 0.249642)
							(end -0.1778 0.2794)
						)
						(arc
							(start 0.1778 0.2794)
							(mid 0.249642 0.249642)
							(end 0.2794 0.1778)
						)
						(arc
							(start 0.2794 -0.1778)
							(mid 0.249642 -0.249642)
							(end 0.1778 -0.2794)
						)
					)
					(width 0)
					(fill yes)
				)
			)
		)
		(pad "2" smd custom
			(at 0 0.4445 270)
			(size 0.1397 0.1397)
			(layers "F.Cu" "F.Mask" "F.Paste")
			(net "SSD_ACT_DR6")
			(options
				(clearance outline)
				(anchor circle)
			)
			(primitives
				(gr_poly
					(pts
						(arc
							(start -0.1778 -0.2794)
							(mid -0.249642 -0.249642)
							(end -0.2794 -0.1778)
						)
						(arc
							(start -0.2794 0.1778)
							(mid -0.249642 0.249642)
							(end -0.1778 0.2794)
						)
						(arc
							(start 0.1778 0.2794)
							(mid 0.249642 0.249642)
							(end 0.2794 0.1778)
						)
						(arc
							(start 0.2794 -0.1778)
							(mid 0.249642 -0.249642)
							(end 0.1778 -0.2794)
						)
					)
					(width 0)
					(fill yes)
				)
			)
		)
	)
	(footprint ""
		(layer "F.Cu")
		(at 20.1676 -206.5528 180)
		(property "Reference" "R9252"
			(at 0 0 180)
			(layer "F.SilkS")
			(hide yes)
			(effects
				(font
					(size 1.27 1.27)
				)
			)
		)
		(property "Value" "2R2010F-GP"
			(at 0.0762 -4.5466 180)
			(unlocked yes)
			(layer "F.Fab")
			(hide yes)
			(effects
				(font
					(size 1.016 1.016)
					(thickness 0.1524)
				)
			)
		)
		(property "Device Type" "R2010H26"
			(at 0.0762 -6.1468 180)
			(unlocked yes)
			(layer "F.Fab")
			(hide yes)
			(effects
				(font
					(size 1.016 1.016)
					(thickness 0.1524)
				)
			)
		)
		(duplicate_pad_numbers_are_jumpers no)
		(fp_line
			(start 3.302 1.651)
			(end 3.302 -1.651)
			(stroke
				(width 0.1524)
				(type default)
			)
			(layer "F.SilkS")
		)
		(fp_line
			(start 3.302 -1.651)
			(end -3.302 -1.651)
			(stroke
				(width 0.1524)
				(type default)
			)
			(layer "F.SilkS")
		)
		(fp_line
			(start -3.302 1.651)
			(end 3.302 1.651)
			(stroke
				(width 0.1524)
				(type default)
			)
			(layer "F.SilkS")
		)
		(fp_line
			(start -3.302 -1.651)
			(end -3.302 1.651)
			(stroke
				(width 0.1524)
				(type default)
			)
			(layer "F.SilkS")
		)
		(fp_rect
			(start -3.3782 1.7272)
			(end 3.3782 -1.7272)
			(stroke
				(width 0)
				(type default)
			)
			(fill no)
			(layer "F.CrtYd")
		)
		(fp_poly
			(pts
				(xy 3.3782 -1.7272) (xy -3.3782 -1.7272) (xy -3.3782 1.7272) (xy 3.3782 1.7272)
			)
			(stroke
				(width 0)
				(type default)
			)
			(fill no)
			(layer "F.Fab")
		)
		(pad "1" smd rect
			(at -2.3495 0 180)
			(size 1.143 2.794)
			(layers "F.Cu" "F.Mask" "F.Paste")
			(net "P12V_SSD12")
		)
		(pad "2" smd rect
			(at 2.3495 0 180)
			(size 1.143 2.794)
			(layers "F.Cu" "F.Mask" "F.Paste")
			(net "12V_PRECH_SSD12")
		)
	)
	(footprint ""
		(layer "F.Cu")
		(at 229.67696 -447.11874)
		(property "Reference" "C9518"
			(at 0 0 0)
			(layer "F.SilkS")
			(hide yes)
			(effects
				(font
					(size 1.27 1.27)
				)
			)
		)
		(property "Value" "SCD1U16V2KX-3GP"
			(at 1.1811 -2.7051 0)
			(unlocked yes)
			(layer "F.Fab")
			(hide yes)
			(effects
				(font
					(size 1.016 1.016)
					(thickness 0.1524)
				)
			)
		)
		(property "Device Type" "C402H22"
			(at 1.1811 -4.2291 0)
			(unlocked yes)
			(layer "F.Fab")
			(hide yes)
			(effects
				(font
					(size 1.016 1.016)
					(thickness 0.1524)
				)
			)
		)
		(duplicate_pad_numbers_are_jumpers no)
		(fp_rect
			(start -0.4318 0.9525)
			(end 0.4318 -0.9525)
			(stroke
				(width 0)
				(type default)
			)
			(fill no)
			(layer "F.CrtYd")
		)
		(fp_rect
			(start -0.4318 0.9525)
			(end 0.4318 -0.9525)
			(stroke
				(width 0)
				(type default)
			)
			(fill no)
			(layer "F.Fab")
		)
		(pad "1" smd custom
			(at 0 -0.4445)
			(size 0.1524 0.1524)
			(layers "F.Cu" "F.Mask" "F.Paste")
			(net "P3V3")
			(options
				(clearance outline)
				(anchor circle)
			)
			(primitives
				(gr_poly
					(pts
						(arc
							(start 0.3048 -0.2032)
							(mid 0.275042 -0.275042)
							(end 0.2032 -0.3048)
						)
						(arc
							(start -0.2032 -0.3048)
							(mid -0.275042 -0.275042)
							(end -0.3048 -0.2032)
						)
						(arc
							(start -0.3048 0.2032)
							(mid -0.275042 0.275042)
							(end -0.2032 0.3048)
						)
						(arc
							(start 0.2032 0.3048)
							(mid 0.275042 0.275042)
							(end 0.3048 0.2032)
						)
					)
					(width 0)
					(fill yes)
				)
			)
		)
		(pad "2" smd custom
			(at 0 0.4445)
			(size 0.1524 0.1524)
			(layers "F.Cu" "F.Mask" "F.Paste")
			(net "GND")
			(options
				(clearance outline)
				(anchor circle)
			)
			(primitives
				(gr_poly
					(pts
						(arc
							(start 0.3048 -0.2032)
							(mid 0.275042 -0.275042)
							(end 0.2032 -0.3048)
						)
						(arc
							(start -0.2032 -0.3048)
							(mid -0.275042 -0.275042)
							(end -0.3048 -0.2032)
						)
						(arc
							(start -0.3048 0.2032)
							(mid -0.275042 0.275042)
							(end -0.2032 0.3048)
						)
						(arc
							(start 0.2032 0.3048)
							(mid 0.275042 0.275042)
							(end 0.3048 0.2032)
						)
					)
					(width 0)
					(fill yes)
				)
			)
		)
	)
	(footprint ""
		(layer "F.Cu")
		(at 228.256592 -243.834158 180)
		(property "Reference" "SR1126"
			(at 0 0 180)
			(layer "F.SilkS")
			(hide yes)
			(effects
				(font
					(size 1.27 1.27)
				)
			)
		)
		(property "Value" "4K7R2J-2-GP"
			(at 0.064008 -3.993896 180)
			(unlocked yes)
			(layer "F.Fab")
			(hide yes)
			(effects
				(font
					(size 1.016 1.016)
					(thickness 0.1524)
				)
			)
		)
		(property "Device Type" "R402H16"
			(at 0.064008 -5.517896 180)
			(unlocked yes)
			(layer "F.Fab")
			(hide yes)
			(effects
				(font
					(size 1.016 1.016)
					(thickness 0.1524)
				)
			)
		)
		(duplicate_pad_numbers_are_jumpers no)
		(fp_line
			(start 0.508 -0.9398)
			(end -0.508 -0.9398)
			(stroke
				(width 0.1524)
				(type default)
			)
			(layer "F.SilkS")
		)
		(fp_line
			(start -0.508 -0.9398)
			(end -0.508 0.9398)
			(stroke
				(width 0.1524)
				(type default)
			)
			(layer "F.SilkS")
		)
		(fp_rect
			(start -0.508 0.9398)
			(end 0.508 -0.9398)
			(stroke
				(width 0)
				(type default)
			)
			(fill no)
			(layer "F.CrtYd")
		)
		(fp_rect
			(start -0.508 0.9398)
			(end 0.508 -0.9398)
			(stroke
				(width 0)
				(type default)
			)
			(fill no)
			(layer "F.Fab")
		)
		(pad "1" smd custom
			(at 0 -0.4445 180)
			(size 0.1397 0.1397)
			(layers "F.Cu" "F.Mask" "F.Paste")
			(net "P3V3")
			(options
				(clearance outline)
				(anchor circle)
			)
			(primitives
				(gr_poly
					(pts
						(arc
							(start -0.1778 -0.2794)
							(mid -0.249642 -0.249642)
							(end -0.2794 -0.1778)
						)
						(arc
							(start -0.2794 0.1778)
							(mid -0.249642 0.249642)
							(end -0.1778 0.2794)
						)
						(arc
							(start 0.1778 0.2794)
							(mid 0.249642 0.249642)
							(end 0.2794 0.1778)
						)
						(arc
							(start 0.2794 -0.1778)
							(mid 0.249642 -0.249642)
							(end 0.1778 -0.2794)
						)
					)
					(width 0)
					(fill yes)
				)
			)
		)
		(pad "2" smd custom
			(at 0 0.4445 180)
			(size 0.1397 0.1397)
			(layers "F.Cu" "F.Mask" "F.Paste")
			(net "SSD_ACT_DR2")
			(options
				(clearance outline)
				(anchor circle)
			)
			(primitives
				(gr_poly
					(pts
						(arc
							(start -0.1778 -0.2794)
							(mid -0.249642 -0.249642)
							(end -0.2794 -0.1778)
						)
						(arc
							(start -0.2794 0.1778)
							(mid -0.249642 0.249642)
							(end -0.1778 0.2794)
						)
						(arc
							(start 0.1778 0.2794)
							(mid 0.249642 0.249642)
							(end 0.2794 0.1778)
						)
						(arc
							(start 0.2794 -0.1778)
							(mid 0.249642 -0.249642)
							(end 0.1778 -0.2794)
						)
					)
					(width 0)
					(fill yes)
				)
			)
		)
	)
	(footprint ""
		(layer "F.Cu")
		(at 209.296 -91.186 180)
		(property "Reference" "Q12"
			(at 0 0 180)
			(layer "F.SilkS")
			(hide yes)
			(effects
				(font
					(size 1.27 1.27)
				)
			)
		)
		(property "Value" "2N7002A-7-GP"
			(at 0.127 -8.9662 180)
			(unlocked yes)
			(layer "F.Fab")
			(hide yes)
			(effects
				(font
					(size 1.016 1.016)
					(thickness 0.1524)
				)
			)
		)
		(property "Device Type" "SOT23DGS2D4H48"
			(at 0.127 -10.4902 180)
			(unlocked yes)
			(layer "F.Fab")
			(hide yes)
			(effects
				(font
					(size 1.016 1.016)
					(thickness 0.1524)
				)
			)
		)
		(duplicate_pad_numbers_are_jumpers no)
		(fp_line
			(start 1.651 1.778)
			(end 1.651 -1.778)
			(stroke
				(width 0.1524)
				(type default)
			)
			(layer "F.SilkS")
		)
		(fp_line
			(start 1.651 -1.778)
			(end -1.651 -1.778)
			(stroke
				(width 0.1524)
				(type default)
			)
			(layer "F.SilkS")
		)
		(fp_line
			(start -1.651 1.778)
			(end 1.651 1.778)
			(stroke
				(width 0.1524)
				(type default)
			)
			(layer "F.SilkS")
		)
		(fp_line
			(start -1.651 -1.778)
			(end -1.651 1.778)
			(stroke
				(width 0.1524)
				(type default)
			)
			(layer "F.SilkS")
		)
		(fp_poly
			(pts
				(xy -1.778 1.8796) (xy -1.778 -1.8796) (xy 1.778 -1.8796) (xy 1.778 1.8796)
			)
			(stroke
				(width 0)
				(type default)
			)
			(fill no)
			(layer "F.CrtYd")
		)
		(fp_poly
			(pts
				(xy -1.778 1.8796) (xy -1.778 -1.8796) (xy 1.778 -1.8796) (xy 1.778 1.8796)
			)
			(stroke
				(width 0)
				(type default)
			)
			(fill no)
			(layer "F.Fab")
		)
		(pad "D" smd custom
			(at 0 -0.9525 180)
			(size 0.1905 0.1905)
			(layers "F.Cu" "F.Mask" "F.Paste")
			(net "SW_SSD4_R")
			(options
				(clearance outline)
				(anchor circle)
			)
			(primitives
				(gr_poly
					(pts
						(arc
							(start -0.1778 0.5715)
							(mid -0.321484 0.511984)
							(end -0.381 0.3683)
						)
						(arc
							(start -0.381 -0.3683)
							(mid -0.321484 -0.511984)
							(end -0.1778 -0.5715)
						)
						(arc
							(start 0.1778 -0.5715)
							(mid 0.321484 -0.511984)
							(end 0.381 -0.3683)
						)
						(arc
							(start 0.381 0.3683)
							(mid 0.321484 0.511984)
							(end 0.1778 0.5715)
						)
					)
					(width 0)
					(fill yes)
				)
			)
		)
		(pad "G" smd custom
			(at -0.98425 0.9525 180)
			(size 0.1905 0.1905)
			(layers "F.Cu" "F.Mask" "F.Paste")
			(net "SSD4_PWREN")
			(options
				(clearance outline)
				(anchor circle)
			)
			(primitives
				(gr_poly
					(pts
						(arc
							(start -0.1778 0.5715)
							(mid -0.321484 0.511984)
							(end -0.381 0.3683)
						)
						(arc
							(start -0.381 -0.3683)
							(mid -0.321484 -0.511984)
							(end -0.1778 -0.5715)
						)
						(arc
							(start 0.1778 -0.5715)
							(mid 0.321484 -0.511984)
							(end 0.381 -0.3683)
						)
						(arc
							(start 0.381 0.3683)
							(mid 0.321484 0.511984)
							(end 0.1778 0.5715)
						)
					)
					(width 0)
					(fill yes)
				)
			)
		)
		(pad "S" smd custom
			(at 0.98425 0.9525 180)
			(size 0.1905 0.1905)
			(layers "F.Cu" "F.Mask" "F.Paste")
			(net "GND")
			(options
				(clearance outline)
				(anchor circle)
			)
			(primitives
				(gr_poly
					(pts
						(arc
							(start -0.1778 0.5715)
							(mid -0.321484 0.511984)
							(end -0.381 0.3683)
						)
						(arc
							(start -0.381 -0.3683)
							(mid -0.321484 -0.511984)
							(end -0.1778 -0.5715)
						)
						(arc
							(start 0.1778 -0.5715)
							(mid 0.321484 -0.511984)
							(end 0.381 -0.3683)
						)
						(arc
							(start 0.381 0.3683)
							(mid 0.321484 0.511984)
							(end 0.1778 0.5715)
						)
					)
					(width 0)
					(fill yes)
				)
			)
		)
	)
	(footprint ""
		(layer "F.Cu")
		(at 102.743 -313.055 -90)
		(property "Reference" "R9583"
			(at 0 0 270)
			(layer "F.SilkS")
			(hide yes)
			(effects
				(font
					(size 1.27 1.27)
				)
			)
		)
		(property "Value" "0R5J-L1-GP"
			(at 0 -8.9535 270)
			(unlocked yes)
			(layer "F.Fab")
			(hide yes)
			(effects
				(font
					(size 1.27 1.016)
					(thickness 0.1524)
				)
			)
		)
		(property "Device Type" "R805H24"
			(at 0 -10.6299 270)
			(unlocked yes)
			(layer "F.Fab")
			(hide yes)
			(effects
				(font
					(size 1.27 1.016)
					(thickness 0.1524)
				)
			)
		)
		(duplicate_pad_numbers_are_jumpers no)
		(fp_line
			(start -0.889 1.7018)
			(end 0.889 1.7018)
			(stroke
				(width 0.1524)
				(type default)
			)
			(layer "F.SilkS")
		)
		(fp_line
			(start 0.889 1.7018)
			(end 0.889 -0.508)
			(stroke
				(width 0.1524)
				(type default)
			)
			(layer "F.SilkS")
		)
		(fp_line
			(start -0.889 0.0762)
			(end -0.889 1.7018)
			(stroke
				(width 0.1524)
				(type default)
			)
			(layer "F.SilkS")
		)
		(fp_line
			(start -0.889 -1.7018)
			(end -0.889 0.2794)
			(stroke
				(width 0.1524)
				(type default)
			)
			(layer "F.SilkS")
		)
		(fp_line
			(start 0.889 -1.7018)
			(end 0.889 -0.381)
			(stroke
				(width 0.1524)
				(type default)
			)
			(layer "F.SilkS")
		)
		(fp_line
			(start 0.889 -1.7018)
			(end -0.889 -1.7018)
			(stroke
				(width 0.1524)
				(type default)
			)
			(layer "F.SilkS")
		)
		(fp_poly
			(pts
				(xy 0.9652 -1.778) (xy 0.9652 1.778) (xy -0.9652 1.778) (xy -0.9652 -1.778)
			)
			(stroke
				(width 0)
				(type default)
			)
			(fill no)
			(layer "F.CrtYd")
		)
		(fp_rect
			(start -0.9652 1.778)
			(end 0.9652 -1.778)
			(stroke
				(width 0)
				(type default)
			)
			(fill no)
			(layer "F.Fab")
		)
		(pad "1" smd rect
			(at 0 -0.9652 270)
			(size 1.397 1.143)
			(layers "F.Cu" "F.Mask" "F.Paste")
			(net "P3V3")
		)
		(pad "2" smd rect
			(at 0 0.9652 270)
			(size 1.397 1.143)
			(layers "F.Cu" "F.Mask" "F.Paste")
			(net "VDD_IO_2")
		)
	)
	(footprint ""
		(layer "F.Cu")
		(at 45.212 -242.443)
		(property "Reference" "SR1136"
			(at 0 0 0)
			(layer "F.SilkS")
			(hide yes)
			(effects
				(font
					(size 1.27 1.27)
				)
			)
		)
		(property "Value" "4K7R2J-2-GP"
			(at 0.064008 -3.993896 0)
			(unlocked yes)
			(layer "F.Fab")
			(hide yes)
			(effects
				(font
					(size 1.016 1.016)
					(thickness 0.1524)
				)
			)
		)
		(property "Device Type" "R402H16"
			(at 0.064008 -5.517896 0)
			(unlocked yes)
			(layer "F.Fab")
			(hide yes)
			(effects
				(font
					(size 1.016 1.016)
					(thickness 0.1524)
				)
			)
		)
		(duplicate_pad_numbers_are_jumpers no)
		(fp_line
			(start -0.508 -0.9398)
			(end -0.508 0.9398)
			(stroke
				(width 0.1524)
				(type default)
			)
			(layer "F.SilkS")
		)
		(fp_line
			(start 0.508 -0.9398)
			(end -0.508 -0.9398)
			(stroke
				(width 0.1524)
				(type default)
			)
			(layer "F.SilkS")
		)
		(fp_rect
			(start -0.508 0.9398)
			(end 0.508 -0.9398)
			(stroke
				(width 0)
				(type default)
			)
			(fill no)
			(layer "F.CrtYd")
		)
		(fp_rect
			(start -0.508 0.9398)
			(end 0.508 -0.9398)
			(stroke
				(width 0)
				(type default)
			)
			(fill no)
			(layer "F.Fab")
		)
		(pad "1" smd custom
			(at 0 -0.4445)
			(size 0.1397 0.1397)
			(layers "F.Cu" "F.Mask" "F.Paste")
			(net "P3V3")
			(options
				(clearance outline)
				(anchor circle)
			)
			(primitives
				(gr_poly
					(pts
						(arc
							(start -0.1778 -0.2794)
							(mid -0.249642 -0.249642)
							(end -0.2794 -0.1778)
						)
						(arc
							(start -0.2794 0.1778)
							(mid -0.249642 0.249642)
							(end -0.1778 0.2794)
						)
						(arc
							(start 0.1778 0.2794)
							(mid 0.249642 0.249642)
							(end 0.2794 0.1778)
						)
						(arc
							(start 0.2794 -0.1778)
							(mid 0.249642 -0.249642)
							(end 0.1778 -0.2794)
						)
					)
					(width 0)
					(fill yes)
				)
			)
		)
		(pad "2" smd custom
			(at 0 0.4445)
			(size 0.1397 0.1397)
			(layers "F.Cu" "F.Mask" "F.Paste")
			(net "SSD_ACT_DR7")
			(options
				(clearance outline)
				(anchor circle)
			)
			(primitives
				(gr_poly
					(pts
						(arc
							(start -0.1778 -0.2794)
							(mid -0.249642 -0.249642)
							(end -0.2794 -0.1778)
						)
						(arc
							(start -0.2794 0.1778)
							(mid -0.249642 0.249642)
							(end -0.1778 0.2794)
						)
						(arc
							(start 0.1778 0.2794)
							(mid 0.249642 0.249642)
							(end 0.2794 0.1778)
						)
						(arc
							(start 0.2794 -0.1778)
							(mid 0.249642 -0.249642)
							(end 0.1778 -0.2794)
						)
					)
					(width 0)
					(fill yes)
				)
			)
		)
	)
	(footprint ""
		(layer "F.Cu")
		(at 16.26616 -259.58419 180)
		(property "Reference" "R9951"
			(at 0 0 180)
			(layer "F.SilkS")
			(hide yes)
			(effects
				(font
					(size 1.27 1.27)
				)
			)
		)
		(property "Value" "4K7R2J-2-GP"
			(at 0.064008 -3.993896 180)
			(unlocked yes)
			(layer "F.Fab")
			(hide yes)
			(effects
				(font
					(size 1.016 1.016)
					(thickness 0.1524)
				)
			)
		)
		(property "Device Type" "R402H16"
			(at 0.064008 -5.517896 180)
			(unlocked yes)
			(layer "F.Fab")
			(hide yes)
			(effects
				(font
					(size 1.016 1.016)
					(thickness 0.1524)
				)
			)
		)
		(duplicate_pad_numbers_are_jumpers no)
		(fp_line
			(start 0.508 -0.9398)
			(end -0.508 -0.9398)
			(stroke
				(width 0.1524)
				(type default)
			)
			(layer "F.SilkS")
		)
		(fp_line
			(start -0.508 -0.9398)
			(end -0.508 0.9398)
			(stroke
				(width 0.1524)
				(type default)
			)
			(layer "F.SilkS")
		)
		(fp_rect
			(start -0.508 0.9398)
			(end 0.508 -0.9398)
			(stroke
				(width 0)
				(type default)
			)
			(fill no)
			(layer "F.CrtYd")
		)
		(fp_rect
			(start -0.508 0.9398)
			(end 0.508 -0.9398)
			(stroke
				(width 0)
				(type default)
			)
			(fill no)
			(layer "F.Fab")
		)
		(pad "1" smd custom
			(at 0 -0.4445 180)
			(size 0.1397 0.1397)
			(layers "F.Cu" "F.Mask" "F.Paste")
			(net "P3V3")
			(options
				(clearance outline)
				(anchor circle)
			)
			(primitives
				(gr_poly
					(pts
						(arc
							(start -0.1778 -0.2794)
							(mid -0.249642 -0.249642)
							(end -0.2794 -0.1778)
						)
						(arc
							(start -0.2794 0.1778)
							(mid -0.249642 0.249642)
							(end -0.1778 0.2794)
						)
						(arc
							(start 0.1778 0.2794)
							(mid 0.249642 0.249642)
							(end 0.2794 0.1778)
						)
						(arc
							(start 0.2794 -0.1778)
							(mid 0.249642 -0.249642)
							(end 0.1778 -0.2794)
						)
					)
					(width 0)
					(fill yes)
				)
			)
		)
		(pad "2" smd custom
			(at 0 0.4445 180)
			(size 0.1397 0.1397)
			(layers "F.Cu" "F.Mask" "F.Paste")
			(net "ATTN_LED_DR12_MOS_N")
			(options
				(clearance outline)
				(anchor circle)
			)
			(primitives
				(gr_poly
					(pts
						(arc
							(start -0.1778 -0.2794)
							(mid -0.249642 -0.249642)
							(end -0.2794 -0.1778)
						)
						(arc
							(start -0.2794 0.1778)
							(mid -0.249642 0.249642)
							(end -0.1778 0.2794)
						)
						(arc
							(start 0.1778 0.2794)
							(mid 0.249642 0.249642)
							(end 0.2794 0.1778)
						)
						(arc
							(start 0.2794 -0.1778)
							(mid 0.249642 -0.249642)
							(end 0.1778 -0.2794)
						)
					)
					(width 0)
					(fill yes)
				)
			)
		)
	)
	(footprint ""
		(layer "F.Cu")
		(at 24.9936 -214.0966 180)
		(property "Reference" "PC1253"
			(at 0 0 180)
			(layer "F.SilkS")
			(hide yes)
			(effects
				(font
					(size 1.27 1.27)
				)
			)
		)
		(property "Value" "SCD01U50V2KX-1GP"
			(at 1.1811 -2.7051 180)
			(unlocked yes)
			(layer "F.Fab")
			(hide yes)
			(effects
				(font
					(size 1.016 1.016)
					(thickness 0.1524)
				)
			)
		)
		(property "Device Type" "C402H22"
			(at 1.1811 -4.2291 180)
			(unlocked yes)
			(layer "F.Fab")
			(hide yes)
			(effects
				(font
					(size 1.016 1.016)
					(thickness 0.1524)
				)
			)
		)
		(duplicate_pad_numbers_are_jumpers no)
		(fp_rect
			(start -0.4318 0.9525)
			(end 0.4318 -0.9525)
			(stroke
				(width 0)
				(type default)
			)
			(fill no)
			(layer "F.CrtYd")
		)
		(fp_rect
			(start -0.4318 0.9525)
			(end 0.4318 -0.9525)
			(stroke
				(width 0)
				(type default)
			)
			(fill no)
			(layer "F.Fab")
		)
		(pad "1" smd custom
			(at 0 -0.4445 180)
			(size 0.1524 0.1524)
			(layers "F.Cu" "F.Mask" "F.Paste")
			(net "P12V_SSD12")
			(options
				(clearance outline)
				(anchor circle)
			)
			(primitives
				(gr_poly
					(pts
						(arc
							(start 0.3048 -0.2032)
							(mid 0.275042 -0.275042)
							(end 0.2032 -0.3048)
						)
						(arc
							(start -0.2032 -0.3048)
							(mid -0.275042 -0.275042)
							(end -0.3048 -0.2032)
						)
						(arc
							(start -0.3048 0.2032)
							(mid -0.275042 0.275042)
							(end -0.2032 0.3048)
						)
						(arc
							(start 0.2032 0.3048)
							(mid 0.275042 0.275042)
							(end 0.3048 0.2032)
						)
					)
					(width 0)
					(fill yes)
				)
			)
		)
		(pad "2" smd custom
			(at 0 0.4445 180)
			(size 0.1524 0.1524)
			(layers "F.Cu" "F.Mask" "F.Paste")
			(net "GND")
			(options
				(clearance outline)
				(anchor circle)
			)
			(primitives
				(gr_poly
					(pts
						(arc
							(start 0.3048 -0.2032)
							(mid 0.275042 -0.275042)
							(end 0.2032 -0.3048)
						)
						(arc
							(start -0.2032 -0.3048)
							(mid -0.275042 -0.275042)
							(end -0.3048 -0.2032)
						)
						(arc
							(start -0.3048 0.2032)
							(mid -0.275042 0.275042)
							(end -0.2032 0.3048)
						)
						(arc
							(start 0.2032 0.3048)
							(mid 0.275042 0.275042)
							(end 0.3048 0.2032)
						)
					)
					(width 0)
					(fill yes)
				)
			)
		)
	)
	(footprint ""
		(layer "F.Cu")
		(at 212.217 -432.816)
		(property "Reference" "PC1286"
			(at 0 0 0)
			(layer "F.SilkS")
			(hide yes)
			(effects
				(font
					(size 1.27 1.27)
				)
			)
		)
		(property "Value" "SC22U6D3V5MX-5-GP"
			(at -0.0762 -6.1214 0)
			(unlocked yes)
			(layer "F.Fab")
			(hide yes)
			(effects
				(font
					(size 1.016 1.016)
					(thickness 0.1524)
				)
			)
		)
		(property "Device Type" "C805H56"
			(at -0.0762 -8.1534 0)
			(unlocked yes)
			(layer "F.Fab")
			(hide yes)
			(effects
				(font
					(size 1.016 1.016)
					(thickness 0.1524)
				)
			)
		)
		(duplicate_pad_numbers_are_jumpers no)
		(fp_line
			(start 0.635 0)
			(end -0.635 0)
			(stroke
				(width 0.508)
				(type default)
			)
			(layer "F.SilkS")
		)
		(fp_rect
			(start -0.9652 1.778)
			(end 0.9652 -1.778)
			(stroke
				(width 0)
				(type default)
			)
			(fill no)
			(layer "F.CrtYd")
		)
		(fp_poly
			(pts
				(xy -0.9652 -1.778) (xy 0.9652 -1.778) (xy 0.9652 1.778) (xy -0.9652 1.778)
			)
			(stroke
				(width 0)
				(type default)
			)
			(fill no)
			(layer "F.Fab")
		)
		(pad "1" smd rect
			(at 0 -0.9652)
			(size 1.397 1.143)
			(layers "F.Cu" "F.Mask" "F.Paste")
			(net "P3V3_OUT")
		)
		(pad "2" smd rect
			(at 0 0.9652)
			(size 1.397 1.143)
			(layers "F.Cu" "F.Mask" "F.Paste")
			(net "GND")
		)
	)
	(footprint ""
		(layer "F.Cu")
		(at 24.8158 -294.7416 -90)
		(property "Reference" "R145"
			(at 0 0 270)
			(layer "F.SilkS")
			(hide yes)
			(effects
				(font
					(size 1.27 1.27)
				)
			)
		)
		(property "Value" "4K7R2J-2-GP"
			(at 0.064008 -3.993896 270)
			(unlocked yes)
			(layer "F.Fab")
			(hide yes)
			(effects
				(font
					(size 1.016 1.016)
					(thickness 0.1524)
				)
			)
		)
		(property "Device Type" "R402H16"
			(at 0.064008 -5.517896 270)
			(unlocked yes)
			(layer "F.Fab")
			(hide yes)
			(effects
				(font
					(size 1.016 1.016)
					(thickness 0.1524)
				)
			)
		)
		(duplicate_pad_numbers_are_jumpers no)
		(fp_line
			(start -0.508 -0.9398)
			(end -0.508 0.9398)
			(stroke
				(width 0.1524)
				(type default)
			)
			(layer "F.SilkS")
		)
		(fp_line
			(start 0.508 -0.9398)
			(end -0.508 -0.9398)
			(stroke
				(width 0.1524)
				(type default)
			)
			(layer "F.SilkS")
		)
		(fp_rect
			(start -0.508 0.9398)
			(end 0.508 -0.9398)
			(stroke
				(width 0)
				(type default)
			)
			(fill no)
			(layer "F.CrtYd")
		)
		(fp_rect
			(start -0.508 0.9398)
			(end 0.508 -0.9398)
			(stroke
				(width 0)
				(type default)
			)
			(fill no)
			(layer "F.Fab")
		)
		(pad "1" smd custom
			(at 0 -0.4445 270)
			(size 0.1397 0.1397)
			(layers "F.Cu" "F.Mask" "F.Paste")
			(net "P12V")
			(options
				(clearance outline)
				(anchor circle)
			)
			(primitives
				(gr_poly
					(pts
						(arc
							(start -0.1778 -0.2794)
							(mid -0.249642 -0.249642)
							(end -0.2794 -0.1778)
						)
						(arc
							(start -0.2794 0.1778)
							(mid -0.249642 0.249642)
							(end -0.1778 0.2794)
						)
						(arc
							(start 0.1778 0.2794)
							(mid 0.249642 0.249642)
							(end 0.2794 0.1778)
						)
						(arc
							(start 0.2794 -0.1778)
							(mid 0.249642 -0.249642)
							(end 0.1778 -0.2794)
						)
					)
					(width 0)
					(fill yes)
				)
			)
		)
		(pad "2" smd custom
			(at 0 0.4445 270)
			(size 0.1397 0.1397)
			(layers "F.Cu" "F.Mask" "F.Paste")
			(net "SW_SSD7_R")
			(options
				(clearance outline)
				(anchor circle)
			)
			(primitives
				(gr_poly
					(pts
						(arc
							(start -0.1778 -0.2794)
							(mid -0.249642 -0.249642)
							(end -0.2794 -0.1778)
						)
						(arc
							(start -0.2794 0.1778)
							(mid -0.249642 0.249642)
							(end -0.1778 0.2794)
						)
						(arc
							(start 0.1778 0.2794)
							(mid 0.249642 0.249642)
							(end 0.2794 0.1778)
						)
						(arc
							(start 0.2794 -0.1778)
							(mid 0.249642 -0.249642)
							(end 0.1778 -0.2794)
						)
					)
					(width 0)
					(fill yes)
				)
			)
		)
	)
	(footprint ""
		(layer "F.Cu")
		(at 24.9936 -111.0996 180)
		(property "Reference" "PC1213"
			(at 0 0 180)
			(layer "F.SilkS")
			(hide yes)
			(effects
				(font
					(size 1.27 1.27)
				)
			)
		)
		(property "Value" "SCD01U50V2KX-1GP"
			(at 1.1811 -2.7051 180)
			(unlocked yes)
			(layer "F.Fab")
			(hide yes)
			(effects
				(font
					(size 1.016 1.016)
					(thickness 0.1524)
				)
			)
		)
		(property "Device Type" "C402H22"
			(at 1.1811 -4.2291 180)
			(unlocked yes)
			(layer "F.Fab")
			(hide yes)
			(effects
				(font
					(size 1.016 1.016)
					(thickness 0.1524)
				)
			)
		)
		(duplicate_pad_numbers_are_jumpers no)
		(fp_rect
			(start -0.4318 0.9525)
			(end 0.4318 -0.9525)
			(stroke
				(width 0)
				(type default)
			)
			(fill no)
			(layer "F.CrtYd")
		)
		(fp_rect
			(start -0.4318 0.9525)
			(end 0.4318 -0.9525)
			(stroke
				(width 0)
				(type default)
			)
			(fill no)
			(layer "F.Fab")
		)
		(pad "1" smd custom
			(at 0 -0.4445 180)
			(size 0.1524 0.1524)
			(layers "F.Cu" "F.Mask" "F.Paste")
			(net "P12V_SSD13")
			(options
				(clearance outline)
				(anchor circle)
			)
			(primitives
				(gr_poly
					(pts
						(arc
							(start 0.3048 -0.2032)
							(mid 0.275042 -0.275042)
							(end 0.2032 -0.3048)
						)
						(arc
							(start -0.2032 -0.3048)
							(mid -0.275042 -0.275042)
							(end -0.3048 -0.2032)
						)
						(arc
							(start -0.3048 0.2032)
							(mid -0.275042 0.275042)
							(end -0.2032 0.3048)
						)
						(arc
							(start 0.2032 0.3048)
							(mid 0.275042 0.275042)
							(end 0.3048 0.2032)
						)
					)
					(width 0)
					(fill yes)
				)
			)
		)
		(pad "2" smd custom
			(at 0 0.4445 180)
			(size 0.1524 0.1524)
			(layers "F.Cu" "F.Mask" "F.Paste")
			(net "GND")
			(options
				(clearance outline)
				(anchor circle)
			)
			(primitives
				(gr_poly
					(pts
						(arc
							(start 0.3048 -0.2032)
							(mid 0.275042 -0.275042)
							(end 0.2032 -0.3048)
						)
						(arc
							(start -0.2032 -0.3048)
							(mid -0.275042 -0.275042)
							(end -0.3048 -0.2032)
						)
						(arc
							(start -0.3048 0.2032)
							(mid -0.275042 0.275042)
							(end -0.2032 0.3048)
						)
						(arc
							(start 0.2032 0.3048)
							(mid 0.275042 0.275042)
							(end 0.3048 0.2032)
						)
					)
					(width 0)
					(fill yes)
				)
			)
		)
	)
	(footprint ""
		(layer "F.Cu")
		(at 215.011 -498.983 180)
		(property "Reference" "PC1187"
			(at 0 0 180)
			(layer "F.SilkS")
			(hide yes)
			(effects
				(font
					(size 1.27 1.27)
				)
			)
		)
		(property "Value" "SCD1U50V3KX-GP"
			(at 0 -2.8194 180)
			(unlocked yes)
			(layer "F.Fab")
			(hide yes)
			(effects
				(font
					(size 1.016 1.016)
					(thickness 0.1524)
				)
			)
		)
		(property "Device Type" "C603H36"
			(at 0 -4.3434 180)
			(unlocked yes)
			(layer "F.Fab")
			(hide yes)
			(effects
				(font
					(size 1.016 1.016)
					(thickness 0.1524)
				)
			)
		)
		(duplicate_pad_numbers_are_jumpers no)
		(fp_line
			(start 0.508 0)
			(end -0.508 0)
			(stroke
				(width 0.2032)
				(type default)
			)
			(layer "F.SilkS")
		)
		(fp_rect
			(start -0.5842 1.3335)
			(end 0.5842 -1.3335)
			(stroke
				(width 0)
				(type default)
			)
			(fill no)
			(layer "F.CrtYd")
		)
		(fp_rect
			(start -0.5842 1.3335)
			(end 0.5842 -1.3335)
			(stroke
				(width 0)
				(type default)
			)
			(fill no)
			(layer "F.Fab")
		)
		(pad "1" smd custom
			(at 0 -0.762 180)
			(size 0.2159 0.2159)
			(layers "F.Cu" "F.Mask" "F.Paste")
			(net "P12V_SSD0")
			(options
				(clearance outline)
				(anchor circle)
			)
			(primitives
				(gr_poly
					(pts
						(arc
							(start -0.3302 -0.4318)
							(mid -0.402042 -0.402042)
							(end -0.4318 -0.3302)
						)
						(arc
							(start -0.4318 0.3302)
							(mid -0.402042 0.402042)
							(end -0.3302 0.4318)
						)
						(arc
							(start 0.3302 0.4318)
							(mid 0.402042 0.402042)
							(end 0.4318 0.3302)
						)
						(arc
							(start 0.4318 -0.3302)
							(mid 0.402042 -0.402042)
							(end 0.3302 -0.4318)
						)
					)
					(width 0)
					(fill yes)
				)
			)
		)
		(pad "2" smd custom
			(at 0 0.762 180)
			(size 0.2159 0.2159)
			(layers "F.Cu" "F.Mask" "F.Paste")
			(net "GND")
			(options
				(clearance outline)
				(anchor circle)
			)
			(primitives
				(gr_poly
					(pts
						(arc
							(start -0.3302 -0.4318)
							(mid -0.402042 -0.402042)
							(end -0.4318 -0.3302)
						)
						(arc
							(start -0.4318 0.3302)
							(mid -0.402042 0.402042)
							(end -0.3302 0.4318)
						)
						(arc
							(start 0.3302 0.4318)
							(mid 0.402042 0.402042)
							(end 0.4318 0.3302)
						)
						(arc
							(start 0.4318 -0.3302)
							(mid 0.402042 -0.402042)
							(end 0.3302 -0.4318)
						)
					)
					(width 0)
					(fill yes)
				)
			)
		)
	)
	(footprint ""
		(layer "F.Cu")
		(at 219.075 -499.237)
		(property "Reference" "R9239"
			(at 0 0 0)
			(layer "F.SilkS")
			(hide yes)
			(effects
				(font
					(size 1.27 1.27)
				)
			)
		)
		(property "Value" "2R2010F-GP"
			(at 0.0762 -4.5466 0)
			(unlocked yes)
			(layer "F.Fab")
			(hide yes)
			(effects
				(font
					(size 1.016 1.016)
					(thickness 0.1524)
				)
			)
		)
		(property "Device Type" "R2010H26"
			(at 0.0762 -6.1468 0)
			(unlocked yes)
			(layer "F.Fab")
			(hide yes)
			(effects
				(font
					(size 1.016 1.016)
					(thickness 0.1524)
				)
			)
		)
		(duplicate_pad_numbers_are_jumpers no)
		(fp_line
			(start -3.302 -1.651)
			(end -3.302 1.651)
			(stroke
				(width 0.1524)
				(type default)
			)
			(layer "F.SilkS")
		)
		(fp_line
			(start -3.302 1.651)
			(end 3.302 1.651)
			(stroke
				(width 0.1524)
				(type default)
			)
			(layer "F.SilkS")
		)
		(fp_line
			(start 3.302 -1.651)
			(end -3.302 -1.651)
			(stroke
				(width 0.1524)
				(type default)
			)
			(layer "F.SilkS")
		)
		(fp_line
			(start 3.302 1.651)
			(end 3.302 -1.651)
			(stroke
				(width 0.1524)
				(type default)
			)
			(layer "F.SilkS")
		)
		(fp_rect
			(start -3.3782 1.7272)
			(end 3.3782 -1.7272)
			(stroke
				(width 0)
				(type default)
			)
			(fill no)
			(layer "F.CrtYd")
		)
		(fp_poly
			(pts
				(xy 3.3782 -1.7272) (xy -3.3782 -1.7272) (xy -3.3782 1.7272) (xy 3.3782 1.7272)
			)
			(stroke
				(width 0)
				(type default)
			)
			(fill no)
			(layer "F.Fab")
		)
		(pad "1" smd rect
			(at -2.3495 0)
			(size 1.143 2.794)
			(layers "F.Cu" "F.Mask" "F.Paste")
			(net "P12V_SSD0")
		)
		(pad "2" smd rect
			(at 2.3495 0)
			(size 1.143 2.794)
			(layers "F.Cu" "F.Mask" "F.Paste")
			(net "12V_PRECH_SSD0")
		)
	)
	(footprint ""
		(layer "F.Cu")
		(at 209.804 -191.643 -90)
		(property "Reference" "R141"
			(at 0 0 270)
			(layer "F.SilkS")
			(hide yes)
			(effects
				(font
					(size 1.27 1.27)
				)
			)
		)
		(property "Value" "4K7R2J-2-GP"
			(at 0.064008 -3.993896 270)
			(unlocked yes)
			(layer "F.Fab")
			(hide yes)
			(effects
				(font
					(size 1.016 1.016)
					(thickness 0.1524)
				)
			)
		)
		(property "Device Type" "R402H16"
			(at 0.064008 -5.517896 270)
			(unlocked yes)
			(layer "F.Fab")
			(hide yes)
			(effects
				(font
					(size 1.016 1.016)
					(thickness 0.1524)
				)
			)
		)
		(duplicate_pad_numbers_are_jumpers no)
		(fp_line
			(start -0.508 -0.9398)
			(end -0.508 0.9398)
			(stroke
				(width 0.1524)
				(type default)
			)
			(layer "F.SilkS")
		)
		(fp_line
			(start 0.508 -0.9398)
			(end -0.508 -0.9398)
			(stroke
				(width 0.1524)
				(type default)
			)
			(layer "F.SilkS")
		)
		(fp_rect
			(start -0.508 0.9398)
			(end 0.508 -0.9398)
			(stroke
				(width 0)
				(type default)
			)
			(fill no)
			(layer "F.CrtYd")
		)
		(fp_rect
			(start -0.508 0.9398)
			(end 0.508 -0.9398)
			(stroke
				(width 0)
				(type default)
			)
			(fill no)
			(layer "F.Fab")
		)
		(pad "1" smd custom
			(at 0 -0.4445 270)
			(size 0.1397 0.1397)
			(layers "F.Cu" "F.Mask" "F.Paste")
			(net "P12V")
			(options
				(clearance outline)
				(anchor circle)
			)
			(primitives
				(gr_poly
					(pts
						(arc
							(start -0.1778 -0.2794)
							(mid -0.249642 -0.249642)
							(end -0.2794 -0.1778)
						)
						(arc
							(start -0.2794 0.1778)
							(mid -0.249642 0.249642)
							(end -0.1778 0.2794)
						)
						(arc
							(start 0.1778 0.2794)
							(mid 0.249642 0.249642)
							(end 0.2794 0.1778)
						)
						(arc
							(start 0.2794 -0.1778)
							(mid 0.249642 -0.249642)
							(end 0.1778 -0.2794)
						)
					)
					(width 0)
					(fill yes)
				)
			)
		)
		(pad "2" smd custom
			(at 0 0.4445 270)
			(size 0.1397 0.1397)
			(layers "F.Cu" "F.Mask" "F.Paste")
			(net "SW_SSD3_R")
			(options
				(clearance outline)
				(anchor circle)
			)
			(primitives
				(gr_poly
					(pts
						(arc
							(start -0.1778 -0.2794)
							(mid -0.249642 -0.249642)
							(end -0.2794 -0.1778)
						)
						(arc
							(start -0.2794 0.1778)
							(mid -0.249642 0.249642)
							(end -0.1778 0.2794)
						)
						(arc
							(start 0.1778 0.2794)
							(mid 0.249642 0.249642)
							(end 0.2794 0.1778)
						)
						(arc
							(start 0.2794 -0.1778)
							(mid 0.249642 -0.249642)
							(end 0.1778 -0.2794)
						)
					)
					(width 0)
					(fill yes)
				)
			)
		)
	)
	(footprint ""
		(layer "F.Cu")
		(at 90.297 -313.817 180)
		(property "Reference" "R9079"
			(at 0 0 180)
			(layer "F.SilkS")
			(hide yes)
			(effects
				(font
					(size 1.27 1.27)
				)
			)
		)
		(property "Value" "27R2F-GP"
			(at 0.064008 -3.993896 180)
			(unlocked yes)
			(layer "F.Fab")
			(hide yes)
			(effects
				(font
					(size 1.016 1.016)
					(thickness 0.1524)
				)
			)
		)
		(property "Device Type" "R402H16"
			(at 0.064008 -5.517896 180)
			(unlocked yes)
			(layer "F.Fab")
			(hide yes)
			(effects
				(font
					(size 1.016 1.016)
					(thickness 0.1524)
				)
			)
		)
		(duplicate_pad_numbers_are_jumpers no)
		(fp_line
			(start 0.508 -0.9398)
			(end -0.508 -0.9398)
			(stroke
				(width 0.1524)
				(type default)
			)
			(layer "F.SilkS")
		)
		(fp_line
			(start -0.508 -0.9398)
			(end -0.508 0.9398)
			(stroke
				(width 0.1524)
				(type default)
			)
			(layer "F.SilkS")
		)
		(fp_rect
			(start -0.508 0.9398)
			(end 0.508 -0.9398)
			(stroke
				(width 0)
				(type default)
			)
			(fill no)
			(layer "F.CrtYd")
		)
		(fp_rect
			(start -0.508 0.9398)
			(end 0.508 -0.9398)
			(stroke
				(width 0)
				(type default)
			)
			(fill no)
			(layer "F.Fab")
		)
		(pad "1" smd custom
			(at 0 -0.4445 180)
			(size 0.1397 0.1397)
			(layers "F.Cu" "F.Mask" "F.Paste")
			(net "PE_CLK_100M_DR11_2_R_N")
			(options
				(clearance outline)
				(anchor circle)
			)
			(primitives
				(gr_poly
					(pts
						(arc
							(start -0.1778 -0.2794)
							(mid -0.249642 -0.249642)
							(end -0.2794 -0.1778)
						)
						(arc
							(start -0.2794 0.1778)
							(mid -0.249642 0.249642)
							(end -0.1778 0.2794)
						)
						(arc
							(start 0.1778 0.2794)
							(mid 0.249642 0.249642)
							(end 0.2794 0.1778)
						)
						(arc
							(start 0.2794 -0.1778)
							(mid 0.249642 -0.249642)
							(end 0.1778 -0.2794)
						)
					)
					(width 0)
					(fill yes)
				)
			)
		)
		(pad "2" smd custom
			(at 0 0.4445 180)
			(size 0.1397 0.1397)
			(layers "F.Cu" "F.Mask" "F.Paste")
			(net "PE_CLK100M_DR11_2_N")
			(options
				(clearance outline)
				(anchor circle)
			)
			(primitives
				(gr_poly
					(pts
						(arc
							(start -0.1778 -0.2794)
							(mid -0.249642 -0.249642)
							(end -0.2794 -0.1778)
						)
						(arc
							(start -0.2794 0.1778)
							(mid -0.249642 0.249642)
							(end -0.1778 0.2794)
						)
						(arc
							(start 0.1778 0.2794)
							(mid 0.249642 0.249642)
							(end 0.2794 0.1778)
						)
						(arc
							(start 0.2794 -0.1778)
							(mid 0.249642 -0.249642)
							(end 0.1778 -0.2794)
						)
					)
					(width 0)
					(fill yes)
				)
			)
		)
	)
	(footprint ""
		(layer "F.Cu")
		(at 24.003 -197.231)
		(property "Reference" "R9768"
			(at 0 0 0)
			(layer "F.SilkS")
			(hide yes)
			(effects
				(font
					(size 1.27 1.27)
				)
			)
		)
		(property "Value" "4K7R2J-2-GP"
			(at 0.064008 -3.993896 0)
			(unlocked yes)
			(layer "F.Fab")
			(hide yes)
			(effects
				(font
					(size 1.016 1.016)
					(thickness 0.1524)
				)
			)
		)
		(property "Device Type" "R402H16"
			(at 0.064008 -5.517896 0)
			(unlocked yes)
			(layer "F.Fab")
			(hide yes)
			(effects
				(font
					(size 1.016 1.016)
					(thickness 0.1524)
				)
			)
		)
		(duplicate_pad_numbers_are_jumpers no)
		(fp_line
			(start -0.508 -0.9398)
			(end -0.508 0.9398)
			(stroke
				(width 0.1524)
				(type default)
			)
			(layer "F.SilkS")
		)
		(fp_line
			(start 0.508 -0.9398)
			(end -0.508 -0.9398)
			(stroke
				(width 0.1524)
				(type default)
			)
			(layer "F.SilkS")
		)
		(fp_rect
			(start -0.508 0.9398)
			(end 0.508 -0.9398)
			(stroke
				(width 0)
				(type default)
			)
			(fill no)
			(layer "F.CrtYd")
		)
		(fp_rect
			(start -0.508 0.9398)
			(end 0.508 -0.9398)
			(stroke
				(width 0)
				(type default)
			)
			(fill no)
			(layer "F.Fab")
		)
		(pad "1" smd custom
			(at 0 -0.4445)
			(size 0.1397 0.1397)
			(layers "F.Cu" "F.Mask" "F.Paste")
			(net "SSD8_PWREN")
			(options
				(clearance outline)
				(anchor circle)
			)
			(primitives
				(gr_poly
					(pts
						(arc
							(start -0.1778 -0.2794)
							(mid -0.249642 -0.249642)
							(end -0.2794 -0.1778)
						)
						(arc
							(start -0.2794 0.1778)
							(mid -0.249642 0.249642)
							(end -0.1778 0.2794)
						)
						(arc
							(start 0.1778 0.2794)
							(mid 0.249642 0.249642)
							(end 0.2794 0.1778)
						)
						(arc
							(start 0.2794 -0.1778)
							(mid 0.249642 -0.249642)
							(end 0.1778 -0.2794)
						)
					)
					(width 0)
					(fill yes)
				)
			)
		)
		(pad "2" smd custom
			(at 0 0.4445)
			(size 0.1397 0.1397)
			(layers "F.Cu" "F.Mask" "F.Paste")
			(net "GND")
			(options
				(clearance outline)
				(anchor circle)
			)
			(primitives
				(gr_poly
					(pts
						(arc
							(start -0.1778 -0.2794)
							(mid -0.249642 -0.249642)
							(end -0.2794 -0.1778)
						)
						(arc
							(start -0.2794 0.1778)
							(mid -0.249642 0.249642)
							(end -0.1778 0.2794)
						)
						(arc
							(start 0.1778 0.2794)
							(mid 0.249642 0.249642)
							(end 0.2794 0.1778)
						)
						(arc
							(start 0.2794 -0.1778)
							(mid 0.249642 -0.249642)
							(end 0.1778 -0.2794)
						)
					)
					(width 0)
					(fill yes)
				)
			)
		)
	)
	(footprint ""
		(layer "F.Cu")
		(at 221.1324 -95.6056 -90)
		(property "Reference" "R9804"
			(at 0 0 270)
			(layer "F.SilkS")
			(hide yes)
			(effects
				(font
					(size 1.27 1.27)
				)
			)
		)
		(property "Value" "2K2R5F-GP"
			(at 0 -8.9535 270)
			(unlocked yes)
			(layer "F.Fab")
			(hide yes)
			(effects
				(font
					(size 1.27 1.016)
					(thickness 0.1524)
				)
			)
		)
		(property "Device Type" "R805H24"
			(at 0 -10.6299 270)
			(unlocked yes)
			(layer "F.Fab")
			(hide yes)
			(effects
				(font
					(size 1.27 1.016)
					(thickness 0.1524)
				)
			)
		)
		(duplicate_pad_numbers_are_jumpers no)
		(fp_line
			(start -0.889 1.7018)
			(end 0.889 1.7018)
			(stroke
				(width 0.1524)
				(type default)
			)
			(layer "F.SilkS")
		)
		(fp_line
			(start 0.889 1.7018)
			(end 0.889 -0.508)
			(stroke
				(width 0.1524)
				(type default)
			)
			(layer "F.SilkS")
		)
		(fp_line
			(start -0.889 0.0762)
			(end -0.889 1.7018)
			(stroke
				(width 0.1524)
				(type default)
			)
			(layer "F.SilkS")
		)
		(fp_line
			(start -0.889 -1.7018)
			(end -0.889 0.2794)
			(stroke
				(width 0.1524)
				(type default)
			)
			(layer "F.SilkS")
		)
		(fp_line
			(start 0.889 -1.7018)
			(end 0.889 -0.381)
			(stroke
				(width 0.1524)
				(type default)
			)
			(layer "F.SilkS")
		)
		(fp_line
			(start 0.889 -1.7018)
			(end -0.889 -1.7018)
			(stroke
				(width 0.1524)
				(type default)
			)
			(layer "F.SilkS")
		)
		(fp_poly
			(pts
				(xy 0.9652 -1.778) (xy 0.9652 1.778) (xy -0.9652 1.778) (xy -0.9652 -1.778)
			)
			(stroke
				(width 0)
				(type default)
			)
			(fill no)
			(layer "F.CrtYd")
		)
		(fp_rect
			(start -0.9652 1.778)
			(end 0.9652 -1.778)
			(stroke
				(width 0)
				(type default)
			)
			(fill no)
			(layer "F.Fab")
		)
		(pad "1" smd rect
			(at 0 -0.9652 270)
			(size 1.397 1.143)
			(layers "F.Cu" "F.Mask" "F.Paste")
			(net "P12V_SSD4")
		)
		(pad "2" smd rect
			(at 0 0.9652 270)
			(size 1.397 1.143)
			(layers "F.Cu" "F.Mask" "F.Paste")
			(net "P12V_MOST4_GATE_D")
		)
	)
	(footprint ""
		(layer "F.Cu")
		(at 32.004 -318.4652 180)
		(property "Reference" "SR1113"
			(at 0 0 180)
			(layer "F.SilkS")
			(hide yes)
			(effects
				(font
					(size 1.27 1.27)
				)
			)
		)
		(property "Value" "4K7R2F-GP"
			(at 0.064008 -3.993896 180)
			(unlocked yes)
			(layer "F.Fab")
			(hide yes)
			(effects
				(font
					(size 1.016 1.016)
					(thickness 0.1524)
				)
			)
		)
		(property "Device Type" "R402H16"
			(at 0.064008 -5.517896 180)
			(unlocked yes)
			(layer "F.Fab")
			(hide yes)
			(effects
				(font
					(size 1.016 1.016)
					(thickness 0.1524)
				)
			)
		)
		(duplicate_pad_numbers_are_jumpers no)
		(fp_line
			(start 0.508 -0.9398)
			(end -0.508 -0.9398)
			(stroke
				(width 0.1524)
				(type default)
			)
			(layer "F.SilkS")
		)
		(fp_line
			(start -0.508 -0.9398)
			(end -0.508 0.9398)
			(stroke
				(width 0.1524)
				(type default)
			)
			(layer "F.SilkS")
		)
		(fp_rect
			(start -0.508 0.9398)
			(end 0.508 -0.9398)
			(stroke
				(width 0)
				(type default)
			)
			(fill no)
			(layer "F.CrtYd")
		)
		(fp_rect
			(start -0.508 0.9398)
			(end 0.508 -0.9398)
			(stroke
				(width 0)
				(type default)
			)
			(fill no)
			(layer "F.Fab")
		)
		(pad "1" smd custom
			(at 0 -0.4445 180)
			(size 0.1397 0.1397)
			(layers "F.Cu" "F.Mask" "F.Paste")
			(net "P3V3")
			(options
				(clearance outline)
				(anchor circle)
			)
			(primitives
				(gr_poly
					(pts
						(arc
							(start -0.1778 -0.2794)
							(mid -0.249642 -0.249642)
							(end -0.2794 -0.1778)
						)
						(arc
							(start -0.2794 0.1778)
							(mid -0.249642 0.249642)
							(end -0.1778 0.2794)
						)
						(arc
							(start 0.1778 0.2794)
							(mid 0.249642 0.249642)
							(end 0.2794 0.1778)
						)
						(arc
							(start 0.2794 -0.1778)
							(mid 0.249642 -0.249642)
							(end 0.1778 -0.2794)
						)
					)
					(width 0)
					(fill yes)
				)
			)
		)
		(pad "2" smd custom
			(at 0 0.4445 180)
			(size 0.1397 0.1397)
			(layers "F.Cu" "F.Mask" "F.Paste")
			(net "DUALPORTEN#11")
			(options
				(clearance outline)
				(anchor circle)
			)
			(primitives
				(gr_poly
					(pts
						(arc
							(start -0.1778 -0.2794)
							(mid -0.249642 -0.249642)
							(end -0.2794 -0.1778)
						)
						(arc
							(start -0.2794 0.1778)
							(mid -0.249642 0.249642)
							(end -0.1778 0.2794)
						)
						(arc
							(start 0.1778 0.2794)
							(mid 0.249642 0.249642)
							(end 0.2794 0.1778)
						)
						(arc
							(start 0.2794 -0.1778)
							(mid 0.249642 -0.249642)
							(end 0.1778 -0.2794)
						)
					)
					(width 0)
					(fill yes)
				)
			)
		)
	)
	(footprint ""
		(layer "F.Cu")
		(at 233.807 -35.802062 180)
		(property "Reference" "Q48"
			(at 0 0 180)
			(layer "F.SilkS")
			(hide yes)
			(effects
				(font
					(size 1.27 1.27)
				)
			)
		)
		(property "Value" "2N7002A-7-GP"
			(at 0.127 -8.9662 180)
			(unlocked yes)
			(layer "F.Fab")
			(hide yes)
			(effects
				(font
					(size 1.016 1.016)
					(thickness 0.1524)
				)
			)
		)
		(property "Device Type" "SOT23DGS2D4H48"
			(at 0.127 -10.4902 180)
			(unlocked yes)
			(layer "F.Fab")
			(hide yes)
			(effects
				(font
					(size 1.016 1.016)
					(thickness 0.1524)
				)
			)
		)
		(duplicate_pad_numbers_are_jumpers no)
		(fp_line
			(start 1.651 1.778)
			(end 1.651 -1.778)
			(stroke
				(width 0.1524)
				(type default)
			)
			(layer "F.SilkS")
		)
		(fp_line
			(start 1.651 -1.778)
			(end -1.651 -1.778)
			(stroke
				(width 0.1524)
				(type default)
			)
			(layer "F.SilkS")
		)
		(fp_line
			(start -1.651 1.778)
			(end 1.651 1.778)
			(stroke
				(width 0.1524)
				(type default)
			)
			(layer "F.SilkS")
		)
		(fp_line
			(start -1.651 -1.778)
			(end -1.651 1.778)
			(stroke
				(width 0.1524)
				(type default)
			)
			(layer "F.SilkS")
		)
		(fp_poly
			(pts
				(xy -1.778 1.8796) (xy -1.778 -1.8796) (xy 1.778 -1.8796) (xy 1.778 1.8796)
			)
			(stroke
				(width 0)
				(type default)
			)
			(fill no)
			(layer "F.CrtYd")
		)
		(fp_poly
			(pts
				(xy -1.778 1.8796) (xy -1.778 -1.8796) (xy 1.778 -1.8796) (xy 1.778 1.8796)
			)
			(stroke
				(width 0)
				(type default)
			)
			(fill no)
			(layer "F.Fab")
		)
		(pad "D" smd custom
			(at 0 -0.9525 180)
			(size 0.1905 0.1905)
			(layers "F.Cu" "F.Mask" "F.Paste")
			(net "SSD_ACT_DR4_MOS_N")
			(options
				(clearance outline)
				(anchor circle)
			)
			(primitives
				(gr_poly
					(pts
						(arc
							(start -0.1778 0.5715)
							(mid -0.321484 0.511984)
							(end -0.381 0.3683)
						)
						(arc
							(start -0.381 -0.3683)
							(mid -0.321484 -0.511984)
							(end -0.1778 -0.5715)
						)
						(arc
							(start 0.1778 -0.5715)
							(mid 0.321484 -0.511984)
							(end 0.381 -0.3683)
						)
						(arc
							(start 0.381 0.3683)
							(mid 0.321484 0.511984)
							(end 0.1778 0.5715)
						)
					)
					(width 0)
					(fill yes)
				)
			)
		)
		(pad "G" smd custom
			(at -0.98425 0.9525 180)
			(size 0.1905 0.1905)
			(layers "F.Cu" "F.Mask" "F.Paste")
			(net "ATTN_LED_DR4_AND_R")
			(options
				(clearance outline)
				(anchor circle)
			)
			(primitives
				(gr_poly
					(pts
						(arc
							(start -0.1778 0.5715)
							(mid -0.321484 0.511984)
							(end -0.381 0.3683)
						)
						(arc
							(start -0.381 -0.3683)
							(mid -0.321484 -0.511984)
							(end -0.1778 -0.5715)
						)
						(arc
							(start 0.1778 -0.5715)
							(mid 0.321484 -0.511984)
							(end 0.381 -0.3683)
						)
						(arc
							(start 0.381 0.3683)
							(mid 0.321484 0.511984)
							(end 0.1778 0.5715)
						)
					)
					(width 0)
					(fill yes)
				)
			)
		)
		(pad "S" smd custom
			(at 0.98425 0.9525 180)
			(size 0.1905 0.1905)
			(layers "F.Cu" "F.Mask" "F.Paste")
			(net "SSD_ACT_DR4_R")
			(options
				(clearance outline)
				(anchor circle)
			)
			(primitives
				(gr_poly
					(pts
						(arc
							(start -0.1778 0.5715)
							(mid -0.321484 0.511984)
							(end -0.381 0.3683)
						)
						(arc
							(start -0.381 -0.3683)
							(mid -0.321484 -0.511984)
							(end -0.1778 -0.5715)
						)
						(arc
							(start 0.1778 -0.5715)
							(mid 0.321484 -0.511984)
							(end 0.381 -0.3683)
						)
						(arc
							(start 0.381 0.3683)
							(mid 0.321484 0.511984)
							(end 0.1778 0.5715)
						)
					)
					(width 0)
					(fill yes)
				)
			)
		)
	)
	(footprint ""
		(layer "F.Cu")
		(at 77.089 -354.076)
		(property "Reference" "SR1050"
			(at 0 0 0)
			(layer "F.SilkS")
			(hide yes)
			(effects
				(font
					(size 1.27 1.27)
				)
			)
		)
		(property "Value" "4K7R2F-GP"
			(at 0.064008 -3.993896 0)
			(unlocked yes)
			(layer "F.Fab")
			(hide yes)
			(effects
				(font
					(size 1.016 1.016)
					(thickness 0.1524)
				)
			)
		)
		(property "Device Type" "R402H16"
			(at 0.064008 -5.517896 0)
			(unlocked yes)
			(layer "F.Fab")
			(hide yes)
			(effects
				(font
					(size 1.016 1.016)
					(thickness 0.1524)
				)
			)
		)
		(duplicate_pad_numbers_are_jumpers no)
		(fp_line
			(start -0.508 -0.9398)
			(end -0.508 0.9398)
			(stroke
				(width 0.1524)
				(type default)
			)
			(layer "F.SilkS")
		)
		(fp_line
			(start 0.508 -0.9398)
			(end -0.508 -0.9398)
			(stroke
				(width 0.1524)
				(type default)
			)
			(layer "F.SilkS")
		)
		(fp_rect
			(start -0.508 0.9398)
			(end 0.508 -0.9398)
			(stroke
				(width 0)
				(type default)
			)
			(fill no)
			(layer "F.CrtYd")
		)
		(fp_rect
			(start -0.508 0.9398)
			(end 0.508 -0.9398)
			(stroke
				(width 0)
				(type default)
			)
			(fill no)
			(layer "F.Fab")
		)
		(pad "1" smd custom
			(at 0 -0.4445)
			(size 0.1397 0.1397)
			(layers "F.Cu" "F.Mask" "F.Paste")
			(net "I2C_SW_EU17_ADDRESS_A0")
			(options
				(clearance outline)
				(anchor circle)
			)
			(primitives
				(gr_poly
					(pts
						(arc
							(start -0.1778 -0.2794)
							(mid -0.249642 -0.249642)
							(end -0.2794 -0.1778)
						)
						(arc
							(start -0.2794 0.1778)
							(mid -0.249642 0.249642)
							(end -0.1778 0.2794)
						)
						(arc
							(start 0.1778 0.2794)
							(mid 0.249642 0.249642)
							(end 0.2794 0.1778)
						)
						(arc
							(start 0.2794 -0.1778)
							(mid 0.249642 -0.249642)
							(end 0.1778 -0.2794)
						)
					)
					(width 0)
					(fill yes)
				)
			)
		)
		(pad "2" smd custom
			(at 0 0.4445)
			(size 0.1397 0.1397)
			(layers "F.Cu" "F.Mask" "F.Paste")
			(net "GND")
			(options
				(clearance outline)
				(anchor circle)
			)
			(primitives
				(gr_poly
					(pts
						(arc
							(start -0.1778 -0.2794)
							(mid -0.249642 -0.249642)
							(end -0.2794 -0.1778)
						)
						(arc
							(start -0.2794 0.1778)
							(mid -0.249642 0.249642)
							(end -0.1778 0.2794)
						)
						(arc
							(start 0.1778 0.2794)
							(mid 0.249642 0.249642)
							(end 0.2794 0.1778)
						)
						(arc
							(start 0.2794 -0.1778)
							(mid 0.249642 -0.249642)
							(end 0.1778 -0.2794)
						)
					)
					(width 0)
					(fill yes)
				)
			)
		)
	)
	(footprint ""
		(layer "F.Cu")
		(at 32.3088 -314.0964 90)
		(property "Reference" "U20"
			(at 0 0 90)
			(layer "F.SilkS")
			(hide yes)
			(effects
				(font
					(size 1.27 1.27)
				)
			)
		)
		(property "Value" "P2003EVG-GP"
			(at 0 -11.1252 90)
			(unlocked yes)
			(layer "F.Fab")
			(hide yes)
			(effects
				(font
					(size 1.016 1.016)
					(thickness 0.1524)
				)
			)
		)
		(property "Device Type" "SOIC8H79"
			(at 0 -12.6492 90)
			(unlocked yes)
			(layer "F.Fab")
			(hide yes)
			(effects
				(font
					(size 1.016 1.016)
					(thickness 0.1524)
				)
			)
		)
		(duplicate_pad_numbers_are_jumpers no)
		(fp_line
			(start 2.1336 -1.4224)
			(end -2.7432 -1.4224)
			(stroke
				(width 0.1524)
				(type default)
			)
			(layer "F.SilkS")
		)
		(fp_line
			(start -2.7432 -1.4224)
			(end -2.7432 1.4224)
			(stroke
				(width 0.1524)
				(type default)
			)
			(layer "F.SilkS")
		)
		(fp_line
			(start -2.7432 -0.508)
			(end -2.2352 0)
			(stroke
				(width 0.1524)
				(type default)
			)
			(layer "F.SilkS")
		)
		(fp_line
			(start -2.2352 0)
			(end -2.7432 0.508)
			(stroke
				(width 0.1524)
				(type default)
			)
			(layer "F.SilkS")
		)
		(fp_line
			(start 2.1336 1.4224)
			(end 2.1336 -1.4224)
			(stroke
				(width 0.1524)
				(type default)
			)
			(layer "F.SilkS")
		)
		(fp_line
			(start -2.7432 1.4224)
			(end 2.1336 1.4224)
			(stroke
				(width 0.1524)
				(type default)
			)
			(layer "F.SilkS")
		)
		(fp_line
			(start -2.6162 3.429)
			(end -2.6162 1.4732)
			(stroke
				(width 0.4064)
				(type default)
			)
			(layer "F.SilkS")
		)
		(fp_poly
			(pts
				(xy 2.2098 -1.4224) (xy 2.2098 1.4224) (xy -2.2225 1.4224) (xy -2.2225 -1.4224)
			)
			(stroke
				(width 0)
				(type default)
			)
			(fill yes)
			(layer "F.SilkS")
		)
		(fp_rect
			(start -2.4511 2.9972)
			(end 2.4511 -2.9972)
			(stroke
				(width 0)
				(type default)
			)
			(fill no)
			(layer "F.CrtYd")
		)
		(fp_poly
			(pts
				(xy -2.8194 3.6322) (xy -2.8194 -3.6322) (xy 2.8194 -3.6322) (xy 2.8194 -2.2987) (xy 2.4511 -2.2987)
				(xy 2.4511 -2.9972) (xy -2.4511 -2.9972) (xy -2.4511 2.9972) (xy 2.4511 2.9972) (xy 2.4511 -2.286)
				(xy 2.8194 -2.286) (xy 2.8194 3.6322)
			)
			(stroke
				(width 0)
				(type default)
			)
			(fill no)
			(layer "F.CrtYd")
		)
		(fp_rect
			(start -2.8194 3.6322)
			(end 2.8194 -3.6322)
			(stroke
				(width 0)
				(type default)
			)
			(fill no)
			(layer "F.Fab")
		)
		(pad "1" smd rect
			(at -1.905 2.54 90)
			(size 0.635 1.651)
			(layers "F.Cu" "F.Mask" "F.Paste")
			(net "P12V")
		)
		(pad "2" smd rect
			(at -0.635 2.54 90)
			(size 0.635 1.651)
			(layers "F.Cu" "F.Mask" "F.Paste")
			(net "P12V")
		)
		(pad "3" smd rect
			(at 0.635 2.54 90)
			(size 0.635 1.651)
			(layers "F.Cu" "F.Mask" "F.Paste")
			(net "P12V")
		)
		(pad "4" smd rect
			(at 1.905 2.54 90)
			(size 0.635 1.651)
			(layers "F.Cu" "F.Mask" "F.Paste")
			(net "SW_SSD11_N")
		)
		(pad "5" smd rect
			(at 1.905 -2.54 90)
			(size 0.635 1.651)
			(layers "F.Cu" "F.Mask" "F.Paste")
			(net "P12V_SSD11")
		)
		(pad "6" smd rect
			(at 0.635 -2.54 90)
			(size 0.635 1.651)
			(layers "F.Cu" "F.Mask" "F.Paste")
			(net "P12V_SSD11")
		)
		(pad "7" smd rect
			(at -0.635 -2.54 90)
			(size 0.635 1.651)
			(layers "F.Cu" "F.Mask" "F.Paste")
			(net "P12V_SSD11")
		)
		(pad "8" smd rect
			(at -1.905 -2.54 90)
			(size 0.635 1.651)
			(layers "F.Cu" "F.Mask" "F.Paste")
			(net "P12V_SSD11")
		)
	)
	(footprint ""
		(layer "F.Cu")
		(at 88.011 -215.519)
		(property "Reference" "C8915"
			(at 0 0 0)
			(layer "F.SilkS")
			(hide yes)
			(effects
				(font
					(size 1.27 1.27)
				)
			)
		)
		(property "Value" "SCD1U16V2KX-3GP"
			(at 1.1811 -2.7051 0)
			(unlocked yes)
			(layer "F.Fab")
			(hide yes)
			(effects
				(font
					(size 1.016 1.016)
					(thickness 0.1524)
				)
			)
		)
		(property "Device Type" "C402H22"
			(at 1.1811 -4.2291 0)
			(unlocked yes)
			(layer "F.Fab")
			(hide yes)
			(effects
				(font
					(size 1.016 1.016)
					(thickness 0.1524)
				)
			)
		)
		(duplicate_pad_numbers_are_jumpers no)
		(fp_rect
			(start -0.4318 0.9525)
			(end 0.4318 -0.9525)
			(stroke
				(width 0)
				(type default)
			)
			(fill no)
			(layer "F.CrtYd")
		)
		(fp_rect
			(start -0.4318 0.9525)
			(end 0.4318 -0.9525)
			(stroke
				(width 0)
				(type default)
			)
			(fill no)
			(layer "F.Fab")
		)
		(pad "1" smd custom
			(at 0 -0.4445)
			(size 0.1524 0.1524)
			(layers "F.Cu" "F.Mask" "F.Paste")
			(net "VDDA_3")
			(options
				(clearance outline)
				(anchor circle)
			)
			(primitives
				(gr_poly
					(pts
						(arc
							(start 0.3048 -0.2032)
							(mid 0.275042 -0.275042)
							(end 0.2032 -0.3048)
						)
						(arc
							(start -0.2032 -0.3048)
							(mid -0.275042 -0.275042)
							(end -0.3048 -0.2032)
						)
						(arc
							(start -0.3048 0.2032)
							(mid -0.275042 0.275042)
							(end -0.2032 0.3048)
						)
						(arc
							(start 0.2032 0.3048)
							(mid 0.275042 0.275042)
							(end 0.3048 0.2032)
						)
					)
					(width 0)
					(fill yes)
				)
			)
		)
		(pad "2" smd custom
			(at 0 0.4445)
			(size 0.1524 0.1524)
			(layers "F.Cu" "F.Mask" "F.Paste")
			(net "GND")
			(options
				(clearance outline)
				(anchor circle)
			)
			(primitives
				(gr_poly
					(pts
						(arc
							(start 0.3048 -0.2032)
							(mid 0.275042 -0.275042)
							(end 0.2032 -0.3048)
						)
						(arc
							(start -0.2032 -0.3048)
							(mid -0.275042 -0.275042)
							(end -0.3048 -0.2032)
						)
						(arc
							(start -0.3048 0.2032)
							(mid -0.275042 0.275042)
							(end -0.2032 0.3048)
						)
						(arc
							(start 0.2032 0.3048)
							(mid 0.275042 0.275042)
							(end 0.3048 0.2032)
						)
					)
					(width 0)
					(fill yes)
				)
			)
		)
	)
	(footprint ""
		(layer "F.Cu")
		(at 230.886 -37.199062 -90)
		(property "Reference" "R9809"
			(at 0 0 270)
			(layer "F.SilkS")
			(hide yes)
			(effects
				(font
					(size 1.27 1.27)
				)
			)
		)
		(property "Value" "0R2J-2-GP"
			(at 0.064008 -3.993896 270)
			(unlocked yes)
			(layer "F.Fab")
			(hide yes)
			(effects
				(font
					(size 1.016 1.016)
					(thickness 0.1524)
				)
			)
		)
		(property "Device Type" "R402H16"
			(at 0.064008 -5.517896 270)
			(unlocked yes)
			(layer "F.Fab")
			(hide yes)
			(effects
				(font
					(size 1.016 1.016)
					(thickness 0.1524)
				)
			)
		)
		(duplicate_pad_numbers_are_jumpers no)
		(fp_line
			(start -0.508 -0.9398)
			(end -0.508 0.9398)
			(stroke
				(width 0.1524)
				(type default)
			)
			(layer "F.SilkS")
		)
		(fp_line
			(start 0.508 -0.9398)
			(end -0.508 -0.9398)
			(stroke
				(width 0.1524)
				(type default)
			)
			(layer "F.SilkS")
		)
		(fp_rect
			(start -0.508 0.9398)
			(end 0.508 -0.9398)
			(stroke
				(width 0)
				(type default)
			)
			(fill no)
			(layer "F.CrtYd")
		)
		(fp_rect
			(start -0.508 0.9398)
			(end 0.508 -0.9398)
			(stroke
				(width 0)
				(type default)
			)
			(fill no)
			(layer "F.Fab")
		)
		(pad "1" smd custom
			(at 0 -0.4445 270)
			(size 0.1397 0.1397)
			(layers "F.Cu" "F.Mask" "F.Paste")
			(net "SSD_ACT_DR4_R")
			(options
				(clearance outline)
				(anchor circle)
			)
			(primitives
				(gr_poly
					(pts
						(arc
							(start -0.1778 -0.2794)
							(mid -0.249642 -0.249642)
							(end -0.2794 -0.1778)
						)
						(arc
							(start -0.2794 0.1778)
							(mid -0.249642 0.249642)
							(end -0.1778 0.2794)
						)
						(arc
							(start 0.1778 0.2794)
							(mid 0.249642 0.249642)
							(end 0.2794 0.1778)
						)
						(arc
							(start 0.2794 -0.1778)
							(mid 0.249642 -0.249642)
							(end 0.1778 -0.2794)
						)
					)
					(width 0)
					(fill yes)
				)
			)
		)
		(pad "2" smd custom
			(at 0 0.4445 270)
			(size 0.1397 0.1397)
			(layers "F.Cu" "F.Mask" "F.Paste")
			(net "SSD_ACT_DR4")
			(options
				(clearance outline)
				(anchor circle)
			)
			(primitives
				(gr_poly
					(pts
						(arc
							(start -0.1778 -0.2794)
							(mid -0.249642 -0.249642)
							(end -0.2794 -0.1778)
						)
						(arc
							(start -0.2794 0.1778)
							(mid -0.249642 0.249642)
							(end -0.1778 0.2794)
						)
						(arc
							(start 0.1778 0.2794)
							(mid 0.249642 0.249642)
							(end 0.2794 0.1778)
						)
						(arc
							(start 0.2794 -0.1778)
							(mid 0.249642 -0.249642)
							(end 0.1778 -0.2794)
						)
					)
					(width 0)
					(fill yes)
				)
			)
		)
	)
	(footprint ""
		(layer "F.Cu")
		(at 49.061116 -342.007952 90)
		(property "Reference" "R9821"
			(at 0 0 90)
			(layer "F.SilkS")
			(hide yes)
			(effects
				(font
					(size 1.27 1.27)
				)
			)
		)
		(property "Value" "0R2J-2-GP"
			(at 0.064008 -3.993896 90)
			(unlocked yes)
			(layer "F.Fab")
			(hide yes)
			(effects
				(font
					(size 1.016 1.016)
					(thickness 0.1524)
				)
			)
		)
		(property "Device Type" "R402H16"
			(at 0.064008 -5.517896 90)
			(unlocked yes)
			(layer "F.Fab")
			(hide yes)
			(effects
				(font
					(size 1.016 1.016)
					(thickness 0.1524)
				)
			)
		)
		(duplicate_pad_numbers_are_jumpers no)
		(fp_line
			(start 0.508 -0.9398)
			(end -0.508 -0.9398)
			(stroke
				(width 0.1524)
				(type default)
			)
			(layer "F.SilkS")
		)
		(fp_line
			(start -0.508 -0.9398)
			(end -0.508 0.9398)
			(stroke
				(width 0.1524)
				(type default)
			)
			(layer "F.SilkS")
		)
		(fp_rect
			(start -0.508 0.9398)
			(end 0.508 -0.9398)
			(stroke
				(width 0)
				(type default)
			)
			(fill no)
			(layer "F.CrtYd")
		)
		(fp_rect
			(start -0.508 0.9398)
			(end 0.508 -0.9398)
			(stroke
				(width 0)
				(type default)
			)
			(fill no)
			(layer "F.Fab")
		)
		(pad "1" smd custom
			(at 0 -0.4445 90)
			(size 0.1397 0.1397)
			(layers "F.Cu" "F.Mask" "F.Paste")
			(net "ATTN_LED_DR6_AND")
			(options
				(clearance outline)
				(anchor circle)
			)
			(primitives
				(gr_poly
					(pts
						(arc
							(start -0.1778 -0.2794)
							(mid -0.249642 -0.249642)
							(end -0.2794 -0.1778)
						)
						(arc
							(start -0.2794 0.1778)
							(mid -0.249642 0.249642)
							(end -0.1778 0.2794)
						)
						(arc
							(start 0.1778 0.2794)
							(mid 0.249642 0.249642)
							(end 0.2794 0.1778)
						)
						(arc
							(start 0.2794 -0.1778)
							(mid 0.249642 -0.249642)
							(end 0.1778 -0.2794)
						)
					)
					(width 0)
					(fill yes)
				)
			)
		)
		(pad "2" smd custom
			(at 0 0.4445 90)
			(size 0.1397 0.1397)
			(layers "F.Cu" "F.Mask" "F.Paste")
			(net "ATTN_LED_DR6_AND_R")
			(options
				(clearance outline)
				(anchor circle)
			)
			(primitives
				(gr_poly
					(pts
						(arc
							(start -0.1778 -0.2794)
							(mid -0.249642 -0.249642)
							(end -0.2794 -0.1778)
						)
						(arc
							(start -0.2794 0.1778)
							(mid -0.249642 0.249642)
							(end -0.1778 0.2794)
						)
						(arc
							(start 0.1778 0.2794)
							(mid 0.249642 0.249642)
							(end 0.2794 0.1778)
						)
						(arc
							(start 0.2794 -0.1778)
							(mid 0.249642 -0.249642)
							(end 0.1778 -0.2794)
						)
					)
					(width 0)
					(fill yes)
				)
			)
		)
	)
	(footprint ""
		(layer "F.Cu")
		(at 43.50004 -247.10009)
		(property "Reference" "LED7"
			(at 0 0 0)
			(layer "F.SilkS")
			(hide yes)
			(effects
				(font
					(size 1.27 1.27)
				)
			)
		)
		(property "Value" "LED-RB-4-GP"
			(at 5.88899 1.80848 0)
			(unlocked yes)
			(layer "F.Fab")
			(hide yes)
			(effects
				(font
					(size 1.016 1.016)
					(thickness 0.1524)
				)
			)
		)
		(property "Device Type" "LED1613-4PH20"
			(at 5.88899 0.28448 0)
			(unlocked yes)
			(layer "F.Fab")
			(hide yes)
			(effects
				(font
					(size 1.016 1.016)
					(thickness 0.1524)
				)
			)
		)
		(duplicate_pad_numbers_are_jumpers no)
		(fp_line
			(start -1.4478 -0.9652)
			(end 1.4478 -0.9652)
			(stroke
				(width 0.1524)
				(type default)
			)
			(layer "F.SilkS")
		)
		(fp_line
			(start -1.4478 0.9652)
			(end -1.4478 -0.9652)
			(stroke
				(width 0.1524)
				(type default)
			)
			(layer "F.SilkS")
		)
		(fp_line
			(start -1.4478 0.9652)
			(end -1.4478 -0.9652)
			(stroke
				(width 0.508)
				(type default)
			)
			(layer "F.SilkS")
		)
		(fp_line
			(start 1.4478 -0.9652)
			(end 1.4478 0.9652)
			(stroke
				(width 0.1524)
				(type default)
			)
			(layer "F.SilkS")
		)
		(fp_line
			(start 1.4478 0.9652)
			(end -1.4478 0.9652)
			(stroke
				(width 0.1524)
				(type default)
			)
			(layer "F.SilkS")
		)
		(fp_rect
			(start -0.8001 0.6477)
			(end 0.8001 -0.6477)
			(stroke
				(width 0)
				(type default)
			)
			(fill no)
			(layer "F.CrtYd")
		)
		(fp_poly
			(pts
				(xy -1.7018 1.2192) (xy -1.7018 -0.06223) (xy -0.8001 -0.06223) (xy -0.8001 0.6477) (xy 0.8001 0.6477)
				(xy 0.8001 -0.6477) (xy -0.8001 -0.6477) (xy -0.8001 -0.0635) (xy -1.7018 -0.0635) (xy -1.7018 -1.2192)
				(xy 1.7018 -1.2192) (xy 1.7018 1.2192)
			)
			(stroke
				(width 0)
				(type default)
			)
			(fill no)
			(layer "F.CrtYd")
		)
		(fp_rect
			(start -1.7018 1.2192)
			(end 1.7018 -1.2192)
			(stroke
				(width 0)
				(type default)
			)
			(fill no)
			(layer "F.Fab")
		)
		(pad "1" smd rect
			(at -0.73025 0.4064)
			(size 0.9144 0.6096)
			(layers "F.Cu" "F.Mask" "F.Paste")
			(net "SSD_ACT_DR7_MOS_N")
		)
		(pad "2" smd rect
			(at -0.73025 -0.4064)
			(size 0.9144 0.6096)
			(layers "F.Cu" "F.Mask" "F.Paste")
			(net "ATTN_LED_DR7_MOS_N")
		)
		(pad "3" smd rect
			(at 0.73025 -0.4064)
			(size 0.9144 0.6096)
			(layers "F.Cu" "F.Mask" "F.Paste")
			(net "DRV_ATTN_7")
		)
		(pad "4" smd rect
			(at 0.73025 0.4064)
			(size 0.9144 0.6096)
			(layers "F.Cu" "F.Mask" "F.Paste")
			(net "DRV_ACT_7")
		)
	)
	(footprint ""
		(layer "F.Cu")
		(at 220.0402 -86.487)
		(property "Reference" "PC1201"
			(at 0 0 0)
			(layer "F.SilkS")
			(hide yes)
			(effects
				(font
					(size 1.27 1.27)
				)
			)
		)
		(property "Value" "SC22U25V6KX-GP-U"
			(at -2.860802 -5.279644 0)
			(unlocked yes)
			(layer "F.Fab")
			(hide yes)
			(effects
				(font
					(size 1.016 1.016)
					(thickness 0.1524)
				)
			)
		)
		(property "Device Type" "C1206-TO0D3H75"
			(at -2.860802 -6.803644 0)
			(unlocked yes)
			(layer "F.Fab")
			(hide yes)
			(effects
				(font
					(size 1.016 1.016)
					(thickness 0.1524)
				)
			)
		)
		(duplicate_pad_numbers_are_jumpers no)
		(fp_line
			(start -1.3081 -2.3749)
			(end 1.3081 -2.3749)
			(stroke
				(width 0.1524)
				(type default)
			)
			(layer "F.SilkS")
		)
		(fp_line
			(start -1.3081 2.3749)
			(end -1.3081 -2.3749)
			(stroke
				(width 0.1524)
				(type default)
			)
			(layer "F.SilkS")
		)
		(fp_line
			(start 1.3081 -2.3749)
			(end 1.3081 2.3749)
			(stroke
				(width 0.1524)
				(type default)
			)
			(layer "F.SilkS")
		)
		(fp_line
			(start 1.3081 2.3749)
			(end -1.3081 2.3749)
			(stroke
				(width 0.1524)
				(type default)
			)
			(layer "F.SilkS")
		)
		(fp_rect
			(start -0.8001 1.6002)
			(end 0.8001 -1.6002)
			(stroke
				(width 0)
				(type default)
			)
			(fill no)
			(layer "F.CrtYd")
		)
		(fp_poly
			(pts
				(xy -1.5621 2.4511) (xy -1.5621 1.6002) (xy 0.8001 1.6002) (xy 0.8001 -1.6002) (xy -0.8001 -1.6002)
				(xy -0.8001 1.5875) (xy -1.5621 1.5875) (xy -1.5621 -2.4511) (xy 1.5621 -2.4511) (xy 1.5621 2.4511)
			)
			(stroke
				(width 0)
				(type default)
			)
			(fill no)
			(layer "F.CrtYd")
		)
		(fp_rect
			(start -1.5621 2.4511)
			(end 1.5621 -2.4511)
			(stroke
				(width 0)
				(type default)
			)
			(fill no)
			(layer "F.Fab")
		)
		(pad "1" smd rect
			(at 0 -1.392936)
			(size 2.1082 1.4478)
			(layers "F.Cu" "F.Mask" "F.Paste")
			(net "P12V_SSD4")
		)
		(pad "2" smd rect
			(at 0 1.392936)
			(size 2.1082 1.4478)
			(layers "F.Cu" "F.Mask" "F.Paste")
			(net "GND")
		)
	)
	(footprint ""
		(layer "F.Cu")
		(at 232.029 -432.562 -90)
		(property "Reference" "PR9077"
			(at 0 0 270)
			(layer "F.SilkS")
			(hide yes)
			(effects
				(font
					(size 1.27 1.27)
				)
			)
		)
		(property "Value" "10KR2F-2-GP"
			(at 0.064008 -3.993896 270)
			(unlocked yes)
			(layer "F.Fab")
			(hide yes)
			(effects
				(font
					(size 1.016 1.016)
					(thickness 0.1524)
				)
			)
		)
		(property "Device Type" "R402H16"
			(at 0.064008 -5.517896 270)
			(unlocked yes)
			(layer "F.Fab")
			(hide yes)
			(effects
				(font
					(size 1.016 1.016)
					(thickness 0.1524)
				)
			)
		)
		(duplicate_pad_numbers_are_jumpers no)
		(fp_line
			(start -0.508 -0.9398)
			(end -0.508 0.9398)
			(stroke
				(width 0.1524)
				(type default)
			)
			(layer "F.SilkS")
		)
		(fp_line
			(start 0.508 -0.9398)
			(end -0.508 -0.9398)
			(stroke
				(width 0.1524)
				(type default)
			)
			(layer "F.SilkS")
		)
		(fp_rect
			(start -0.508 0.9398)
			(end 0.508 -0.9398)
			(stroke
				(width 0)
				(type default)
			)
			(fill no)
			(layer "F.CrtYd")
		)
		(fp_rect
			(start -0.508 0.9398)
			(end 0.508 -0.9398)
			(stroke
				(width 0)
				(type default)
			)
			(fill no)
			(layer "F.Fab")
		)
		(pad "1" smd custom
			(at 0 -0.4445 270)
			(size 0.1397 0.1397)
			(layers "F.Cu" "F.Mask" "F.Paste")
			(net "AGND_P3V3")
			(options
				(clearance outline)
				(anchor circle)
			)
			(primitives
				(gr_poly
					(pts
						(arc
							(start -0.1778 -0.2794)
							(mid -0.249642 -0.249642)
							(end -0.2794 -0.1778)
						)
						(arc
							(start -0.2794 0.1778)
							(mid -0.249642 0.249642)
							(end -0.1778 0.2794)
						)
						(arc
							(start 0.1778 0.2794)
							(mid 0.249642 0.249642)
							(end 0.2794 0.1778)
						)
						(arc
							(start 0.2794 -0.1778)
							(mid 0.249642 -0.249642)
							(end 0.1778 -0.2794)
						)
					)
					(width 0)
					(fill yes)
				)
			)
		)
		(pad "2" smd custom
			(at 0 0.4445 270)
			(size 0.1397 0.1397)
			(layers "F.Cu" "F.Mask" "F.Paste")
			(net "P3V3_VFB")
			(options
				(clearance outline)
				(anchor circle)
			)
			(primitives
				(gr_poly
					(pts
						(arc
							(start -0.1778 -0.2794)
							(mid -0.249642 -0.249642)
							(end -0.2794 -0.1778)
						)
						(arc
							(start -0.2794 0.1778)
							(mid -0.249642 0.249642)
							(end -0.1778 0.2794)
						)
						(arc
							(start 0.1778 0.2794)
							(mid 0.249642 0.249642)
							(end 0.2794 0.1778)
						)
						(arc
							(start 0.2794 -0.1778)
							(mid 0.249642 -0.249642)
							(end 0.1778 -0.2794)
						)
					)
					(width 0)
					(fill yes)
				)
			)
		)
	)
	(footprint ""
		(layer "F.Cu")
		(at 28.1432 -393.2428 -90)
		(property "Reference" "SR1104"
			(at 0 0 270)
			(layer "F.SilkS")
			(hide yes)
			(effects
				(font
					(size 1.27 1.27)
				)
			)
		)
		(property "Value" "4K7R2F-GP"
			(at 0.064008 -3.993896 270)
			(unlocked yes)
			(layer "F.Fab")
			(hide yes)
			(effects
				(font
					(size 1.016 1.016)
					(thickness 0.1524)
				)
			)
		)
		(property "Device Type" "R402H16"
			(at 0.064008 -5.517896 270)
			(unlocked yes)
			(layer "F.Fab")
			(hide yes)
			(effects
				(font
					(size 1.016 1.016)
					(thickness 0.1524)
				)
			)
		)
		(duplicate_pad_numbers_are_jumpers no)
		(fp_line
			(start -0.508 -0.9398)
			(end -0.508 0.9398)
			(stroke
				(width 0.1524)
				(type default)
			)
			(layer "F.SilkS")
		)
		(fp_line
			(start 0.508 -0.9398)
			(end -0.508 -0.9398)
			(stroke
				(width 0.1524)
				(type default)
			)
			(layer "F.SilkS")
		)
		(fp_rect
			(start -0.508 0.9398)
			(end 0.508 -0.9398)
			(stroke
				(width 0)
				(type default)
			)
			(fill no)
			(layer "F.CrtYd")
		)
		(fp_rect
			(start -0.508 0.9398)
			(end 0.508 -0.9398)
			(stroke
				(width 0)
				(type default)
			)
			(fill no)
			(layer "F.Fab")
		)
		(pad "1" smd custom
			(at 0 -0.4445 270)
			(size 0.1397 0.1397)
			(layers "F.Cu" "F.Mask" "F.Paste")
			(net "DUALPORTEN#6")
			(options
				(clearance outline)
				(anchor circle)
			)
			(primitives
				(gr_poly
					(pts
						(arc
							(start -0.1778 -0.2794)
							(mid -0.249642 -0.249642)
							(end -0.2794 -0.1778)
						)
						(arc
							(start -0.2794 0.1778)
							(mid -0.249642 0.249642)
							(end -0.1778 0.2794)
						)
						(arc
							(start 0.1778 0.2794)
							(mid 0.249642 0.249642)
							(end 0.2794 0.1778)
						)
						(arc
							(start 0.2794 -0.1778)
							(mid 0.249642 -0.249642)
							(end 0.1778 -0.2794)
						)
					)
					(width 0)
					(fill yes)
				)
			)
		)
		(pad "2" smd custom
			(at 0 0.4445 270)
			(size 0.1397 0.1397)
			(layers "F.Cu" "F.Mask" "F.Paste")
			(net "GND")
			(options
				(clearance outline)
				(anchor circle)
			)
			(primitives
				(gr_poly
					(pts
						(arc
							(start -0.1778 -0.2794)
							(mid -0.249642 -0.249642)
							(end -0.2794 -0.1778)
						)
						(arc
							(start -0.2794 0.1778)
							(mid -0.249642 0.249642)
							(end -0.1778 0.2794)
						)
						(arc
							(start 0.1778 0.2794)
							(mid 0.249642 0.249642)
							(end 0.2794 0.1778)
						)
						(arc
							(start 0.2794 -0.1778)
							(mid 0.249642 -0.249642)
							(end 0.1778 -0.2794)
						)
					)
					(width 0)
					(fill yes)
				)
			)
		)
	)
	(footprint ""
		(layer "F.Cu")
		(at 9.2329 -384.0988 180)
		(property "Reference" "C9536"
			(at 0 0 180)
			(layer "F.SilkS")
			(hide yes)
			(effects
				(font
					(size 1.27 1.27)
				)
			)
		)
		(property "Value" "SCD01U50V2KX-1GP"
			(at 1.1811 -2.7051 180)
			(unlocked yes)
			(layer "F.Fab")
			(hide yes)
			(effects
				(font
					(size 1.016 1.016)
					(thickness 0.1524)
				)
			)
		)
		(property "Device Type" "C402H22"
			(at 1.1811 -4.2291 180)
			(unlocked yes)
			(layer "F.Fab")
			(hide yes)
			(effects
				(font
					(size 1.016 1.016)
					(thickness 0.1524)
				)
			)
		)
		(duplicate_pad_numbers_are_jumpers no)
		(fp_rect
			(start -0.4318 0.9525)
			(end 0.4318 -0.9525)
			(stroke
				(width 0)
				(type default)
			)
			(fill no)
			(layer "F.CrtYd")
		)
		(fp_rect
			(start -0.4318 0.9525)
			(end 0.4318 -0.9525)
			(stroke
				(width 0)
				(type default)
			)
			(fill no)
			(layer "F.Fab")
		)
		(pad "1" smd custom
			(at 0 -0.4445 180)
			(size 0.1524 0.1524)
			(layers "F.Cu" "F.Mask" "F.Paste")
			(net "PE_100M_CLK2_P")
			(options
				(clearance outline)
				(anchor circle)
			)
			(primitives
				(gr_poly
					(pts
						(arc
							(start 0.3048 -0.2032)
							(mid 0.275042 -0.275042)
							(end 0.2032 -0.3048)
						)
						(arc
							(start -0.2032 -0.3048)
							(mid -0.275042 -0.275042)
							(end -0.3048 -0.2032)
						)
						(arc
							(start -0.3048 0.2032)
							(mid -0.275042 0.275042)
							(end -0.2032 0.3048)
						)
						(arc
							(start 0.2032 0.3048)
							(mid 0.275042 0.275042)
							(end 0.3048 0.2032)
						)
					)
					(width 0)
					(fill yes)
				)
			)
		)
		(pad "2" smd custom
			(at 0 0.4445 180)
			(size 0.1524 0.1524)
			(layers "F.Cu" "F.Mask" "F.Paste")
			(net "PE_100M_CLK2_C_P")
			(options
				(clearance outline)
				(anchor circle)
			)
			(primitives
				(gr_poly
					(pts
						(arc
							(start 0.3048 -0.2032)
							(mid 0.275042 -0.275042)
							(end 0.2032 -0.3048)
						)
						(arc
							(start -0.2032 -0.3048)
							(mid -0.275042 -0.275042)
							(end -0.3048 -0.2032)
						)
						(arc
							(start -0.3048 0.2032)
							(mid -0.275042 0.275042)
							(end -0.2032 0.3048)
						)
						(arc
							(start 0.2032 0.3048)
							(mid 0.275042 0.275042)
							(end 0.3048 0.2032)
						)
					)
					(width 0)
					(fill yes)
				)
			)
		)
	)
	(footprint ""
		(layer "F.Cu")
		(at 215.9 -197.9676 -90)
		(property "Reference" "Q41"
			(at 0 0 270)
			(layer "F.SilkS")
			(hide yes)
			(effects
				(font
					(size 1.27 1.27)
				)
			)
		)
		(property "Value" "2N7002A-7-GP"
			(at 0.127 -8.9662 270)
			(unlocked yes)
			(layer "F.Fab")
			(hide yes)
			(effects
				(font
					(size 1.016 1.016)
					(thickness 0.1524)
				)
			)
		)
		(property "Device Type" "SOT23DGS2D4H48"
			(at 0.127 -10.4902 270)
			(unlocked yes)
			(layer "F.Fab")
			(hide yes)
			(effects
				(font
					(size 1.016 1.016)
					(thickness 0.1524)
				)
			)
		)
		(duplicate_pad_numbers_are_jumpers no)
		(fp_line
			(start -1.651 1.778)
			(end 1.651 1.778)
			(stroke
				(width 0.1524)
				(type default)
			)
			(layer "F.SilkS")
		)
		(fp_line
			(start 1.651 1.778)
			(end 1.651 -1.778)
			(stroke
				(width 0.1524)
				(type default)
			)
			(layer "F.SilkS")
		)
		(fp_line
			(start -1.651 -1.778)
			(end -1.651 1.778)
			(stroke
				(width 0.1524)
				(type default)
			)
			(layer "F.SilkS")
		)
		(fp_line
			(start 1.651 -1.778)
			(end -1.651 -1.778)
			(stroke
				(width 0.1524)
				(type default)
			)
			(layer "F.SilkS")
		)
		(fp_poly
			(pts
				(xy -1.778 1.8796) (xy -1.778 -1.8796) (xy 1.778 -1.8796) (xy 1.778 1.8796)
			)
			(stroke
				(width 0)
				(type default)
			)
			(fill no)
			(layer "F.CrtYd")
		)
		(fp_poly
			(pts
				(xy -1.778 1.8796) (xy -1.778 -1.8796) (xy 1.778 -1.8796) (xy 1.778 1.8796)
			)
			(stroke
				(width 0)
				(type default)
			)
			(fill no)
			(layer "F.Fab")
		)
		(pad "D" smd custom
			(at 0 -0.9525 270)
			(size 0.1905 0.1905)
			(layers "F.Cu" "F.Mask" "F.Paste")
			(net "P12V_MOST3_GATE_D")
			(options
				(clearance outline)
				(anchor circle)
			)
			(primitives
				(gr_poly
					(pts
						(arc
							(start -0.1778 0.5715)
							(mid -0.321484 0.511984)
							(end -0.381 0.3683)
						)
						(arc
							(start -0.381 -0.3683)
							(mid -0.321484 -0.511984)
							(end -0.1778 -0.5715)
						)
						(arc
							(start 0.1778 -0.5715)
							(mid 0.321484 -0.511984)
							(end 0.381 -0.3683)
						)
						(arc
							(start 0.381 0.3683)
							(mid 0.321484 0.511984)
							(end 0.1778 0.5715)
						)
					)
					(width 0)
					(fill yes)
				)
			)
		)
		(pad "G" smd custom
			(at -0.98425 0.9525 270)
			(size 0.1905 0.1905)
			(layers "F.Cu" "F.Mask" "F.Paste")
			(net "P12V_MOST3_GATE")
			(options
				(clearance outline)
				(anchor circle)
			)
			(primitives
				(gr_poly
					(pts
						(arc
							(start -0.1778 0.5715)
							(mid -0.321484 0.511984)
							(end -0.381 0.3683)
						)
						(arc
							(start -0.381 -0.3683)
							(mid -0.321484 -0.511984)
							(end -0.1778 -0.5715)
						)
						(arc
							(start 0.1778 -0.5715)
							(mid 0.321484 -0.511984)
							(end 0.381 -0.3683)
						)
						(arc
							(start 0.381 0.3683)
							(mid 0.321484 0.511984)
							(end 0.1778 0.5715)
						)
					)
					(width 0)
					(fill yes)
				)
			)
		)
		(pad "S" smd custom
			(at 0.98425 0.9525 270)
			(size 0.1905 0.1905)
			(layers "F.Cu" "F.Mask" "F.Paste")
			(net "GND")
			(options
				(clearance outline)
				(anchor circle)
			)
			(primitives
				(gr_poly
					(pts
						(arc
							(start -0.1778 0.5715)
							(mid -0.321484 0.511984)
							(end -0.381 0.3683)
						)
						(arc
							(start -0.381 -0.3683)
							(mid -0.321484 -0.511984)
							(end -0.1778 -0.5715)
						)
						(arc
							(start 0.1778 -0.5715)
							(mid 0.321484 -0.511984)
							(end 0.381 -0.3683)
						)
						(arc
							(start 0.381 0.3683)
							(mid 0.321484 0.511984)
							(end 0.1778 0.5715)
						)
					)
					(width 0)
					(fill yes)
				)
			)
		)
	)
	(footprint ""
		(layer "F.Cu")
		(at 30.8864 -12.5984 180)
		(property "Reference" "SR1120"
			(at 0 0 180)
			(layer "F.SilkS")
			(hide yes)
			(effects
				(font
					(size 1.27 1.27)
				)
			)
		)
		(property "Value" "4K7R2F-GP"
			(at 0.064008 -3.993896 180)
			(unlocked yes)
			(layer "F.Fab")
			(hide yes)
			(effects
				(font
					(size 1.016 1.016)
					(thickness 0.1524)
				)
			)
		)
		(property "Device Type" "R402H16"
			(at 0.064008 -5.517896 180)
			(unlocked yes)
			(layer "F.Fab")
			(hide yes)
			(effects
				(font
					(size 1.016 1.016)
					(thickness 0.1524)
				)
			)
		)
		(duplicate_pad_numbers_are_jumpers no)
		(fp_line
			(start 0.508 -0.9398)
			(end -0.508 -0.9398)
			(stroke
				(width 0.1524)
				(type default)
			)
			(layer "F.SilkS")
		)
		(fp_line
			(start -0.508 -0.9398)
			(end -0.508 0.9398)
			(stroke
				(width 0.1524)
				(type default)
			)
			(layer "F.SilkS")
		)
		(fp_rect
			(start -0.508 0.9398)
			(end 0.508 -0.9398)
			(stroke
				(width 0)
				(type default)
			)
			(fill no)
			(layer "F.CrtYd")
		)
		(fp_rect
			(start -0.508 0.9398)
			(end 0.508 -0.9398)
			(stroke
				(width 0)
				(type default)
			)
			(fill no)
			(layer "F.Fab")
		)
		(pad "1" smd custom
			(at 0 -0.4445 180)
			(size 0.1397 0.1397)
			(layers "F.Cu" "F.Mask" "F.Paste")
			(net "DUALPORTEN#14")
			(options
				(clearance outline)
				(anchor circle)
			)
			(primitives
				(gr_poly
					(pts
						(arc
							(start -0.1778 -0.2794)
							(mid -0.249642 -0.249642)
							(end -0.2794 -0.1778)
						)
						(arc
							(start -0.2794 0.1778)
							(mid -0.249642 0.249642)
							(end -0.1778 0.2794)
						)
						(arc
							(start 0.1778 0.2794)
							(mid 0.249642 0.249642)
							(end 0.2794 0.1778)
						)
						(arc
							(start 0.2794 -0.1778)
							(mid 0.249642 -0.249642)
							(end 0.1778 -0.2794)
						)
					)
					(width 0)
					(fill yes)
				)
			)
		)
		(pad "2" smd custom
			(at 0 0.4445 180)
			(size 0.1397 0.1397)
			(layers "F.Cu" "F.Mask" "F.Paste")
			(net "GND")
			(options
				(clearance outline)
				(anchor circle)
			)
			(primitives
				(gr_poly
					(pts
						(arc
							(start -0.1778 -0.2794)
							(mid -0.249642 -0.249642)
							(end -0.2794 -0.1778)
						)
						(arc
							(start -0.2794 0.1778)
							(mid -0.249642 0.249642)
							(end -0.1778 0.2794)
						)
						(arc
							(start 0.1778 0.2794)
							(mid 0.249642 0.249642)
							(end 0.2794 0.1778)
						)
						(arc
							(start 0.2794 -0.1778)
							(mid 0.249642 -0.249642)
							(end 0.1778 -0.2794)
						)
					)
					(width 0)
					(fill yes)
				)
			)
		)
	)
	(footprint ""
		(layer "F.Cu")
		(at 224.623122 -427.609 -90)
		(property "Reference" "PC1284"
			(at 0 0 270)
			(layer "F.SilkS")
			(hide yes)
			(effects
				(font
					(size 1.27 1.27)
				)
			)
		)
		(property "Value" "SC22U25V6KX-GP-U"
			(at -2.860802 -5.279644 270)
			(unlocked yes)
			(layer "F.Fab")
			(hide yes)
			(effects
				(font
					(size 1.016 1.016)
					(thickness 0.1524)
				)
			)
		)
		(property "Device Type" "C1206-TO0D3H75"
			(at -2.860802 -6.803644 270)
			(unlocked yes)
			(layer "F.Fab")
			(hide yes)
			(effects
				(font
					(size 1.016 1.016)
					(thickness 0.1524)
				)
			)
		)
		(duplicate_pad_numbers_are_jumpers no)
		(fp_line
			(start -1.3081 2.3749)
			(end -1.3081 -2.3749)
			(stroke
				(width 0.1524)
				(type default)
			)
			(layer "F.SilkS")
		)
		(fp_line
			(start 1.3081 2.3749)
			(end -1.3081 2.3749)
			(stroke
				(width 0.1524)
				(type default)
			)
			(layer "F.SilkS")
		)
		(fp_line
			(start -1.3081 -2.3749)
			(end 1.3081 -2.3749)
			(stroke
				(width 0.1524)
				(type default)
			)
			(layer "F.SilkS")
		)
		(fp_line
			(start 1.3081 -2.3749)
			(end 1.3081 2.3749)
			(stroke
				(width 0.1524)
				(type default)
			)
			(layer "F.SilkS")
		)
		(fp_rect
			(start -0.8001 1.6002)
			(end 0.8001 -1.6002)
			(stroke
				(width 0)
				(type default)
			)
			(fill no)
			(layer "F.CrtYd")
		)
		(fp_poly
			(pts
				(xy -1.5621 2.4511) (xy -1.5621 1.6002) (xy 0.8001 1.6002) (xy 0.8001 -1.6002) (xy -0.8001 -1.6002)
				(xy -0.8001 1.5875) (xy -1.5621 1.5875) (xy -1.5621 -2.4511) (xy 1.5621 -2.4511) (xy 1.5621 2.4511)
			)
			(stroke
				(width 0)
				(type default)
			)
			(fill no)
			(layer "F.CrtYd")
		)
		(fp_rect
			(start -1.5621 2.4511)
			(end 1.5621 -2.4511)
			(stroke
				(width 0)
				(type default)
			)
			(fill no)
			(layer "F.Fab")
		)
		(pad "1" smd rect
			(at 0 -1.392936 270)
			(size 2.1082 1.4478)
			(layers "F.Cu" "F.Mask" "F.Paste")
			(net "P3V3_VIN")
		)
		(pad "2" smd rect
			(at 0 1.392936 270)
			(size 2.1082 1.4478)
			(layers "F.Cu" "F.Mask" "F.Paste")
			(net "GND")
		)
	)
	(footprint ""
		(layer "F.Cu")
		(at 88.011 -89.535 90)
		(property "Reference" "C9337"
			(at 0 0 90)
			(layer "F.SilkS")
			(hide yes)
			(effects
				(font
					(size 1.27 1.27)
				)
			)
		)
		(property "Value" "SC1KP50V2KX-1GP"
			(at 1.1811 -2.7051 90)
			(unlocked yes)
			(layer "F.Fab")
			(hide yes)
			(effects
				(font
					(size 1.016 1.016)
					(thickness 0.1524)
				)
			)
		)
		(property "Device Type" "C402H22"
			(at 1.1811 -4.2291 90)
			(unlocked yes)
			(layer "F.Fab")
			(hide yes)
			(effects
				(font
					(size 1.016 1.016)
					(thickness 0.1524)
				)
			)
		)
		(duplicate_pad_numbers_are_jumpers no)
		(fp_rect
			(start -0.4318 0.9525)
			(end 0.4318 -0.9525)
			(stroke
				(width 0)
				(type default)
			)
			(fill no)
			(layer "F.CrtYd")
		)
		(fp_rect
			(start -0.4318 0.9525)
			(end 0.4318 -0.9525)
			(stroke
				(width 0)
				(type default)
			)
			(fill no)
			(layer "F.Fab")
		)
		(pad "1" smd custom
			(at 0 -0.4445 90)
			(size 0.1524 0.1524)
			(layers "F.Cu" "F.Mask" "F.Paste")
			(net "SSD_PRSNT9")
			(options
				(clearance outline)
				(anchor circle)
			)
			(primitives
				(gr_poly
					(pts
						(arc
							(start 0.3048 -0.2032)
							(mid 0.275042 -0.275042)
							(end 0.2032 -0.3048)
						)
						(arc
							(start -0.2032 -0.3048)
							(mid -0.275042 -0.275042)
							(end -0.3048 -0.2032)
						)
						(arc
							(start -0.3048 0.2032)
							(mid -0.275042 0.275042)
							(end -0.2032 0.3048)
						)
						(arc
							(start 0.2032 0.3048)
							(mid 0.275042 0.275042)
							(end 0.3048 0.2032)
						)
					)
					(width 0)
					(fill yes)
				)
			)
		)
		(pad "2" smd custom
			(at 0 0.4445 90)
			(size 0.1524 0.1524)
			(layers "F.Cu" "F.Mask" "F.Paste")
			(net "GND")
			(options
				(clearance outline)
				(anchor circle)
			)
			(primitives
				(gr_poly
					(pts
						(arc
							(start 0.3048 -0.2032)
							(mid 0.275042 -0.275042)
							(end 0.2032 -0.3048)
						)
						(arc
							(start -0.2032 -0.3048)
							(mid -0.275042 -0.275042)
							(end -0.3048 -0.2032)
						)
						(arc
							(start -0.3048 0.2032)
							(mid -0.275042 0.275042)
							(end -0.2032 0.3048)
						)
						(arc
							(start 0.2032 0.3048)
							(mid 0.275042 0.275042)
							(end 0.3048 0.2032)
						)
					)
					(width 0)
					(fill yes)
				)
			)
		)
	)
	(footprint ""
		(layer "F.Cu")
		(at 217.4494 -187.579 180)
		(property "Reference" "SR1098"
			(at 0 0 180)
			(layer "F.SilkS")
			(hide yes)
			(effects
				(font
					(size 1.27 1.27)
				)
			)
		)
		(property "Value" "4K7R2F-GP"
			(at 0.064008 -3.993896 180)
			(unlocked yes)
			(layer "F.Fab")
			(hide yes)
			(effects
				(font
					(size 1.016 1.016)
					(thickness 0.1524)
				)
			)
		)
		(property "Device Type" "R402H16"
			(at 0.064008 -5.517896 180)
			(unlocked yes)
			(layer "F.Fab")
			(hide yes)
			(effects
				(font
					(size 1.016 1.016)
					(thickness 0.1524)
				)
			)
		)
		(duplicate_pad_numbers_are_jumpers no)
		(fp_line
			(start 0.508 -0.9398)
			(end -0.508 -0.9398)
			(stroke
				(width 0.1524)
				(type default)
			)
			(layer "F.SilkS")
		)
		(fp_line
			(start -0.508 -0.9398)
			(end -0.508 0.9398)
			(stroke
				(width 0.1524)
				(type default)
			)
			(layer "F.SilkS")
		)
		(fp_rect
			(start -0.508 0.9398)
			(end 0.508 -0.9398)
			(stroke
				(width 0)
				(type default)
			)
			(fill no)
			(layer "F.CrtYd")
		)
		(fp_rect
			(start -0.508 0.9398)
			(end 0.508 -0.9398)
			(stroke
				(width 0)
				(type default)
			)
			(fill no)
			(layer "F.Fab")
		)
		(pad "1" smd custom
			(at 0 -0.4445 180)
			(size 0.1397 0.1397)
			(layers "F.Cu" "F.Mask" "F.Paste")
			(net "DUALPORTEN#3")
			(options
				(clearance outline)
				(anchor circle)
			)
			(primitives
				(gr_poly
					(pts
						(arc
							(start -0.1778 -0.2794)
							(mid -0.249642 -0.249642)
							(end -0.2794 -0.1778)
						)
						(arc
							(start -0.2794 0.1778)
							(mid -0.249642 0.249642)
							(end -0.1778 0.2794)
						)
						(arc
							(start 0.1778 0.2794)
							(mid 0.249642 0.249642)
							(end 0.2794 0.1778)
						)
						(arc
							(start 0.2794 -0.1778)
							(mid 0.249642 -0.249642)
							(end 0.1778 -0.2794)
						)
					)
					(width 0)
					(fill yes)
				)
			)
		)
		(pad "2" smd custom
			(at 0 0.4445 180)
			(size 0.1397 0.1397)
			(layers "F.Cu" "F.Mask" "F.Paste")
			(net "GND")
			(options
				(clearance outline)
				(anchor circle)
			)
			(primitives
				(gr_poly
					(pts
						(arc
							(start -0.1778 -0.2794)
							(mid -0.249642 -0.249642)
							(end -0.2794 -0.1778)
						)
						(arc
							(start -0.2794 0.1778)
							(mid -0.249642 0.249642)
							(end -0.1778 0.2794)
						)
						(arc
							(start 0.1778 0.2794)
							(mid 0.249642 0.249642)
							(end 0.2794 0.1778)
						)
						(arc
							(start 0.2794 -0.1778)
							(mid 0.249642 -0.249642)
							(end 0.1778 -0.2794)
						)
					)
					(width 0)
					(fill yes)
				)
			)
		)
	)
	(footprint ""
		(layer "F.Cu")
		(at 43.50004 -350.099884)
		(property "Reference" "LED6"
			(at 0 0 0)
			(layer "F.SilkS")
			(hide yes)
			(effects
				(font
					(size 1.27 1.27)
				)
			)
		)
		(property "Value" "LED-RB-4-GP"
			(at 5.88899 1.80848 0)
			(unlocked yes)
			(layer "F.Fab")
			(hide yes)
			(effects
				(font
					(size 1.016 1.016)
					(thickness 0.1524)
				)
			)
		)
		(property "Device Type" "LED1613-4PH20"
			(at 5.88899 0.28448 0)
			(unlocked yes)
			(layer "F.Fab")
			(hide yes)
			(effects
				(font
					(size 1.016 1.016)
					(thickness 0.1524)
				)
			)
		)
		(duplicate_pad_numbers_are_jumpers no)
		(fp_line
			(start -1.4478 -0.9652)
			(end 1.4478 -0.9652)
			(stroke
				(width 0.1524)
				(type default)
			)
			(layer "F.SilkS")
		)
		(fp_line
			(start -1.4478 0.9652)
			(end -1.4478 -0.9652)
			(stroke
				(width 0.1524)
				(type default)
			)
			(layer "F.SilkS")
		)
		(fp_line
			(start -1.4478 0.9652)
			(end -1.4478 -0.9652)
			(stroke
				(width 0.508)
				(type default)
			)
			(layer "F.SilkS")
		)
		(fp_line
			(start 1.4478 -0.9652)
			(end 1.4478 0.9652)
			(stroke
				(width 0.1524)
				(type default)
			)
			(layer "F.SilkS")
		)
		(fp_line
			(start 1.4478 0.9652)
			(end -1.4478 0.9652)
			(stroke
				(width 0.1524)
				(type default)
			)
			(layer "F.SilkS")
		)
		(fp_rect
			(start -0.8001 0.6477)
			(end 0.8001 -0.6477)
			(stroke
				(width 0)
				(type default)
			)
			(fill no)
			(layer "F.CrtYd")
		)
		(fp_poly
			(pts
				(xy -1.7018 1.2192) (xy -1.7018 -0.06223) (xy -0.8001 -0.06223) (xy -0.8001 0.6477) (xy 0.8001 0.6477)
				(xy 0.8001 -0.6477) (xy -0.8001 -0.6477) (xy -0.8001 -0.0635) (xy -1.7018 -0.0635) (xy -1.7018 -1.2192)
				(xy 1.7018 -1.2192) (xy 1.7018 1.2192)
			)
			(stroke
				(width 0)
				(type default)
			)
			(fill no)
			(layer "F.CrtYd")
		)
		(fp_rect
			(start -1.7018 1.2192)
			(end 1.7018 -1.2192)
			(stroke
				(width 0)
				(type default)
			)
			(fill no)
			(layer "F.Fab")
		)
		(pad "1" smd rect
			(at -0.73025 0.4064)
			(size 0.9144 0.6096)
			(layers "F.Cu" "F.Mask" "F.Paste")
			(net "SSD_ACT_DR6_MOS_N")
		)
		(pad "2" smd rect
			(at -0.73025 -0.4064)
			(size 0.9144 0.6096)
			(layers "F.Cu" "F.Mask" "F.Paste")
			(net "ATTN_LED_DR6_MOS_N")
		)
		(pad "3" smd rect
			(at 0.73025 -0.4064)
			(size 0.9144 0.6096)
			(layers "F.Cu" "F.Mask" "F.Paste")
			(net "DRV_ATTN_6")
		)
		(pad "4" smd rect
			(at 0.73025 0.4064)
			(size 0.9144 0.6096)
			(layers "F.Cu" "F.Mask" "F.Paste")
			(net "DRV_ACT_6")
		)
	)
	(footprint ""
		(layer "F.Cu")
		(at 33.1089 -205.4479)
		(property "Reference" "R9860"
			(at 0 0 0)
			(layer "F.SilkS")
			(hide yes)
			(effects
				(font
					(size 1.27 1.27)
				)
			)
		)
		(property "Value" "47KR2J-2-GP"
			(at 0.064008 -3.993896 0)
			(unlocked yes)
			(layer "F.Fab")
			(hide yes)
			(effects
				(font
					(size 1.016 1.016)
					(thickness 0.1524)
				)
			)
		)
		(property "Device Type" "R402H16"
			(at 0.064008 -5.517896 0)
			(unlocked yes)
			(layer "F.Fab")
			(hide yes)
			(effects
				(font
					(size 1.016 1.016)
					(thickness 0.1524)
				)
			)
		)
		(duplicate_pad_numbers_are_jumpers no)
		(fp_line
			(start -0.508 -0.9398)
			(end -0.508 0.9398)
			(stroke
				(width 0.1524)
				(type default)
			)
			(layer "F.SilkS")
		)
		(fp_line
			(start 0.508 -0.9398)
			(end -0.508 -0.9398)
			(stroke
				(width 0.1524)
				(type default)
			)
			(layer "F.SilkS")
		)
		(fp_rect
			(start -0.508 0.9398)
			(end 0.508 -0.9398)
			(stroke
				(width 0)
				(type default)
			)
			(fill no)
			(layer "F.CrtYd")
		)
		(fp_rect
			(start -0.508 0.9398)
			(end 0.508 -0.9398)
			(stroke
				(width 0)
				(type default)
			)
			(fill no)
			(layer "F.Fab")
		)
		(pad "1" smd custom
			(at 0 -0.4445)
			(size 0.1397 0.1397)
			(layers "F.Cu" "F.Mask" "F.Paste")
			(net "P12V")
			(options
				(clearance outline)
				(anchor circle)
			)
			(primitives
				(gr_poly
					(pts
						(arc
							(start -0.1778 -0.2794)
							(mid -0.249642 -0.249642)
							(end -0.2794 -0.1778)
						)
						(arc
							(start -0.2794 0.1778)
							(mid -0.249642 0.249642)
							(end -0.1778 0.2794)
						)
						(arc
							(start 0.1778 0.2794)
							(mid 0.249642 0.249642)
							(end 0.2794 0.1778)
						)
						(arc
							(start 0.2794 -0.1778)
							(mid 0.249642 -0.249642)
							(end 0.1778 -0.2794)
						)
					)
					(width 0)
					(fill yes)
				)
			)
		)
		(pad "2" smd custom
			(at 0 0.4445)
			(size 0.1397 0.1397)
			(layers "F.Cu" "F.Mask" "F.Paste")
			(net "P12V_MOST12_GATE")
			(options
				(clearance outline)
				(anchor circle)
			)
			(primitives
				(gr_poly
					(pts
						(arc
							(start -0.1778 -0.2794)
							(mid -0.249642 -0.249642)
							(end -0.2794 -0.1778)
						)
						(arc
							(start -0.2794 0.1778)
							(mid -0.249642 0.249642)
							(end -0.1778 0.2794)
						)
						(arc
							(start 0.1778 0.2794)
							(mid 0.249642 0.249642)
							(end 0.2794 0.1778)
						)
						(arc
							(start 0.2794 -0.1778)
							(mid 0.249642 -0.249642)
							(end 0.1778 -0.2794)
						)
					)
					(width 0)
					(fill yes)
				)
			)
		)
	)
	(footprint ""
		(layer "F.Cu")
		(at 234.061 -451.485 -90)
		(property "Reference" "R9892"
			(at 0 0 270)
			(layer "F.SilkS")
			(hide yes)
			(effects
				(font
					(size 1.27 1.27)
				)
			)
		)
		(property "Value" "1K82R2F-1-GP"
			(at 0.064008 -3.993896 270)
			(unlocked yes)
			(layer "F.Fab")
			(hide yes)
			(effects
				(font
					(size 1.016 1.016)
					(thickness 0.1524)
				)
			)
		)
		(property "Device Type" "R402H16"
			(at 0.064008 -5.517896 270)
			(unlocked yes)
			(layer "F.Fab")
			(hide yes)
			(effects
				(font
					(size 1.016 1.016)
					(thickness 0.1524)
				)
			)
		)
		(duplicate_pad_numbers_are_jumpers no)
		(fp_line
			(start -0.508 -0.9398)
			(end -0.508 0.9398)
			(stroke
				(width 0.1524)
				(type default)
			)
			(layer "F.SilkS")
		)
		(fp_line
			(start 0.508 -0.9398)
			(end -0.508 -0.9398)
			(stroke
				(width 0.1524)
				(type default)
			)
			(layer "F.SilkS")
		)
		(fp_rect
			(start -0.508 0.9398)
			(end 0.508 -0.9398)
			(stroke
				(width 0)
				(type default)
			)
			(fill no)
			(layer "F.CrtYd")
		)
		(fp_rect
			(start -0.508 0.9398)
			(end 0.508 -0.9398)
			(stroke
				(width 0)
				(type default)
			)
			(fill no)
			(layer "F.Fab")
		)
		(pad "1" smd custom
			(at 0 -0.4445 270)
			(size 0.1397 0.1397)
			(layers "F.Cu" "F.Mask" "F.Paste")
			(net "P12V")
			(options
				(clearance outline)
				(anchor circle)
			)
			(primitives
				(gr_poly
					(pts
						(arc
							(start -0.1778 -0.2794)
							(mid -0.249642 -0.249642)
							(end -0.2794 -0.1778)
						)
						(arc
							(start -0.2794 0.1778)
							(mid -0.249642 0.249642)
							(end -0.1778 0.2794)
						)
						(arc
							(start 0.1778 0.2794)
							(mid 0.249642 0.249642)
							(end 0.2794 0.1778)
						)
						(arc
							(start 0.2794 -0.1778)
							(mid 0.249642 -0.249642)
							(end 0.1778 -0.2794)
						)
					)
					(width 0)
					(fill yes)
				)
			)
		)
		(pad "2" smd custom
			(at 0 0.4445 270)
			(size 0.1397 0.1397)
			(layers "F.Cu" "F.Mask" "F.Paste")
			(net "DRV_ACT_0")
			(options
				(clearance outline)
				(anchor circle)
			)
			(primitives
				(gr_poly
					(pts
						(arc
							(start -0.1778 -0.2794)
							(mid -0.249642 -0.249642)
							(end -0.2794 -0.1778)
						)
						(arc
							(start -0.2794 0.1778)
							(mid -0.249642 0.249642)
							(end -0.1778 0.2794)
						)
						(arc
							(start 0.1778 0.2794)
							(mid 0.249642 0.249642)
							(end 0.2794 0.1778)
						)
						(arc
							(start 0.2794 -0.1778)
							(mid 0.249642 -0.249642)
							(end 0.1778 -0.2794)
						)
					)
					(width 0)
					(fill yes)
				)
			)
		)
	)
	(footprint ""
		(layer "F.Cu")
		(at 29.3878 -10.6172 180)
		(property "Reference" "PC1233"
			(at 0 0 180)
			(layer "F.SilkS")
			(hide yes)
			(effects
				(font
					(size 1.27 1.27)
				)
			)
		)
		(property "Value" "SCD01U50V2KX-1GP"
			(at 1.1811 -2.7051 180)
			(unlocked yes)
			(layer "F.Fab")
			(hide yes)
			(effects
				(font
					(size 1.016 1.016)
					(thickness 0.1524)
				)
			)
		)
		(property "Device Type" "C402H22"
			(at 1.1811 -4.2291 180)
			(unlocked yes)
			(layer "F.Fab")
			(hide yes)
			(effects
				(font
					(size 1.016 1.016)
					(thickness 0.1524)
				)
			)
		)
		(duplicate_pad_numbers_are_jumpers no)
		(fp_rect
			(start -0.4318 0.9525)
			(end 0.4318 -0.9525)
			(stroke
				(width 0)
				(type default)
			)
			(fill no)
			(layer "F.CrtYd")
		)
		(fp_rect
			(start -0.4318 0.9525)
			(end 0.4318 -0.9525)
			(stroke
				(width 0)
				(type default)
			)
			(fill no)
			(layer "F.Fab")
		)
		(pad "1" smd custom
			(at 0 -0.4445 180)
			(size 0.1524 0.1524)
			(layers "F.Cu" "F.Mask" "F.Paste")
			(net "P12V_SSD14")
			(options
				(clearance outline)
				(anchor circle)
			)
			(primitives
				(gr_poly
					(pts
						(arc
							(start 0.3048 -0.2032)
							(mid 0.275042 -0.275042)
							(end 0.2032 -0.3048)
						)
						(arc
							(start -0.2032 -0.3048)
							(mid -0.275042 -0.275042)
							(end -0.3048 -0.2032)
						)
						(arc
							(start -0.3048 0.2032)
							(mid -0.275042 0.275042)
							(end -0.2032 0.3048)
						)
						(arc
							(start 0.2032 0.3048)
							(mid 0.275042 0.275042)
							(end 0.3048 0.2032)
						)
					)
					(width 0)
					(fill yes)
				)
			)
		)
		(pad "2" smd custom
			(at 0 0.4445 180)
			(size 0.1524 0.1524)
			(layers "F.Cu" "F.Mask" "F.Paste")
			(net "GND")
			(options
				(clearance outline)
				(anchor circle)
			)
			(primitives
				(gr_poly
					(pts
						(arc
							(start 0.3048 -0.2032)
							(mid 0.275042 -0.275042)
							(end 0.2032 -0.3048)
						)
						(arc
							(start -0.2032 -0.3048)
							(mid -0.275042 -0.275042)
							(end -0.3048 -0.2032)
						)
						(arc
							(start -0.3048 0.2032)
							(mid -0.275042 0.275042)
							(end -0.2032 0.3048)
						)
						(arc
							(start 0.2032 0.3048)
							(mid 0.275042 0.275042)
							(end 0.3048 0.2032)
						)
					)
					(width 0)
					(fill yes)
				)
			)
		)
	)
	(footprint ""
		(layer "F.Cu")
		(at 37.87775 -102.64775 180)
		(property "Reference" "R9773"
			(at 0 0 180)
			(layer "F.SilkS")
			(hide yes)
			(effects
				(font
					(size 1.27 1.27)
				)
			)
		)
		(property "Value" "4K7R2J-2-GP"
			(at 0.064008 -3.993896 180)
			(unlocked yes)
			(layer "F.Fab")
			(hide yes)
			(effects
				(font
					(size 1.016 1.016)
					(thickness 0.1524)
				)
			)
		)
		(property "Device Type" "R402H16"
			(at 0.064008 -5.517896 180)
			(unlocked yes)
			(layer "F.Fab")
			(hide yes)
			(effects
				(font
					(size 1.016 1.016)
					(thickness 0.1524)
				)
			)
		)
		(duplicate_pad_numbers_are_jumpers no)
		(fp_line
			(start 0.508 -0.9398)
			(end -0.508 -0.9398)
			(stroke
				(width 0.1524)
				(type default)
			)
			(layer "F.SilkS")
		)
		(fp_line
			(start -0.508 -0.9398)
			(end -0.508 0.9398)
			(stroke
				(width 0.1524)
				(type default)
			)
			(layer "F.SilkS")
		)
		(fp_rect
			(start -0.508 0.9398)
			(end 0.508 -0.9398)
			(stroke
				(width 0)
				(type default)
			)
			(fill no)
			(layer "F.CrtYd")
		)
		(fp_rect
			(start -0.508 0.9398)
			(end 0.508 -0.9398)
			(stroke
				(width 0)
				(type default)
			)
			(fill no)
			(layer "F.Fab")
		)
		(pad "1" smd custom
			(at 0 -0.4445 180)
			(size 0.1397 0.1397)
			(layers "F.Cu" "F.Mask" "F.Paste")
			(net "SSD13_PWREN")
			(options
				(clearance outline)
				(anchor circle)
			)
			(primitives
				(gr_poly
					(pts
						(arc
							(start -0.1778 -0.2794)
							(mid -0.249642 -0.249642)
							(end -0.2794 -0.1778)
						)
						(arc
							(start -0.2794 0.1778)
							(mid -0.249642 0.249642)
							(end -0.1778 0.2794)
						)
						(arc
							(start 0.1778 0.2794)
							(mid 0.249642 0.249642)
							(end 0.2794 0.1778)
						)
						(arc
							(start 0.2794 -0.1778)
							(mid 0.249642 -0.249642)
							(end 0.1778 -0.2794)
						)
					)
					(width 0)
					(fill yes)
				)
			)
		)
		(pad "2" smd custom
			(at 0 0.4445 180)
			(size 0.1397 0.1397)
			(layers "F.Cu" "F.Mask" "F.Paste")
			(net "GND")
			(options
				(clearance outline)
				(anchor circle)
			)
			(primitives
				(gr_poly
					(pts
						(arc
							(start -0.1778 -0.2794)
							(mid -0.249642 -0.249642)
							(end -0.2794 -0.1778)
						)
						(arc
							(start -0.2794 0.1778)
							(mid -0.249642 0.249642)
							(end -0.1778 0.2794)
						)
						(arc
							(start 0.1778 0.2794)
							(mid 0.249642 0.249642)
							(end 0.2794 0.1778)
						)
						(arc
							(start 0.2794 -0.1778)
							(mid 0.249642 -0.249642)
							(end 0.1778 -0.2794)
						)
					)
					(width 0)
					(fill yes)
				)
			)
		)
	)
	(footprint ""
		(layer "F.Cu")
		(at 73.025 -454.66 180)
		(property "Reference" "R348"
			(at 0 0 180)
			(layer "F.SilkS")
			(hide yes)
			(effects
				(font
					(size 1.27 1.27)
				)
			)
		)
		(property "Value" "4K7R2F-GP"
			(at 0.064008 -3.993896 180)
			(unlocked yes)
			(layer "F.Fab")
			(hide yes)
			(effects
				(font
					(size 1.016 1.016)
					(thickness 0.1524)
				)
			)
		)
		(property "Device Type" "R402H16"
			(at 0.064008 -5.517896 180)
			(unlocked yes)
			(layer "F.Fab")
			(hide yes)
			(effects
				(font
					(size 1.016 1.016)
					(thickness 0.1524)
				)
			)
		)
		(duplicate_pad_numbers_are_jumpers no)
		(fp_line
			(start 0.508 -0.9398)
			(end -0.508 -0.9398)
			(stroke
				(width 0.1524)
				(type default)
			)
			(layer "F.SilkS")
		)
		(fp_line
			(start -0.508 -0.9398)
			(end -0.508 0.9398)
			(stroke
				(width 0.1524)
				(type default)
			)
			(layer "F.SilkS")
		)
		(fp_rect
			(start -0.508 0.9398)
			(end 0.508 -0.9398)
			(stroke
				(width 0)
				(type default)
			)
			(fill no)
			(layer "F.CrtYd")
		)
		(fp_rect
			(start -0.508 0.9398)
			(end 0.508 -0.9398)
			(stroke
				(width 0)
				(type default)
			)
			(fill no)
			(layer "F.Fab")
		)
		(pad "1" smd custom
			(at 0 -0.4445 180)
			(size 0.1397 0.1397)
			(layers "F.Cu" "F.Mask" "F.Paste")
			(net "EEPROM_A0")
			(options
				(clearance outline)
				(anchor circle)
			)
			(primitives
				(gr_poly
					(pts
						(arc
							(start -0.1778 -0.2794)
							(mid -0.249642 -0.249642)
							(end -0.2794 -0.1778)
						)
						(arc
							(start -0.2794 0.1778)
							(mid -0.249642 0.249642)
							(end -0.1778 0.2794)
						)
						(arc
							(start 0.1778 0.2794)
							(mid 0.249642 0.249642)
							(end 0.2794 0.1778)
						)
						(arc
							(start 0.2794 -0.1778)
							(mid 0.249642 -0.249642)
							(end 0.1778 -0.2794)
						)
					)
					(width 0)
					(fill yes)
				)
			)
		)
		(pad "2" smd custom
			(at 0 0.4445 180)
			(size 0.1397 0.1397)
			(layers "F.Cu" "F.Mask" "F.Paste")
			(net "GND")
			(options
				(clearance outline)
				(anchor circle)
			)
			(primitives
				(gr_poly
					(pts
						(arc
							(start -0.1778 -0.2794)
							(mid -0.249642 -0.249642)
							(end -0.2794 -0.1778)
						)
						(arc
							(start -0.2794 0.1778)
							(mid -0.249642 0.249642)
							(end -0.1778 0.2794)
						)
						(arc
							(start 0.1778 0.2794)
							(mid 0.249642 0.249642)
							(end 0.2794 0.1778)
						)
						(arc
							(start 0.2794 -0.1778)
							(mid 0.249642 -0.249642)
							(end 0.1778 -0.2794)
						)
					)
					(width 0)
					(fill yes)
				)
			)
		)
	)
	(footprint ""
		(layer "F.Cu")
		(at 37.2618 -314.3504 90)
		(property "Reference" "R149"
			(at 0 0 90)
			(layer "F.SilkS")
			(hide yes)
			(effects
				(font
					(size 1.27 1.27)
				)
			)
		)
		(property "Value" "4K7R2J-2-GP"
			(at 0.064008 -3.993896 90)
			(unlocked yes)
			(layer "F.Fab")
			(hide yes)
			(effects
				(font
					(size 1.016 1.016)
					(thickness 0.1524)
				)
			)
		)
		(property "Device Type" "R402H16"
			(at 0.064008 -5.517896 90)
			(unlocked yes)
			(layer "F.Fab")
			(hide yes)
			(effects
				(font
					(size 1.016 1.016)
					(thickness 0.1524)
				)
			)
		)
		(duplicate_pad_numbers_are_jumpers no)
		(fp_line
			(start 0.508 -0.9398)
			(end -0.508 -0.9398)
			(stroke
				(width 0.1524)
				(type default)
			)
			(layer "F.SilkS")
		)
		(fp_line
			(start -0.508 -0.9398)
			(end -0.508 0.9398)
			(stroke
				(width 0.1524)
				(type default)
			)
			(layer "F.SilkS")
		)
		(fp_rect
			(start -0.508 0.9398)
			(end 0.508 -0.9398)
			(stroke
				(width 0)
				(type default)
			)
			(fill no)
			(layer "F.CrtYd")
		)
		(fp_rect
			(start -0.508 0.9398)
			(end 0.508 -0.9398)
			(stroke
				(width 0)
				(type default)
			)
			(fill no)
			(layer "F.Fab")
		)
		(pad "1" smd custom
			(at 0 -0.4445 90)
			(size 0.1397 0.1397)
			(layers "F.Cu" "F.Mask" "F.Paste")
			(net "P12V")
			(options
				(clearance outline)
				(anchor circle)
			)
			(primitives
				(gr_poly
					(pts
						(arc
							(start -0.1778 -0.2794)
							(mid -0.249642 -0.249642)
							(end -0.2794 -0.1778)
						)
						(arc
							(start -0.2794 0.1778)
							(mid -0.249642 0.249642)
							(end -0.1778 0.2794)
						)
						(arc
							(start 0.1778 0.2794)
							(mid 0.249642 0.249642)
							(end 0.2794 0.1778)
						)
						(arc
							(start 0.2794 -0.1778)
							(mid 0.249642 -0.249642)
							(end 0.1778 -0.2794)
						)
					)
					(width 0)
					(fill yes)
				)
			)
		)
		(pad "2" smd custom
			(at 0 0.4445 90)
			(size 0.1397 0.1397)
			(layers "F.Cu" "F.Mask" "F.Paste")
			(net "SW_SSD11_R")
			(options
				(clearance outline)
				(anchor circle)
			)
			(primitives
				(gr_poly
					(pts
						(arc
							(start -0.1778 -0.2794)
							(mid -0.249642 -0.249642)
							(end -0.2794 -0.1778)
						)
						(arc
							(start -0.2794 0.1778)
							(mid -0.249642 0.249642)
							(end -0.1778 0.2794)
						)
						(arc
							(start 0.1778 0.2794)
							(mid 0.249642 0.249642)
							(end 0.2794 0.1778)
						)
						(arc
							(start 0.2794 -0.1778)
							(mid 0.249642 -0.249642)
							(end 0.1778 -0.2794)
						)
					)
					(width 0)
					(fill yes)
				)
			)
		)
	)
	(footprint ""
		(layer "F.Cu")
		(at 85.471 -209.042 -90)
		(property "Reference" "PR9040"
			(at 0 0 270)
			(layer "F.SilkS")
			(hide yes)
			(effects
				(font
					(size 1.27 1.27)
				)
			)
		)
		(property "Value" "4K7R2F-GP"
			(at 0.064008 -3.993896 270)
			(unlocked yes)
			(layer "F.Fab")
			(hide yes)
			(effects
				(font
					(size 1.016 1.016)
					(thickness 0.1524)
				)
			)
		)
		(property "Device Type" "R402H16"
			(at 0.064008 -5.517896 270)
			(unlocked yes)
			(layer "F.Fab")
			(hide yes)
			(effects
				(font
					(size 1.016 1.016)
					(thickness 0.1524)
				)
			)
		)
		(duplicate_pad_numbers_are_jumpers no)
		(fp_line
			(start -0.508 -0.9398)
			(end -0.508 0.9398)
			(stroke
				(width 0.1524)
				(type default)
			)
			(layer "F.SilkS")
		)
		(fp_line
			(start 0.508 -0.9398)
			(end -0.508 -0.9398)
			(stroke
				(width 0.1524)
				(type default)
			)
			(layer "F.SilkS")
		)
		(fp_rect
			(start -0.508 0.9398)
			(end 0.508 -0.9398)
			(stroke
				(width 0)
				(type default)
			)
			(fill no)
			(layer "F.CrtYd")
		)
		(fp_rect
			(start -0.508 0.9398)
			(end 0.508 -0.9398)
			(stroke
				(width 0)
				(type default)
			)
			(fill no)
			(layer "F.Fab")
		)
		(pad "1" smd custom
			(at 0 -0.4445 270)
			(size 0.1397 0.1397)
			(layers "F.Cu" "F.Mask" "F.Paste")
			(net "CLK_BUF_EU3_SMB_A0_TRI")
			(options
				(clearance outline)
				(anchor circle)
			)
			(primitives
				(gr_poly
					(pts
						(arc
							(start -0.1778 -0.2794)
							(mid -0.249642 -0.249642)
							(end -0.2794 -0.1778)
						)
						(arc
							(start -0.2794 0.1778)
							(mid -0.249642 0.249642)
							(end -0.1778 0.2794)
						)
						(arc
							(start 0.1778 0.2794)
							(mid 0.249642 0.249642)
							(end 0.2794 0.1778)
						)
						(arc
							(start 0.2794 -0.1778)
							(mid 0.249642 -0.249642)
							(end 0.1778 -0.2794)
						)
					)
					(width 0)
					(fill yes)
				)
			)
		)
		(pad "2" smd custom
			(at 0 0.4445 270)
			(size 0.1397 0.1397)
			(layers "F.Cu" "F.Mask" "F.Paste")
			(net "GND")
			(options
				(clearance outline)
				(anchor circle)
			)
			(primitives
				(gr_poly
					(pts
						(arc
							(start -0.1778 -0.2794)
							(mid -0.249642 -0.249642)
							(end -0.2794 -0.1778)
						)
						(arc
							(start -0.2794 0.1778)
							(mid -0.249642 0.249642)
							(end -0.1778 0.2794)
						)
						(arc
							(start 0.1778 0.2794)
							(mid 0.249642 0.249642)
							(end 0.2794 0.1778)
						)
						(arc
							(start 0.2794 -0.1778)
							(mid 0.249642 -0.249642)
							(end 0.1778 -0.2794)
						)
					)
					(width 0)
					(fill yes)
				)
			)
		)
	)
	(footprint ""
		(layer "F.Cu")
		(at 71.0311 -366.522)
		(property "Reference" "SR983"
			(at 0 0 0)
			(layer "F.SilkS")
			(hide yes)
			(effects
				(font
					(size 1.27 1.27)
				)
			)
		)
		(property "Value" "2KR2F-3-GP"
			(at 0.064008 -3.993896 0)
			(unlocked yes)
			(layer "F.Fab")
			(hide yes)
			(effects
				(font
					(size 1.016 1.016)
					(thickness 0.1524)
				)
			)
		)
		(property "Device Type" "R402H16"
			(at 0.064008 -5.517896 0)
			(unlocked yes)
			(layer "F.Fab")
			(hide yes)
			(effects
				(font
					(size 1.016 1.016)
					(thickness 0.1524)
				)
			)
		)
		(duplicate_pad_numbers_are_jumpers no)
		(fp_line
			(start -0.508 -0.9398)
			(end -0.508 0.9398)
			(stroke
				(width 0.1524)
				(type default)
			)
			(layer "F.SilkS")
		)
		(fp_line
			(start 0.508 -0.9398)
			(end -0.508 -0.9398)
			(stroke
				(width 0.1524)
				(type default)
			)
			(layer "F.SilkS")
		)
		(fp_rect
			(start -0.508 0.9398)
			(end 0.508 -0.9398)
			(stroke
				(width 0)
				(type default)
			)
			(fill no)
			(layer "F.CrtYd")
		)
		(fp_rect
			(start -0.508 0.9398)
			(end 0.508 -0.9398)
			(stroke
				(width 0)
				(type default)
			)
			(fill no)
			(layer "F.Fab")
		)
		(pad "1" smd custom
			(at 0 -0.4445)
			(size 0.1397 0.1397)
			(layers "F.Cu" "F.Mask" "F.Paste")
			(net "P3V3")
			(options
				(clearance outline)
				(anchor circle)
			)
			(primitives
				(gr_poly
					(pts
						(arc
							(start -0.1778 -0.2794)
							(mid -0.249642 -0.249642)
							(end -0.2794 -0.1778)
						)
						(arc
							(start -0.2794 0.1778)
							(mid -0.249642 0.249642)
							(end -0.1778 0.2794)
						)
						(arc
							(start 0.1778 0.2794)
							(mid 0.249642 0.249642)
							(end 0.2794 0.1778)
						)
						(arc
							(start 0.2794 -0.1778)
							(mid 0.249642 -0.249642)
							(end 0.1778 -0.2794)
						)
					)
					(width 0)
					(fill yes)
				)
			)
		)
		(pad "2" smd custom
			(at 0 0.4445)
			(size 0.1397 0.1397)
			(layers "F.Cu" "F.Mask" "F.Paste")
			(net "SCL_DR6")
			(options
				(clearance outline)
				(anchor circle)
			)
			(primitives
				(gr_poly
					(pts
						(arc
							(start -0.1778 -0.2794)
							(mid -0.249642 -0.249642)
							(end -0.2794 -0.1778)
						)
						(arc
							(start -0.2794 0.1778)
							(mid -0.249642 0.249642)
							(end -0.1778 0.2794)
						)
						(arc
							(start 0.1778 0.2794)
							(mid 0.249642 0.249642)
							(end 0.2794 0.1778)
						)
						(arc
							(start 0.2794 -0.1778)
							(mid 0.249642 -0.249642)
							(end 0.1778 -0.2794)
						)
					)
					(width 0)
					(fill yes)
				)
			)
		)
	)
	(footprint ""
		(layer "F.Cu")
		(at 206.67345 -301.94885 90)
		(property "Reference" "R9793"
			(at 0 0 90)
			(layer "F.SilkS")
			(hide yes)
			(effects
				(font
					(size 1.27 1.27)
				)
			)
		)
		(property "Value" "1KR2J-1-GP"
			(at 0.064008 -3.993896 90)
			(unlocked yes)
			(layer "F.Fab")
			(hide yes)
			(effects
				(font
					(size 1.016 1.016)
					(thickness 0.1524)
				)
			)
		)
		(property "Device Type" "R402H16"
			(at 0.064008 -5.517896 90)
			(unlocked yes)
			(layer "F.Fab")
			(hide yes)
			(effects
				(font
					(size 1.016 1.016)
					(thickness 0.1524)
				)
			)
		)
		(duplicate_pad_numbers_are_jumpers no)
		(fp_line
			(start 0.508 -0.9398)
			(end -0.508 -0.9398)
			(stroke
				(width 0.1524)
				(type default)
			)
			(layer "F.SilkS")
		)
		(fp_line
			(start -0.508 -0.9398)
			(end -0.508 0.9398)
			(stroke
				(width 0.1524)
				(type default)
			)
			(layer "F.SilkS")
		)
		(fp_rect
			(start -0.508 0.9398)
			(end 0.508 -0.9398)
			(stroke
				(width 0)
				(type default)
			)
			(fill no)
			(layer "F.CrtYd")
		)
		(fp_rect
			(start -0.508 0.9398)
			(end 0.508 -0.9398)
			(stroke
				(width 0)
				(type default)
			)
			(fill no)
			(layer "F.Fab")
		)
		(pad "1" smd custom
			(at 0 -0.4445 90)
			(size 0.1397 0.1397)
			(layers "F.Cu" "F.Mask" "F.Paste")
			(net "SSD2_PWREN")
			(options
				(clearance outline)
				(anchor circle)
			)
			(primitives
				(gr_poly
					(pts
						(arc
							(start -0.1778 -0.2794)
							(mid -0.249642 -0.249642)
							(end -0.2794 -0.1778)
						)
						(arc
							(start -0.2794 0.1778)
							(mid -0.249642 0.249642)
							(end -0.1778 0.2794)
						)
						(arc
							(start 0.1778 0.2794)
							(mid 0.249642 0.249642)
							(end 0.2794 0.1778)
						)
						(arc
							(start 0.2794 -0.1778)
							(mid 0.249642 -0.249642)
							(end 0.1778 -0.2794)
						)
					)
					(width 0)
					(fill yes)
				)
			)
		)
		(pad "2" smd custom
			(at 0 0.4445 90)
			(size 0.1397 0.1397)
			(layers "F.Cu" "F.Mask" "F.Paste")
			(net "SSD2_PWREN_R")
			(options
				(clearance outline)
				(anchor circle)
			)
			(primitives
				(gr_poly
					(pts
						(arc
							(start -0.1778 -0.2794)
							(mid -0.249642 -0.249642)
							(end -0.2794 -0.1778)
						)
						(arc
							(start -0.2794 0.1778)
							(mid -0.249642 0.249642)
							(end -0.1778 0.2794)
						)
						(arc
							(start 0.1778 0.2794)
							(mid 0.249642 0.249642)
							(end 0.2794 0.1778)
						)
						(arc
							(start 0.2794 -0.1778)
							(mid 0.249642 -0.249642)
							(end 0.1778 -0.2794)
						)
					)
					(width 0)
					(fill yes)
				)
			)
		)
	)
	(footprint ""
		(layer "F.Cu")
		(at 228.2698 -196.7484)
		(property "Reference" "R9261"
			(at 0 0 0)
			(layer "F.SilkS")
			(hide yes)
			(effects
				(font
					(size 1.27 1.27)
				)
			)
		)
		(property "Value" "2R2010F-GP"
			(at 0.0762 -4.5466 0)
			(unlocked yes)
			(layer "F.Fab")
			(hide yes)
			(effects
				(font
					(size 1.016 1.016)
					(thickness 0.1524)
				)
			)
		)
		(property "Device Type" "R2010H26"
			(at 0.0762 -6.1468 0)
			(unlocked yes)
			(layer "F.Fab")
			(hide yes)
			(effects
				(font
					(size 1.016 1.016)
					(thickness 0.1524)
				)
			)
		)
		(duplicate_pad_numbers_are_jumpers no)
		(fp_line
			(start -3.302 -1.651)
			(end -3.302 1.651)
			(stroke
				(width 0.1524)
				(type default)
			)
			(layer "F.SilkS")
		)
		(fp_line
			(start -3.302 1.651)
			(end 3.302 1.651)
			(stroke
				(width 0.1524)
				(type default)
			)
			(layer "F.SilkS")
		)
		(fp_line
			(start 3.302 -1.651)
			(end -3.302 -1.651)
			(stroke
				(width 0.1524)
				(type default)
			)
			(layer "F.SilkS")
		)
		(fp_line
			(start 3.302 1.651)
			(end 3.302 -1.651)
			(stroke
				(width 0.1524)
				(type default)
			)
			(layer "F.SilkS")
		)
		(fp_rect
			(start -3.3782 1.7272)
			(end 3.3782 -1.7272)
			(stroke
				(width 0)
				(type default)
			)
			(fill no)
			(layer "F.CrtYd")
		)
		(fp_poly
			(pts
				(xy 3.3782 -1.7272) (xy -3.3782 -1.7272) (xy -3.3782 1.7272) (xy 3.3782 1.7272)
			)
			(stroke
				(width 0)
				(type default)
			)
			(fill no)
			(layer "F.Fab")
		)
		(pad "1" smd rect
			(at -2.3495 0)
			(size 1.143 2.794)
			(layers "F.Cu" "F.Mask" "F.Paste")
			(net "P12V_SSD3")
		)
		(pad "2" smd rect
			(at 2.3495 0)
			(size 1.143 2.794)
			(layers "F.Cu" "F.Mask" "F.Paste")
			(net "12V_PRECH_SSD3")
		)
	)
	(footprint ""
		(layer "F.Cu")
		(at 99.314 -296.545)
		(property "Reference" "R9076"
			(at 0 0 0)
			(layer "F.SilkS")
			(hide yes)
			(effects
				(font
					(size 1.27 1.27)
				)
			)
		)
		(property "Value" "27R2F-GP"
			(at 0.064008 -3.993896 0)
			(unlocked yes)
			(layer "F.Fab")
			(hide yes)
			(effects
				(font
					(size 1.016 1.016)
					(thickness 0.1524)
				)
			)
		)
		(property "Device Type" "R402H16"
			(at 0.064008 -5.517896 0)
			(unlocked yes)
			(layer "F.Fab")
			(hide yes)
			(effects
				(font
					(size 1.016 1.016)
					(thickness 0.1524)
				)
			)
		)
		(duplicate_pad_numbers_are_jumpers no)
		(fp_line
			(start -0.508 -0.9398)
			(end -0.508 0.9398)
			(stroke
				(width 0.1524)
				(type default)
			)
			(layer "F.SilkS")
		)
		(fp_line
			(start 0.508 -0.9398)
			(end -0.508 -0.9398)
			(stroke
				(width 0.1524)
				(type default)
			)
			(layer "F.SilkS")
		)
		(fp_rect
			(start -0.508 0.9398)
			(end 0.508 -0.9398)
			(stroke
				(width 0)
				(type default)
			)
			(fill no)
			(layer "F.CrtYd")
		)
		(fp_rect
			(start -0.508 0.9398)
			(end 0.508 -0.9398)
			(stroke
				(width 0)
				(type default)
			)
			(fill no)
			(layer "F.Fab")
		)
		(pad "1" smd custom
			(at 0 -0.4445)
			(size 0.1397 0.1397)
			(layers "F.Cu" "F.Mask" "F.Paste")
			(net "PE_CLK_100M_DR2_1_R_P")
			(options
				(clearance outline)
				(anchor circle)
			)
			(primitives
				(gr_poly
					(pts
						(arc
							(start -0.1778 -0.2794)
							(mid -0.249642 -0.249642)
							(end -0.2794 -0.1778)
						)
						(arc
							(start -0.2794 0.1778)
							(mid -0.249642 0.249642)
							(end -0.1778 0.2794)
						)
						(arc
							(start 0.1778 0.2794)
							(mid 0.249642 0.249642)
							(end 0.2794 0.1778)
						)
						(arc
							(start 0.2794 -0.1778)
							(mid 0.249642 -0.249642)
							(end 0.1778 -0.2794)
						)
					)
					(width 0)
					(fill yes)
				)
			)
		)
		(pad "2" smd custom
			(at 0 0.4445)
			(size 0.1397 0.1397)
			(layers "F.Cu" "F.Mask" "F.Paste")
			(net "PE_CLK100M_DR2_1_P")
			(options
				(clearance outline)
				(anchor circle)
			)
			(primitives
				(gr_poly
					(pts
						(arc
							(start -0.1778 -0.2794)
							(mid -0.249642 -0.249642)
							(end -0.2794 -0.1778)
						)
						(arc
							(start -0.2794 0.1778)
							(mid -0.249642 0.249642)
							(end -0.1778 0.2794)
						)
						(arc
							(start 0.1778 0.2794)
							(mid 0.249642 0.249642)
							(end 0.2794 0.1778)
						)
						(arc
							(start 0.2794 -0.1778)
							(mid 0.249642 -0.249642)
							(end 0.1778 -0.2794)
						)
					)
					(width 0)
					(fill yes)
				)
			)
		)
	)
	(footprint ""
		(layer "F.Cu")
		(at 35.56 -142.24 180)
		(property "Reference" "Q69"
			(at 0 0 180)
			(layer "F.SilkS")
			(hide yes)
			(effects
				(font
					(size 1.27 1.27)
				)
			)
		)
		(property "Value" "2N7002A-7-GP"
			(at 0.127 -8.9662 180)
			(unlocked yes)
			(layer "F.Fab")
			(hide yes)
			(effects
				(font
					(size 1.016 1.016)
					(thickness 0.1524)
				)
			)
		)
		(property "Device Type" "SOT23DGS2D4H48"
			(at 0.127 -10.4902 180)
			(unlocked yes)
			(layer "F.Fab")
			(hide yes)
			(effects
				(font
					(size 1.016 1.016)
					(thickness 0.1524)
				)
			)
		)
		(duplicate_pad_numbers_are_jumpers no)
		(fp_line
			(start 1.651 1.778)
			(end 1.651 -1.778)
			(stroke
				(width 0.1524)
				(type default)
			)
			(layer "F.SilkS")
		)
		(fp_line
			(start 1.651 -1.778)
			(end -1.651 -1.778)
			(stroke
				(width 0.1524)
				(type default)
			)
			(layer "F.SilkS")
		)
		(fp_line
			(start -1.651 1.778)
			(end 1.651 1.778)
			(stroke
				(width 0.1524)
				(type default)
			)
			(layer "F.SilkS")
		)
		(fp_line
			(start -1.651 -1.778)
			(end -1.651 1.778)
			(stroke
				(width 0.1524)
				(type default)
			)
			(layer "F.SilkS")
		)
		(fp_poly
			(pts
				(xy -1.778 1.8796) (xy -1.778 -1.8796) (xy 1.778 -1.8796) (xy 1.778 1.8796)
			)
			(stroke
				(width 0)
				(type default)
			)
			(fill no)
			(layer "F.CrtYd")
		)
		(fp_poly
			(pts
				(xy -1.778 1.8796) (xy -1.778 -1.8796) (xy 1.778 -1.8796) (xy 1.778 1.8796)
			)
			(stroke
				(width 0)
				(type default)
			)
			(fill no)
			(layer "F.Fab")
		)
		(pad "D" smd custom
			(at 0 -0.9525 180)
			(size 0.1905 0.1905)
			(layers "F.Cu" "F.Mask" "F.Paste")
			(net "SSD8_CLK0_OE_MOS_N")
			(options
				(clearance outline)
				(anchor circle)
			)
			(primitives
				(gr_poly
					(pts
						(arc
							(start -0.1778 0.5715)
							(mid -0.321484 0.511984)
							(end -0.381 0.3683)
						)
						(arc
							(start -0.381 -0.3683)
							(mid -0.321484 -0.511984)
							(end -0.1778 -0.5715)
						)
						(arc
							(start 0.1778 -0.5715)
							(mid 0.321484 -0.511984)
							(end 0.381 -0.3683)
						)
						(arc
							(start 0.381 0.3683)
							(mid 0.321484 0.511984)
							(end 0.1778 0.5715)
						)
					)
					(width 0)
					(fill yes)
				)
			)
		)
		(pad "G" smd custom
			(at -0.98425 0.9525 180)
			(size 0.1905 0.1905)
			(layers "F.Cu" "F.Mask" "F.Paste")
			(net "SSD8_CLK0_OE_R_N")
			(options
				(clearance outline)
				(anchor circle)
			)
			(primitives
				(gr_poly
					(pts
						(arc
							(start -0.1778 0.5715)
							(mid -0.321484 0.511984)
							(end -0.381 0.3683)
						)
						(arc
							(start -0.381 -0.3683)
							(mid -0.321484 -0.511984)
							(end -0.1778 -0.5715)
						)
						(arc
							(start 0.1778 -0.5715)
							(mid 0.321484 -0.511984)
							(end 0.381 -0.3683)
						)
						(arc
							(start 0.381 0.3683)
							(mid 0.321484 0.511984)
							(end 0.1778 0.5715)
						)
					)
					(width 0)
					(fill yes)
				)
			)
		)
		(pad "S" smd custom
			(at 0.98425 0.9525 180)
			(size 0.1905 0.1905)
			(layers "F.Cu" "F.Mask" "F.Paste")
			(net "GND")
			(options
				(clearance outline)
				(anchor circle)
			)
			(primitives
				(gr_poly
					(pts
						(arc
							(start -0.1778 0.5715)
							(mid -0.321484 0.511984)
							(end -0.381 0.3683)
						)
						(arc
							(start -0.381 -0.3683)
							(mid -0.321484 -0.511984)
							(end -0.1778 -0.5715)
						)
						(arc
							(start 0.1778 -0.5715)
							(mid 0.321484 -0.511984)
							(end 0.381 -0.3683)
						)
						(arc
							(start 0.381 0.3683)
							(mid 0.321484 0.511984)
							(end 0.1778 0.5715)
						)
					)
					(width 0)
					(fill yes)
				)
			)
		)
	)
	(footprint ""
		(layer "F.Cu")
		(at 206.502 -398.526)
		(property "Reference" "D19"
			(at 0 0 0)
			(layer "F.SilkS")
			(hide yes)
			(effects
				(font
					(size 1.27 1.27)
				)
			)
		)
		(property "Value" "RB551V30-1-GP"
			(at 0 -6.7818 0)
			(unlocked yes)
			(layer "F.Fab")
			(hide yes)
			(effects
				(font
					(size 1.016 1.016)
					(thickness 0.1524)
				)
			)
		)
		(property "Device Type" "SOD323AKH44"
			(at 0 -8.6868 0)
			(unlocked yes)
			(layer "F.Fab")
			(hide yes)
			(effects
				(font
					(size 1.016 1.016)
					(thickness 0.1524)
				)
			)
		)
		(duplicate_pad_numbers_are_jumpers no)
		(fp_line
			(start -0.889 -1.9304)
			(end 0.889 -1.9304)
			(stroke
				(width 0.1524)
				(type default)
			)
			(layer "F.SilkS")
		)
		(fp_line
			(start -0.889 2.159)
			(end -0.889 -1.9304)
			(stroke
				(width 0.1524)
				(type default)
			)
			(layer "F.SilkS")
		)
		(fp_line
			(start 0.762 2.0574)
			(end -0.762 2.0574)
			(stroke
				(width 0.508)
				(type default)
			)
			(layer "F.SilkS")
		)
		(fp_line
			(start 0.889 -1.9304)
			(end 0.889 2.159)
			(stroke
				(width 0.1524)
				(type default)
			)
			(layer "F.SilkS")
		)
		(fp_line
			(start 0.889 2.159)
			(end -0.889 2.159)
			(stroke
				(width 0.1524)
				(type default)
			)
			(layer "F.SilkS")
		)
		(fp_rect
			(start -1.016 2.3114)
			(end 1.016 -2.0066)
			(stroke
				(width 0)
				(type default)
			)
			(fill no)
			(layer "F.CrtYd")
		)
		(fp_poly
			(pts
				(xy -1.016 -2.0066) (xy 1.016 -2.0066) (xy 1.016 2.3114) (xy -1.016 2.3114)
			)
			(stroke
				(width 0)
				(type default)
			)
			(fill no)
			(layer "F.Fab")
		)
		(pad "A" smd rect
			(at 0 -1.143)
			(size 0.5588 1.016)
			(layers "F.Cu" "F.Mask" "F.Paste")
			(net "SW_SSD1_R")
		)
		(pad "K" smd rect
			(at 0 1.143)
			(size 0.5588 1.016)
			(layers "F.Cu" "F.Mask" "F.Paste")
			(net "SW_SSD1_N")
		)
	)
	(footprint ""
		(layer "F.Cu")
		(at 96.52 -92.964)
		(property "Reference" "R9125"
			(at 0 0 0)
			(layer "F.SilkS")
			(hide yes)
			(effects
				(font
					(size 1.27 1.27)
				)
			)
		)
		(property "Value" "27R2F-GP"
			(at 0.064008 -3.993896 0)
			(unlocked yes)
			(layer "F.Fab")
			(hide yes)
			(effects
				(font
					(size 1.016 1.016)
					(thickness 0.1524)
				)
			)
		)
		(property "Device Type" "R402H16"
			(at 0.064008 -5.517896 0)
			(unlocked yes)
			(layer "F.Fab")
			(hide yes)
			(effects
				(font
					(size 1.016 1.016)
					(thickness 0.1524)
				)
			)
		)
		(duplicate_pad_numbers_are_jumpers no)
		(fp_line
			(start -0.508 -0.9398)
			(end -0.508 0.9398)
			(stroke
				(width 0.1524)
				(type default)
			)
			(layer "F.SilkS")
		)
		(fp_line
			(start 0.508 -0.9398)
			(end -0.508 -0.9398)
			(stroke
				(width 0.1524)
				(type default)
			)
			(layer "F.SilkS")
		)
		(fp_rect
			(start -0.508 0.9398)
			(end 0.508 -0.9398)
			(stroke
				(width 0)
				(type default)
			)
			(fill no)
			(layer "F.CrtYd")
		)
		(fp_rect
			(start -0.508 0.9398)
			(end 0.508 -0.9398)
			(stroke
				(width 0)
				(type default)
			)
			(fill no)
			(layer "F.Fab")
		)
		(pad "1" smd custom
			(at 0 -0.4445)
			(size 0.1397 0.1397)
			(layers "F.Cu" "F.Mask" "F.Paste")
			(net "PE_CLK_100M_DR14_2_R_N")
			(options
				(clearance outline)
				(anchor circle)
			)
			(primitives
				(gr_poly
					(pts
						(arc
							(start -0.1778 -0.2794)
							(mid -0.249642 -0.249642)
							(end -0.2794 -0.1778)
						)
						(arc
							(start -0.2794 0.1778)
							(mid -0.249642 0.249642)
							(end -0.1778 0.2794)
						)
						(arc
							(start 0.1778 0.2794)
							(mid 0.249642 0.249642)
							(end 0.2794 0.1778)
						)
						(arc
							(start 0.2794 -0.1778)
							(mid 0.249642 -0.249642)
							(end 0.1778 -0.2794)
						)
					)
					(width 0)
					(fill yes)
				)
			)
		)
		(pad "2" smd custom
			(at 0 0.4445)
			(size 0.1397 0.1397)
			(layers "F.Cu" "F.Mask" "F.Paste")
			(net "PE_CLK100M_DR14_2_N")
			(options
				(clearance outline)
				(anchor circle)
			)
			(primitives
				(gr_poly
					(pts
						(arc
							(start -0.1778 -0.2794)
							(mid -0.249642 -0.249642)
							(end -0.2794 -0.1778)
						)
						(arc
							(start -0.2794 0.1778)
							(mid -0.249642 0.249642)
							(end -0.1778 0.2794)
						)
						(arc
							(start 0.1778 0.2794)
							(mid 0.249642 0.249642)
							(end 0.2794 0.1778)
						)
						(arc
							(start 0.2794 -0.1778)
							(mid 0.249642 -0.249642)
							(end 0.1778 -0.2794)
						)
					)
					(width 0)
					(fill yes)
				)
			)
		)
	)
	(footprint ""
		(layer "F.Cu")
		(at 244.0178 -360.6038)
		(property "Reference" "C349"
			(at 0 0 0)
			(layer "F.SilkS")
			(hide yes)
			(effects
				(font
					(size 1.27 1.27)
				)
			)
		)
		(property "Value" "SC22U25V6KX-GP-U"
			(at -2.860802 -5.279644 0)
			(unlocked yes)
			(layer "F.Fab")
			(hide yes)
			(effects
				(font
					(size 1.016 1.016)
					(thickness 0.1524)
				)
			)
		)
		(property "Device Type" "C1206-TO0D3H75"
			(at -2.860802 -6.803644 0)
			(unlocked yes)
			(layer "F.Fab")
			(hide yes)
			(effects
				(font
					(size 1.016 1.016)
					(thickness 0.1524)
				)
			)
		)
		(duplicate_pad_numbers_are_jumpers no)
		(fp_line
			(start -1.3081 -2.3749)
			(end 1.3081 -2.3749)
			(stroke
				(width 0.1524)
				(type default)
			)
			(layer "F.SilkS")
		)
		(fp_line
			(start -1.3081 2.3749)
			(end -1.3081 -2.3749)
			(stroke
				(width 0.1524)
				(type default)
			)
			(layer "F.SilkS")
		)
		(fp_line
			(start 1.3081 -2.3749)
			(end 1.3081 2.3749)
			(stroke
				(width 0.1524)
				(type default)
			)
			(layer "F.SilkS")
		)
		(fp_line
			(start 1.3081 2.3749)
			(end -1.3081 2.3749)
			(stroke
				(width 0.1524)
				(type default)
			)
			(layer "F.SilkS")
		)
		(fp_rect
			(start -0.8001 1.6002)
			(end 0.8001 -1.6002)
			(stroke
				(width 0)
				(type default)
			)
			(fill no)
			(layer "F.CrtYd")
		)
		(fp_poly
			(pts
				(xy -1.5621 2.4511) (xy -1.5621 1.6002) (xy 0.8001 1.6002) (xy 0.8001 -1.6002) (xy -0.8001 -1.6002)
				(xy -0.8001 1.5875) (xy -1.5621 1.5875) (xy -1.5621 -2.4511) (xy 1.5621 -2.4511) (xy 1.5621 2.4511)
			)
			(stroke
				(width 0)
				(type default)
			)
			(fill no)
			(layer "F.CrtYd")
		)
		(fp_rect
			(start -1.5621 2.4511)
			(end 1.5621 -2.4511)
			(stroke
				(width 0)
				(type default)
			)
			(fill no)
			(layer "F.Fab")
		)
		(pad "1" smd rect
			(at 0 -1.392936)
			(size 2.1082 1.4478)
			(layers "F.Cu" "F.Mask" "F.Paste")
			(net "P12V")
		)
		(pad "2" smd rect
			(at 0 1.392936)
			(size 2.1082 1.4478)
			(layers "F.Cu" "F.Mask" "F.Paste")
			(net "GND")
		)
	)
	(footprint ""
		(layer "F.Cu")
		(at 99.949 -105.791)
		(property "Reference" "C8874"
			(at 0 0 0)
			(layer "F.SilkS")
			(hide yes)
			(effects
				(font
					(size 1.27 1.27)
				)
			)
		)
		(property "Value" "SCD1U16V2KX-3GP"
			(at 1.1811 -2.7051 0)
			(unlocked yes)
			(layer "F.Fab")
			(hide yes)
			(effects
				(font
					(size 1.016 1.016)
					(thickness 0.1524)
				)
			)
		)
		(property "Device Type" "C402H22"
			(at 1.1811 -4.2291 0)
			(unlocked yes)
			(layer "F.Fab")
			(hide yes)
			(effects
				(font
					(size 1.016 1.016)
					(thickness 0.1524)
				)
			)
		)
		(duplicate_pad_numbers_are_jumpers no)
		(fp_rect
			(start -0.4318 0.9525)
			(end 0.4318 -0.9525)
			(stroke
				(width 0)
				(type default)
			)
			(fill no)
			(layer "F.CrtYd")
		)
		(fp_rect
			(start -0.4318 0.9525)
			(end 0.4318 -0.9525)
			(stroke
				(width 0)
				(type default)
			)
			(fill no)
			(layer "F.Fab")
		)
		(pad "1" smd custom
			(at 0 -0.4445)
			(size 0.1524 0.1524)
			(layers "F.Cu" "F.Mask" "F.Paste")
			(net "VDD_IO_4")
			(options
				(clearance outline)
				(anchor circle)
			)
			(primitives
				(gr_poly
					(pts
						(arc
							(start 0.3048 -0.2032)
							(mid 0.275042 -0.275042)
							(end 0.2032 -0.3048)
						)
						(arc
							(start -0.2032 -0.3048)
							(mid -0.275042 -0.275042)
							(end -0.3048 -0.2032)
						)
						(arc
							(start -0.3048 0.2032)
							(mid -0.275042 0.275042)
							(end -0.2032 0.3048)
						)
						(arc
							(start 0.2032 0.3048)
							(mid 0.275042 0.275042)
							(end 0.3048 0.2032)
						)
					)
					(width 0)
					(fill yes)
				)
			)
		)
		(pad "2" smd custom
			(at 0 0.4445)
			(size 0.1524 0.1524)
			(layers "F.Cu" "F.Mask" "F.Paste")
			(net "GND")
			(options
				(clearance outline)
				(anchor circle)
			)
			(primitives
				(gr_poly
					(pts
						(arc
							(start 0.3048 -0.2032)
							(mid 0.275042 -0.275042)
							(end 0.2032 -0.3048)
						)
						(arc
							(start -0.2032 -0.3048)
							(mid -0.275042 -0.275042)
							(end -0.3048 -0.2032)
						)
						(arc
							(start -0.3048 0.2032)
							(mid -0.275042 0.275042)
							(end -0.2032 0.3048)
						)
						(arc
							(start 0.2032 0.3048)
							(mid 0.275042 0.275042)
							(end 0.3048 0.2032)
						)
					)
					(width 0)
					(fill yes)
				)
			)
		)
	)
	(footprint ""
		(layer "F.Cu")
		(at 30.6578 -493.7506 90)
		(property "Reference" "SR1101"
			(at 0 0 90)
			(layer "F.SilkS")
			(hide yes)
			(effects
				(font
					(size 1.27 1.27)
				)
			)
		)
		(property "Value" "4K7R2F-GP"
			(at 0.064008 -3.993896 90)
			(unlocked yes)
			(layer "F.Fab")
			(hide yes)
			(effects
				(font
					(size 1.016 1.016)
					(thickness 0.1524)
				)
			)
		)
		(property "Device Type" "R402H16"
			(at 0.064008 -5.517896 90)
			(unlocked yes)
			(layer "F.Fab")
			(hide yes)
			(effects
				(font
					(size 1.016 1.016)
					(thickness 0.1524)
				)
			)
		)
		(duplicate_pad_numbers_are_jumpers no)
		(fp_line
			(start 0.508 -0.9398)
			(end -0.508 -0.9398)
			(stroke
				(width 0.1524)
				(type default)
			)
			(layer "F.SilkS")
		)
		(fp_line
			(start -0.508 -0.9398)
			(end -0.508 0.9398)
			(stroke
				(width 0.1524)
				(type default)
			)
			(layer "F.SilkS")
		)
		(fp_rect
			(start -0.508 0.9398)
			(end 0.508 -0.9398)
			(stroke
				(width 0)
				(type default)
			)
			(fill no)
			(layer "F.CrtYd")
		)
		(fp_rect
			(start -0.508 0.9398)
			(end 0.508 -0.9398)
			(stroke
				(width 0)
				(type default)
			)
			(fill no)
			(layer "F.Fab")
		)
		(pad "1" smd custom
			(at 0 -0.4445 90)
			(size 0.1397 0.1397)
			(layers "F.Cu" "F.Mask" "F.Paste")
			(net "P3V3")
			(options
				(clearance outline)
				(anchor circle)
			)
			(primitives
				(gr_poly
					(pts
						(arc
							(start -0.1778 -0.2794)
							(mid -0.249642 -0.249642)
							(end -0.2794 -0.1778)
						)
						(arc
							(start -0.2794 0.1778)
							(mid -0.249642 0.249642)
							(end -0.1778 0.2794)
						)
						(arc
							(start 0.1778 0.2794)
							(mid 0.249642 0.249642)
							(end 0.2794 0.1778)
						)
						(arc
							(start 0.2794 -0.1778)
							(mid 0.249642 -0.249642)
							(end 0.1778 -0.2794)
						)
					)
					(width 0)
					(fill yes)
				)
			)
		)
		(pad "2" smd custom
			(at 0 0.4445 90)
			(size 0.1397 0.1397)
			(layers "F.Cu" "F.Mask" "F.Paste")
			(net "DUALPORTEN#5")
			(options
				(clearance outline)
				(anchor circle)
			)
			(primitives
				(gr_poly
					(pts
						(arc
							(start -0.1778 -0.2794)
							(mid -0.249642 -0.249642)
							(end -0.2794 -0.1778)
						)
						(arc
							(start -0.2794 0.1778)
							(mid -0.249642 0.249642)
							(end -0.1778 0.2794)
						)
						(arc
							(start 0.1778 0.2794)
							(mid 0.249642 0.249642)
							(end 0.2794 0.1778)
						)
						(arc
							(start 0.2794 -0.1778)
							(mid 0.249642 -0.249642)
							(end 0.1778 -0.2794)
						)
					)
					(width 0)
					(fill yes)
				)
			)
		)
	)
	(footprint ""
		(layer "F.Cu")
		(at 51.903884 -450.088 -90)
		(property "Reference" "U202"
			(at 0 0 270)
			(layer "F.SilkS")
			(hide yes)
			(effects
				(font
					(size 1.27 1.27)
				)
			)
		)
		(property "Value" "SN74LVC1G08DCKR-GP"
			(at -2.3368 -8.6868 270)
			(unlocked yes)
			(layer "F.Fab")
			(hide yes)
			(effects
				(font
					(size 1.016 1.016)
					(thickness 0.1524)
				)
			)
		)
		(property "Device Type" "SC70-5H44"
			(at -2.3114 -10.414 270)
			(unlocked yes)
			(layer "F.Fab")
			(hide yes)
			(effects
				(font
					(size 1.016 1.016)
					(thickness 0.1524)
				)
			)
		)
		(duplicate_pad_numbers_are_jumpers no)
		(fp_line
			(start -1.27 1.7018)
			(end -1.27 -1.7018)
			(stroke
				(width 0.1524)
				(type default)
			)
			(layer "F.SilkS")
		)
		(fp_line
			(start 1.27 1.7018)
			(end -1.27 1.7018)
			(stroke
				(width 0.1524)
				(type default)
			)
			(layer "F.SilkS")
		)
		(fp_line
			(start -1.27 -1.7018)
			(end 1.27 -1.7018)
			(stroke
				(width 0.1524)
				(type default)
			)
			(layer "F.SilkS")
		)
		(fp_line
			(start 1.27 -1.7018)
			(end 1.27 1.7018)
			(stroke
				(width 0.1524)
				(type default)
			)
			(layer "F.SilkS")
		)
		(fp_line
			(start 0.6604 -1.8034)
			(end 1.3843 -1.8034)
			(stroke
				(width 0.3302)
				(type default)
			)
			(layer "F.SilkS")
		)
		(fp_line
			(start 1.3843 -1.8034)
			(end 1.3843 -1.1176)
			(stroke
				(width 0.3302)
				(type default)
			)
			(layer "F.SilkS")
		)
		(fp_rect
			(start -1.524 1.9558)
			(end 1.524 -1.9558)
			(stroke
				(width 0)
				(type default)
			)
			(fill no)
			(layer "F.CrtYd")
		)
		(fp_poly
			(pts
				(xy -1.524 -1.9558) (xy 1.524 -1.9558) (xy 1.524 1.9558) (xy -1.524 1.9558)
			)
			(stroke
				(width 0)
				(type default)
			)
			(fill no)
			(layer "F.Fab")
		)
		(pad "1" smd rect
			(at 0.65024 -0.8255 270)
			(size 0.4064 1.2192)
			(layers "F.Cu" "F.Mask" "F.Paste")
			(net "SSD5_CLK0_OE_MOS_N")
		)
		(pad "2" smd rect
			(at 0 -0.8255 270)
			(size 0.4064 1.2192)
			(layers "F.Cu" "F.Mask" "F.Paste")
			(net "ATTN_LED_DR5_N")
		)
		(pad "3" smd rect
			(at -0.65024 -0.8255 270)
			(size 0.4064 1.2192)
			(layers "F.Cu" "F.Mask" "F.Paste")
			(net "GND")
		)
		(pad "4" smd rect
			(at -0.65024 0.8255 270)
			(size 0.4064 1.2192)
			(layers "F.Cu" "F.Mask" "F.Paste")
			(net "ATTN_LED_DR5_AND")
		)
		(pad "5" smd rect
			(at 0.65024 0.8255 270)
			(size 0.4064 1.2192)
			(layers "F.Cu" "F.Mask" "F.Paste")
			(net "P3V3")
		)
	)
	(footprint ""
		(layer "F.Cu")
		(at 205.867 -456.438)
		(property "Reference" "TP4"
			(at 0 0 0)
			(layer "F.SilkS")
			(hide yes)
			(effects
				(font
					(size 1.27 1.27)
				)
			)
		)
		(property "Value" "TPAD32-GP"
			(at -0.0508 -1.6764 0)
			(unlocked yes)
			(layer "F.Fab")
			(hide yes)
			(effects
				(font
					(size 1.016 1.016)
					(thickness 0.1524)
				)
			)
		)
		(property "Device Type" "TPAD32"
			(at -0.0508 -3.2004 0)
			(unlocked yes)
			(layer "F.Fab")
			(hide yes)
			(effects
				(font
					(size 1.016 1.016)
					(thickness 0.1524)
				)
			)
		)
		(duplicate_pad_numbers_are_jumpers no)
		(fp_poly
			(pts
				(arc
					(start 0.4064 0)
					(mid -0.4064 0)
					(end 0.4064 0)
				)
			)
			(stroke
				(width 0)
				(type default)
			)
			(fill no)
			(layer "F.CrtYd")
		)
		(fp_poly
			(pts
				(arc
					(start 0.7112 0)
					(mid -0.7112 0)
					(end 0.7112 0)
				)
			)
			(stroke
				(width 0)
				(type default)
			)
			(fill no)
			(layer "F.Fab")
		)
		(pad "1" smd circle
			(at 0 0)
			(size 0.8128 0.8128)
			(layers "F.Cu" "F.Mask" "F.Paste")
			(net "I2C_B_TMP2_ALERT")
		)
	)
	(footprint ""
		(layer "F.Cu")
		(at 94.869 -202.184)
		(property "Reference" "R9088"
			(at 0 0 0)
			(layer "F.SilkS")
			(hide yes)
			(effects
				(font
					(size 1.27 1.27)
				)
			)
		)
		(property "Value" "27R2F-GP"
			(at 0.064008 -3.993896 0)
			(unlocked yes)
			(layer "F.Fab")
			(hide yes)
			(effects
				(font
					(size 1.016 1.016)
					(thickness 0.1524)
				)
			)
		)
		(property "Device Type" "R402H16"
			(at 0.064008 -5.517896 0)
			(unlocked yes)
			(layer "F.Fab")
			(hide yes)
			(effects
				(font
					(size 1.016 1.016)
					(thickness 0.1524)
				)
			)
		)
		(duplicate_pad_numbers_are_jumpers no)
		(fp_line
			(start -0.508 -0.9398)
			(end -0.508 0.9398)
			(stroke
				(width 0.1524)
				(type default)
			)
			(layer "F.SilkS")
		)
		(fp_line
			(start 0.508 -0.9398)
			(end -0.508 -0.9398)
			(stroke
				(width 0.1524)
				(type default)
			)
			(layer "F.SilkS")
		)
		(fp_rect
			(start -0.508 0.9398)
			(end 0.508 -0.9398)
			(stroke
				(width 0)
				(type default)
			)
			(fill no)
			(layer "F.CrtYd")
		)
		(fp_rect
			(start -0.508 0.9398)
			(end 0.508 -0.9398)
			(stroke
				(width 0)
				(type default)
			)
			(fill no)
			(layer "F.Fab")
		)
		(pad "1" smd custom
			(at 0 -0.4445)
			(size 0.1397 0.1397)
			(layers "F.Cu" "F.Mask" "F.Paste")
			(net "PE_CLK_100M_DR4_2_R_N")
			(options
				(clearance outline)
				(anchor circle)
			)
			(primitives
				(gr_poly
					(pts
						(arc
							(start -0.1778 -0.2794)
							(mid -0.249642 -0.249642)
							(end -0.2794 -0.1778)
						)
						(arc
							(start -0.2794 0.1778)
							(mid -0.249642 0.249642)
							(end -0.1778 0.2794)
						)
						(arc
							(start 0.1778 0.2794)
							(mid 0.249642 0.249642)
							(end 0.2794 0.1778)
						)
						(arc
							(start 0.2794 -0.1778)
							(mid 0.249642 -0.249642)
							(end 0.1778 -0.2794)
						)
					)
					(width 0)
					(fill yes)
				)
			)
		)
		(pad "2" smd custom
			(at 0 0.4445)
			(size 0.1397 0.1397)
			(layers "F.Cu" "F.Mask" "F.Paste")
			(net "PE_CLK100M_DR4_2_N")
			(options
				(clearance outline)
				(anchor circle)
			)
			(primitives
				(gr_poly
					(pts
						(arc
							(start -0.1778 -0.2794)
							(mid -0.249642 -0.249642)
							(end -0.2794 -0.1778)
						)
						(arc
							(start -0.2794 0.1778)
							(mid -0.249642 0.249642)
							(end -0.1778 0.2794)
						)
						(arc
							(start 0.1778 0.2794)
							(mid 0.249642 0.249642)
							(end 0.2794 0.1778)
						)
						(arc
							(start 0.2794 -0.1778)
							(mid 0.249642 -0.249642)
							(end 0.1778 -0.2794)
						)
					)
					(width 0)
					(fill yes)
				)
			)
		)
	)
	(footprint ""
		(layer "F.Cu")
		(at 29.6418 -396.6464 -90)
		(property "Reference" "U15"
			(at 0 0 270)
			(layer "F.SilkS")
			(hide yes)
			(effects
				(font
					(size 1.27 1.27)
				)
			)
		)
		(property "Value" "P2003EVG-GP"
			(at 0 -11.1252 270)
			(unlocked yes)
			(layer "F.Fab")
			(hide yes)
			(effects
				(font
					(size 1.016 1.016)
					(thickness 0.1524)
				)
			)
		)
		(property "Device Type" "SOIC8H79"
			(at 0 -12.6492 270)
			(unlocked yes)
			(layer "F.Fab")
			(hide yes)
			(effects
				(font
					(size 1.016 1.016)
					(thickness 0.1524)
				)
			)
		)
		(duplicate_pad_numbers_are_jumpers no)
		(fp_line
			(start -2.6162 3.429)
			(end -2.6162 1.4732)
			(stroke
				(width 0.4064)
				(type default)
			)
			(layer "F.SilkS")
		)
		(fp_line
			(start -2.7432 1.4224)
			(end 2.1336 1.4224)
			(stroke
				(width 0.1524)
				(type default)
			)
			(layer "F.SilkS")
		)
		(fp_line
			(start 2.1336 1.4224)
			(end 2.1336 -1.4224)
			(stroke
				(width 0.1524)
				(type default)
			)
			(layer "F.SilkS")
		)
		(fp_line
			(start -2.2352 0)
			(end -2.7432 0.508)
			(stroke
				(width 0.1524)
				(type default)
			)
			(layer "F.SilkS")
		)
		(fp_line
			(start -2.7432 -0.508)
			(end -2.2352 0)
			(stroke
				(width 0.1524)
				(type default)
			)
			(layer "F.SilkS")
		)
		(fp_line
			(start -2.7432 -1.4224)
			(end -2.7432 1.4224)
			(stroke
				(width 0.1524)
				(type default)
			)
			(layer "F.SilkS")
		)
		(fp_line
			(start 2.1336 -1.4224)
			(end -2.7432 -1.4224)
			(stroke
				(width 0.1524)
				(type default)
			)
			(layer "F.SilkS")
		)
		(fp_poly
			(pts
				(xy 2.2098 -1.4224) (xy 2.2098 1.4224) (xy -2.2225 1.4224) (xy -2.2225 -1.4224)
			)
			(stroke
				(width 0)
				(type default)
			)
			(fill yes)
			(layer "F.SilkS")
		)
		(fp_rect
			(start -2.4511 2.9972)
			(end 2.4511 -2.9972)
			(stroke
				(width 0)
				(type default)
			)
			(fill no)
			(layer "F.CrtYd")
		)
		(fp_poly
			(pts
				(xy -2.8194 3.6322) (xy -2.8194 -3.6322) (xy 2.8194 -3.6322) (xy 2.8194 -2.2987) (xy 2.4511 -2.2987)
				(xy 2.4511 -2.9972) (xy -2.4511 -2.9972) (xy -2.4511 2.9972) (xy 2.4511 2.9972) (xy 2.4511 -2.286)
				(xy 2.8194 -2.286) (xy 2.8194 3.6322)
			)
			(stroke
				(width 0)
				(type default)
			)
			(fill no)
			(layer "F.CrtYd")
		)
		(fp_rect
			(start -2.8194 3.6322)
			(end 2.8194 -3.6322)
			(stroke
				(width 0)
				(type default)
			)
			(fill no)
			(layer "F.Fab")
		)
		(pad "1" smd rect
			(at -1.905 2.54 270)
			(size 0.635 1.651)
			(layers "F.Cu" "F.Mask" "F.Paste")
			(net "P12V")
		)
		(pad "2" smd rect
			(at -0.635 2.54 270)
			(size 0.635 1.651)
			(layers "F.Cu" "F.Mask" "F.Paste")
			(net "P12V")
		)
		(pad "3" smd rect
			(at 0.635 2.54 270)
			(size 0.635 1.651)
			(layers "F.Cu" "F.Mask" "F.Paste")
			(net "P12V")
		)
		(pad "4" smd rect
			(at 1.905 2.54 270)
			(size 0.635 1.651)
			(layers "F.Cu" "F.Mask" "F.Paste")
			(net "SW_SSD6_N")
		)
		(pad "5" smd rect
			(at 1.905 -2.54 270)
			(size 0.635 1.651)
			(layers "F.Cu" "F.Mask" "F.Paste")
			(net "P12V_SSD6")
		)
		(pad "6" smd rect
			(at 0.635 -2.54 270)
			(size 0.635 1.651)
			(layers "F.Cu" "F.Mask" "F.Paste")
			(net "P12V_SSD6")
		)
		(pad "7" smd rect
			(at -0.635 -2.54 270)
			(size 0.635 1.651)
			(layers "F.Cu" "F.Mask" "F.Paste")
			(net "P12V_SSD6")
		)
		(pad "8" smd rect
			(at -1.905 -2.54 270)
			(size 0.635 1.651)
			(layers "F.Cu" "F.Mask" "F.Paste")
			(net "P12V_SSD6")
		)
	)
	(footprint ""
		(layer "F.Cu")
		(at 2.999994 -193.142108 90)
		(property "Reference" "J19"
			(at 0 0 90)
			(layer "F.SilkS")
			(hide yes)
			(effects
				(font
					(size 1.27 1.27)
				)
			)
		)
		(property "Value" "PCISLT200-5-GP-U"
			(at -48.7045 -6.7818 90)
			(unlocked yes)
			(layer "F.Fab")
			(hide yes)
			(effects
				(font
					(size 1.016 1.016)
					(thickness 0.1524)
				)
			)
		)
		(property "Device Type" "G639F200221431HR-U"
			(at -48.7045 -8.3058 90)
			(unlocked yes)
			(layer "F.Fab")
			(hide yes)
			(effects
				(font
					(size 1.016 1.016)
					(thickness 0.1524)
				)
			)
		)
		(duplicate_pad_numbers_are_jumpers no)
		(fp_line
			(start 51.7525 -2.999994)
			(end 51.7525 2.9464)
			(stroke
				(width 0.1524)
				(type default)
			)
			(layer "F.SilkS")
		)
		(fp_line
			(start -3.199892 -2.999994)
			(end 51.7525 -2.999994)
			(stroke
				(width 0.1524)
				(type default)
			)
			(layer "F.SilkS")
		)
		(fp_line
			(start -6.400038 -2.999994)
			(end -51.7525 -2.999994)
			(stroke
				(width 0.1524)
				(type default)
			)
			(layer "F.SilkS")
		)
		(fp_line
			(start -51.7525 -2.999994)
			(end -51.7525 2.9464)
			(stroke
				(width 0.1524)
				(type default)
			)
			(layer "F.SilkS")
		)
		(fp_line
			(start -3.700018 -2.499868)
			(end -3.199892 -2.999994)
			(stroke
				(width 0.1524)
				(type default)
			)
			(layer "F.SilkS")
		)
		(fp_line
			(start -5.899912 -2.499868)
			(end -6.400038 -2.999994)
			(stroke
				(width 0.1524)
				(type default)
			)
			(layer "F.SilkS")
		)
		(fp_line
			(start -3.700018 1.400048)
			(end -3.700018 -2.499868)
			(stroke
				(width 0.1524)
				(type default)
			)
			(layer "F.SilkS")
		)
		(fp_line
			(start -5.899912 1.400048)
			(end -5.899912 -2.499868)
			(stroke
				(width 0.1524)
				(type default)
			)
			(layer "F.SilkS")
		)
		(fp_line
			(start 51.7525 2.9464)
			(end -51.7525 2.9464)
			(stroke
				(width 0.1524)
				(type default)
			)
			(layer "F.SilkS")
		)
		(fp_arc
			(start -3.700018 1.400048)
			(mid -4.800092 2.500122)
			(end -5.900166 1.400048)
			(stroke
				(width 0.1524)
				(type default)
			)
			(layer "F.SilkS")
		)
		(fp_poly
			(pts
				(xy -51.4985 2.6924) (xy -51.4985 -5.3086) (xy -46.6979 -5.3086) (xy -46.6979 -18.796) (xy -41.6941 -18.796)
				(xy -41.6941 -10.795) (xy 41.6941 -10.795) (xy 41.6941 -18.796) (xy 46.6979 -18.796) (xy 46.6979 -5.3086)
				(xy 51.4985 -5.3086) (xy 51.4985 2.6924)
			)
			(stroke
				(width 0)
				(type default)
			)
			(fill no)
			(layer "B.CrtYd")
		)
		(fp_poly
			(pts
				(xy -52.0065 3.2004) (xy -52.0065 -5.8166) (xy -47.2059 -5.8166) (xy -47.2059 -19.304) (xy -41.1861 -19.304)
				(xy -41.1861 -11.303) (xy 41.1861 -11.303) (xy 41.1861 -19.304) (xy 47.2059 -19.304) (xy 47.2059 -5.8166)
				(xy 52.0065 -5.8166) (xy 52.0065 -0.00635) (xy 51.4985 -0.00635) (xy 51.4985 -5.3086) (xy 46.6979 -5.3086)
				(xy 46.6979 -18.796) (xy 41.6941 -18.796) (xy 41.6941 -10.795) (xy -41.6941 -10.795) (xy -41.6941 -18.796)
				(xy -46.6979 -18.796) (xy -46.6979 -5.3086) (xy -51.4985 -5.3086) (xy -51.4985 2.6924) (xy 51.4985 2.6924)
				(xy 51.4985 0.00635) (xy 52.0065 0.00635) (xy 52.0065 3.2004)
			)
			(stroke
				(width 0)
				(type default)
			)
			(fill no)
			(layer "B.CrtYd")
		)
		(fp_poly
			(pts
				(xy -51.4985 2.6924) (xy -51.4985 -5.3086) (xy -46.6979 -5.3086) (xy -46.6979 -18.796) (xy -41.6941 -18.796)
				(xy -41.6941 -10.795) (xy 41.6941 -10.795) (xy 41.6941 -18.796) (xy 46.6979 -18.796) (xy 46.6979 -5.3086)
				(xy 51.4985 -5.3086) (xy 51.4985 2.6924)
			)
			(stroke
				(width 0)
				(type default)
			)
			(fill no)
			(layer "F.CrtYd")
		)
		(fp_poly
			(pts
				(xy -52.0065 3.2004) (xy -52.0065 -5.8166) (xy -47.2059 -5.8166) (xy -47.2059 -19.304) (xy -41.1861 -19.304)
				(xy -41.1861 -11.303) (xy 41.1861 -11.303) (xy 41.1861 -19.304) (xy 47.2059 -19.304) (xy 47.2059 -5.8166)
				(xy 52.0065 -5.8166) (xy 52.0065 -0.00635) (xy 51.4985 -0.00635) (xy 51.4985 -5.3086) (xy 46.6979 -5.3086)
				(xy 46.6979 -18.796) (xy 41.6941 -18.796) (xy 41.6941 -10.795) (xy -41.6941 -10.795) (xy -41.6941 -18.796)
				(xy -46.6979 -18.796) (xy -46.6979 -5.3086) (xy -51.4985 -5.3086) (xy -51.4985 2.6924) (xy 51.4985 2.6924)
				(xy 51.4985 0.00635) (xy 52.0065 0.00635) (xy 52.0065 3.2004)
			)
			(stroke
				(width 0)
				(type default)
			)
			(fill no)
			(layer "F.CrtYd")
		)
		(fp_poly
			(pts
				(xy -52.0065 3.2004) (xy -52.0065 -5.8166) (xy -47.2059 -5.8166) (xy -47.2059 -19.304) (xy -41.1861 -19.304)
				(xy -41.1861 -11.303) (xy 41.1861 -11.303) (xy 41.1861 -19.304) (xy 47.2059 -19.304) (xy 47.2059 -5.8166)
				(xy 52.0065 -5.8166) (xy 52.0065 3.2004)
			)
			(stroke
				(width 0)
				(type default)
			)
			(fill no)
			(layer "B.Fab")
		)
		(fp_poly
			(pts
				(xy -52.0065 3.2004) (xy -52.0065 -5.8166) (xy -47.2059 -5.8166) (xy -47.2059 -19.304) (xy -41.1861 -19.304)
				(xy -41.1861 -11.303) (xy 41.1861 -11.303) (xy 41.1861 -19.304) (xy 47.2059 -19.304) (xy 47.2059 -5.8166)
				(xy 52.0065 -5.8166) (xy 52.0065 3.2004)
			)
			(stroke
				(width 0)
				(type default)
			)
			(fill no)
			(layer "F.Fab")
		)
		(fp_text user "Slit"
			(at 10.2108 -6.5786 90)
			(unlocked yes)
			(layer "F.SilkS")
			(effects
				(font
					(size 1.016 1.016)
					(thickness 0.1524)
				)
				(justify left)
			)
		)
		(pad "" np_thru_hole circle
			(at -47.999904 0 90)
			(size 0.254 0.254)
			(drill 2.2098)
			(layers "*.Cu" "*.Mask")
			(clearance 1.3335)
			(thermal_gap 1.3335)
		)
		(pad "" np_thru_hole circle
			(at 47.999904 0 90)
			(size 0.254 0.254)
			(drill 2.2098)
			(layers "*.Cu" "*.Mask")
			(clearance 1.3335)
			(thermal_gap 1.3335)
		)
		(pad "A1" smd rect
			(at -41.20007 -0.750062 90)
			(size 0.508 2.4892)
			(layers "F.Cu" "F.Mask" "F.Paste")
			(net "GND")
		)
		(pad "A2" smd rect
			(at -40.39997 -0.750062 90)
			(size 0.508 2.4892)
			(layers "F.Cu" "F.Mask" "F.Paste")
			(net "PE_TX1_DR14_N")
		)
		(pad "A3" smd rect
			(at -39.600124 -0.750062 90)
			(size 0.508 2.4892)
			(layers "F.Cu" "F.Mask" "F.Paste")
			(net "PE_TX1_DR14_P")
		)
		(pad "A4" smd rect
			(at -38.800024 -0.750062 90)
			(size 0.508 2.4892)
			(layers "F.Cu" "F.Mask" "F.Paste")
			(net "GND")
		)
		(pad "A5" smd rect
			(at -37.999924 -0.750062 90)
			(size 0.508 2.4892)
			(layers "F.Cu" "F.Mask" "F.Paste")
			(net "GND")
		)
		(pad "A6" smd rect
			(at -37.200078 -0.750062 90)
			(size 0.508 2.4892)
			(layers "F.Cu" "F.Mask" "F.Paste")
			(net "PE_TX2_DR14_N")
		)
		(pad "A7" smd rect
			(at -36.399978 -0.750062 90)
			(size 0.508 2.4892)
			(layers "F.Cu" "F.Mask" "F.Paste")
			(net "PE_TX2_DR14_P")
		)
		(pad "A8" smd rect
			(at -35.599878 -0.750062 90)
			(size 0.508 2.4892)
			(layers "F.Cu" "F.Mask" "F.Paste")
			(net "GND")
		)
		(pad "A9" smd rect
			(at -34.800032 -0.750062 90)
			(size 0.508 2.4892)
			(layers "F.Cu" "F.Mask" "F.Paste")
			(net "GND")
		)
		(pad "A10" smd rect
			(at -33.999932 -0.750062 90)
			(size 0.508 2.4892)
			(layers "F.Cu" "F.Mask" "F.Paste")
			(net "PE_TX3_DR14_N")
		)
		(pad "A11" smd rect
			(at -33.200086 -0.750062 90)
			(size 0.508 2.4892)
			(layers "F.Cu" "F.Mask" "F.Paste")
			(net "PE_TX3_DR14_P")
		)
		(pad "A12" smd rect
			(at -32.399986 -0.750062 90)
			(size 0.508 2.4892)
			(layers "F.Cu" "F.Mask" "F.Paste")
			(net "GND")
		)
		(pad "A13" smd rect
			(at -31.599886 -0.750062 90)
			(size 0.508 2.4892)
			(layers "F.Cu" "F.Mask" "F.Paste")
			(net "GND")
		)
		(pad "A14" smd rect
			(at -30.80004 -0.750062 90)
			(size 0.508 2.4892)
			(layers "F.Cu" "F.Mask" "F.Paste")
			(net "PE_TX4_DR14_N")
		)
		(pad "A15" smd rect
			(at -29.99994 -0.750062 90)
			(size 0.508 2.4892)
			(layers "F.Cu" "F.Mask" "F.Paste")
			(net "PE_TX4_DR14_P")
		)
		(pad "A16" smd rect
			(at -29.200094 -0.750062 90)
			(size 0.508 2.4892)
			(layers "F.Cu" "F.Mask" "F.Paste")
			(net "GND")
		)
		(pad "A17" smd rect
			(at -28.399994 -0.750062 90)
			(size 0.508 2.4892)
			(layers "F.Cu" "F.Mask" "F.Paste")
			(net "SSD14_CLK0_OE_R_N")
		)
		(pad "A18" smd rect
			(at -27.599894 -0.750062 90)
			(size 0.508 2.4892)
			(layers "F.Cu" "F.Mask" "F.Paste")
			(net "SSD9_PWREN")
		)
		(pad "A19" smd rect
			(at -26.800048 -0.750062 90)
			(size 0.508 2.4892)
			(layers "F.Cu" "F.Mask" "F.Paste")
			(net "ATTN_LED_DR9_N")
		)
		(pad "A20" smd rect
			(at -25.999948 -0.750062 90)
			(size 0.508 2.4892)
			(layers "F.Cu" "F.Mask" "F.Paste")
			(net "SSD9_CLK0_OE_R_N")
		)
		(pad "A21" smd rect
			(at -25.200102 -0.750062 90)
			(size 0.508 2.4892)
			(layers "F.Cu" "F.Mask" "F.Paste")
			(net "GND")
		)
		(pad "A22" smd rect
			(at -24.400002 -0.750062 90)
			(size 0.508 2.4892)
			(layers "F.Cu" "F.Mask" "F.Paste")
			(net "PE_TX1_DR13_N")
		)
		(pad "A23" smd rect
			(at -23.599902 -0.750062 90)
			(size 0.508 2.4892)
			(layers "F.Cu" "F.Mask" "F.Paste")
			(net "PE_TX1_DR13_P")
		)
		(pad "A24" smd rect
			(at -22.800056 -0.750062 90)
			(size 0.508 2.4892)
			(layers "F.Cu" "F.Mask" "F.Paste")
			(net "GND")
		)
		(pad "A25" smd rect
			(at -21.999956 -0.750062 90)
			(size 0.508 2.4892)
			(layers "F.Cu" "F.Mask" "F.Paste")
			(net "GND")
		)
		(pad "A26" smd rect
			(at -21.20011 -0.750062 90)
			(size 0.508 2.4892)
			(layers "F.Cu" "F.Mask" "F.Paste")
			(net "PE_TX2_DR13_N")
		)
		(pad "A27" smd rect
			(at -20.40001 -0.750062 90)
			(size 0.508 2.4892)
			(layers "F.Cu" "F.Mask" "F.Paste")
			(net "PE_TX2_DR13_P")
		)
		(pad "A28" smd rect
			(at -19.59991 -0.750062 90)
			(size 0.508 2.4892)
			(layers "F.Cu" "F.Mask" "F.Paste")
			(net "GND")
		)
		(pad "A29" smd rect
			(at -18.800064 -0.750062 90)
			(size 0.508 2.4892)
			(layers "F.Cu" "F.Mask" "F.Paste")
			(net "GND")
		)
		(pad "A30" smd rect
			(at -17.999964 -0.750062 90)
			(size 0.508 2.4892)
			(layers "F.Cu" "F.Mask" "F.Paste")
			(net "PE_TX3_DR13_N")
		)
		(pad "A31" smd rect
			(at -17.200118 -0.750062 90)
			(size 0.508 2.4892)
			(layers "F.Cu" "F.Mask" "F.Paste")
			(net "PE_TX3_DR13_P")
		)
		(pad "A32" smd rect
			(at -16.400018 -0.750062 90)
			(size 0.508 2.4892)
			(layers "F.Cu" "F.Mask" "F.Paste")
			(net "GND")
		)
		(pad "A33" smd rect
			(at -15.599918 -0.750062 90)
			(size 0.508 2.4892)
			(layers "F.Cu" "F.Mask" "F.Paste")
			(net "GND")
		)
		(pad "A34" smd rect
			(at -14.800072 -0.750062 90)
			(size 0.508 2.4892)
			(layers "F.Cu" "F.Mask" "F.Paste")
			(net "PE_TX4_DR13_N")
		)
		(pad "A35" smd rect
			(at -13.999972 -0.750062 90)
			(size 0.508 2.4892)
			(layers "F.Cu" "F.Mask" "F.Paste")
			(net "PE_TX4_DR13_P")
		)
		(pad "A36" smd rect
			(at -13.200126 -0.750062 90)
			(size 0.508 2.4892)
			(layers "F.Cu" "F.Mask" "F.Paste")
			(net "GND")
		)
		(pad "A37" smd rect
			(at -12.400026 -0.750062 90)
			(size 0.508 2.4892)
			(layers "F.Cu" "F.Mask" "F.Paste")
			(net "GND")
		)
		(pad "A38" smd rect
			(at -11.599926 -0.750062 90)
			(size 0.508 2.4892)
			(layers "F.Cu" "F.Mask" "F.Paste")
			(net "PE_TX1_DR9_N")
		)
		(pad "A39" smd rect
			(at -10.80008 -0.750062 90)
			(size 0.508 2.4892)
			(layers "F.Cu" "F.Mask" "F.Paste")
			(net "PE_TX1_DR9_P")
		)
		(pad "A40" smd rect
			(at -9.99998 -0.750062 90)
			(size 0.508 2.4892)
			(layers "F.Cu" "F.Mask" "F.Paste")
			(net "GND")
		)
		(pad "A41" smd rect
			(at -9.19988 -0.750062 90)
			(size 0.508 2.4892)
			(layers "F.Cu" "F.Mask" "F.Paste")
			(net "GND")
		)
		(pad "A42" smd rect
			(at -8.400034 -0.750062 90)
			(size 0.508 2.4892)
			(layers "F.Cu" "F.Mask" "F.Paste")
			(net "PE_TX2_DR9_N")
		)
		(pad "A43" smd rect
			(at -7.599934 -0.750062 90)
			(size 0.508 2.4892)
			(layers "F.Cu" "F.Mask" "F.Paste")
			(net "PE_TX2_DR9_P")
		)
		(pad "A44" smd rect
			(at -6.800088 -0.750062 90)
			(size 0.508 2.4892)
			(layers "F.Cu" "F.Mask" "F.Paste")
			(net "GND")
		)
		(pad "A45" smd rect
			(at -2.800096 -0.750062 90)
			(size 0.508 2.4892)
			(layers "F.Cu" "F.Mask" "F.Paste")
			(net "SSD9_PERST_N")
		)
		(pad "A46" smd rect
			(at -1.999996 -0.750062 90)
			(size 0.508 2.4892)
			(layers "F.Cu" "F.Mask" "F.Paste")
			(net "SSD13_PERST_N")
		)
		(pad "A47" smd rect
			(at -1.199896 -0.750062 90)
			(size 0.508 2.4892)
			(layers "F.Cu" "F.Mask" "F.Paste")
			(net "GND")
		)
		(pad "A48" smd rect
			(at -0.40005 -0.750062 90)
			(size 0.508 2.4892)
			(layers "F.Cu" "F.Mask" "F.Paste")
			(net "PE_TX3_DR9_N")
		)
		(pad "A49" smd rect
			(at 0.40005 -0.750062 90)
			(size 0.508 2.4892)
			(layers "F.Cu" "F.Mask" "F.Paste")
			(net "PE_TX3_DR9_P")
		)
		(pad "A50" smd rect
			(at 1.199896 -0.750062 90)
			(size 0.508 2.4892)
			(layers "F.Cu" "F.Mask" "F.Paste")
			(net "GND")
		)
		(pad "A51" smd rect
			(at 1.999996 -0.750062 90)
			(size 0.508 2.4892)
			(layers "F.Cu" "F.Mask" "F.Paste")
			(net "GND")
		)
		(pad "A52" smd rect
			(at 2.800096 -0.750062 90)
			(size 0.508 2.4892)
			(layers "F.Cu" "F.Mask" "F.Paste")
			(net "PE_TX4_DR9_N")
		)
		(pad "A53" smd rect
			(at 3.599942 -0.750062 90)
			(size 0.508 2.4892)
			(layers "F.Cu" "F.Mask" "F.Paste")
			(net "PE_TX4_DR9_P")
		)
		(pad "A54" smd rect
			(at 4.400042 -0.750062 90)
			(size 0.508 2.4892)
			(layers "F.Cu" "F.Mask" "F.Paste")
			(net "GND")
		)
		(pad "A55" smd rect
			(at 5.199888 -0.750062 90)
			(size 0.508 2.4892)
			(layers "F.Cu" "F.Mask" "F.Paste")
			(net "SSD13_PWREN")
		)
		(pad "A56" smd rect
			(at 5.999988 -0.750062 90)
			(size 0.508 2.4892)
			(layers "F.Cu" "F.Mask" "F.Paste")
			(net "ATTN_LED_DR13_N")
		)
		(pad "A57" smd rect
			(at 6.800088 -0.750062 90)
			(size 0.508 2.4892)
			(layers "F.Cu" "F.Mask" "F.Paste")
			(net "SSD13_CLK0_OE_R_N")
		)
		(pad "A58" smd rect
			(at 7.599934 -0.750062 90)
			(size 0.508 2.4892)
			(layers "F.Cu" "F.Mask" "F.Paste")
			(net "GND")
		)
		(pad "A59" smd rect
			(at 8.400034 -0.750062 90)
			(size 0.508 2.4892)
			(layers "F.Cu" "F.Mask" "F.Paste")
			(net "PE_TX1_DR8_N")
		)
		(pad "A60" smd rect
			(at 9.19988 -0.750062 90)
			(size 0.508 2.4892)
			(layers "F.Cu" "F.Mask" "F.Paste")
			(net "PE_TX1_DR8_P")
		)
		(pad "A61" smd rect
			(at 9.99998 -0.750062 90)
			(size 0.508 2.4892)
			(layers "F.Cu" "F.Mask" "F.Paste")
			(net "GND")
		)
		(pad "A62" smd rect
			(at 10.80008 -0.750062 90)
			(size 0.508 2.4892)
			(layers "F.Cu" "F.Mask" "F.Paste")
			(net "GND")
		)
		(pad "A63" smd rect
			(at 11.599926 -0.750062 90)
			(size 0.508 2.4892)
			(layers "F.Cu" "F.Mask" "F.Paste")
			(net "PE_TX2_DR8_N")
		)
		(pad "A64" smd rect
			(at 12.400026 -0.750062 90)
			(size 0.508 2.4892)
			(layers "F.Cu" "F.Mask" "F.Paste")
			(net "PE_TX2_DR8_P")
		)
		(pad "A65" smd rect
			(at 13.200126 -0.750062 90)
			(size 0.508 2.4892)
			(layers "F.Cu" "F.Mask" "F.Paste")
			(net "GND")
		)
		(pad "A66" smd rect
			(at 13.999972 -0.750062 90)
			(size 0.508 2.4892)
			(layers "F.Cu" "F.Mask" "F.Paste")
			(net "GND")
		)
		(pad "A67" smd rect
			(at 14.800072 -0.750062 90)
			(size 0.508 2.4892)
			(layers "F.Cu" "F.Mask" "F.Paste")
			(net "PE_TX3_DR8_N")
		)
		(pad "A68" smd rect
			(at 15.599918 -0.750062 90)
			(size 0.508 2.4892)
			(layers "F.Cu" "F.Mask" "F.Paste")
			(net "PE_TX3_DR8_P")
		)
		(pad "A69" smd rect
			(at 16.400018 -0.750062 90)
			(size 0.508 2.4892)
			(layers "F.Cu" "F.Mask" "F.Paste")
			(net "GND")
		)
		(pad "A70" smd rect
			(at 17.200118 -0.750062 90)
			(size 0.508 2.4892)
			(layers "F.Cu" "F.Mask" "F.Paste")
			(net "GND")
		)
		(pad "A71" smd rect
			(at 17.999964 -0.750062 90)
			(size 0.508 2.4892)
			(layers "F.Cu" "F.Mask" "F.Paste")
			(net "PE_TX4_DR8_N")
		)
		(pad "A72" smd rect
			(at 18.800064 -0.750062 90)
			(size 0.508 2.4892)
			(layers "F.Cu" "F.Mask" "F.Paste")
			(net "PE_TX4_DR8_P")
		)
		(pad "A73" smd rect
			(at 19.59991 -0.750062 90)
			(size 0.508 2.4892)
			(layers "F.Cu" "F.Mask" "F.Paste")
			(net "GND")
		)
		(pad "A74" smd rect
			(at 20.40001 -0.750062 90)
			(size 0.508 2.4892)
			(layers "F.Cu" "F.Mask" "F.Paste")
			(net "GND")
		)
		(pad "A75" smd rect
			(at 21.20011 -0.750062 90)
			(size 0.508 2.4892)
			(layers "F.Cu" "F.Mask" "F.Paste")
			(net "PE_TX1_DR12_N")
		)
		(pad "A76" smd rect
			(at 21.999956 -0.750062 90)
			(size 0.508 2.4892)
			(layers "F.Cu" "F.Mask" "F.Paste")
			(net "PE_TX1_DR12_P")
		)
		(pad "A77" smd rect
			(at 22.800056 -0.750062 90)
			(size 0.508 2.4892)
			(layers "F.Cu" "F.Mask" "F.Paste")
			(net "GND")
		)
		(pad "A78" smd rect
			(at 23.599902 -0.750062 90)
			(size 0.508 2.4892)
			(layers "F.Cu" "F.Mask" "F.Paste")
			(net "GND")
		)
		(pad "A79" smd rect
			(at 24.400002 -0.750062 90)
			(size 0.508 2.4892)
			(layers "F.Cu" "F.Mask" "F.Paste")
			(net "PE_TX2_DR12_N")
		)
		(pad "A80" smd rect
			(at 25.200102 -0.750062 90)
			(size 0.508 2.4892)
			(layers "F.Cu" "F.Mask" "F.Paste")
			(net "PE_TX2_DR12_P")
		)
		(pad "A81" smd rect
			(at 25.999948 -0.750062 90)
			(size 0.508 2.4892)
			(layers "F.Cu" "F.Mask" "F.Paste")
			(net "GND")
		)
		(pad "A82" smd rect
			(at 26.800048 -0.750062 90)
			(size 0.508 2.4892)
			(layers "F.Cu" "F.Mask" "F.Paste")
			(net "GND")
		)
		(pad "A83" smd rect
			(at 27.599894 -0.750062 90)
			(size 0.508 2.4892)
			(layers "F.Cu" "F.Mask" "F.Paste")
			(net "PE_TX3_DR12_N")
		)
		(pad "A84" smd rect
			(at 28.399994 -0.750062 90)
			(size 0.508 2.4892)
			(layers "F.Cu" "F.Mask" "F.Paste")
			(net "PE_TX3_DR12_P")
		)
		(pad "A85" smd rect
			(at 29.200094 -0.750062 90)
			(size 0.508 2.4892)
			(layers "F.Cu" "F.Mask" "F.Paste")
			(net "GND")
		)
		(pad "A86" smd rect
			(at 29.99994 -0.750062 90)
			(size 0.508 2.4892)
			(layers "F.Cu" "F.Mask" "F.Paste")
			(net "GND")
		)
		(pad "A87" smd rect
			(at 30.80004 -0.750062 90)
			(size 0.508 2.4892)
			(layers "F.Cu" "F.Mask" "F.Paste")
			(net "PE_TX4_DR12_N")
		)
		(pad "A88" smd rect
			(at 31.599886 -0.750062 90)
			(size 0.508 2.4892)
			(layers "F.Cu" "F.Mask" "F.Paste")
			(net "PE_TX4_DR12_P")
		)
		(pad "A89" smd rect
			(at 32.399986 -0.750062 90)
			(size 0.508 2.4892)
			(layers "F.Cu" "F.Mask" "F.Paste")
			(net "GND")
		)
		(pad "A90" smd rect
			(at 33.200086 -0.750062 90)
			(size 0.508 2.4892)
			(layers "F.Cu" "F.Mask" "F.Paste")
			(net "GND")
		)
		(pad "A91" smd rect
			(at 33.999932 -0.750062 90)
			(size 0.508 2.4892)
			(layers "F.Cu" "F.Mask" "F.Paste")
			(net "PE_TX1_DR4_N")
		)
		(pad "A92" smd rect
			(at 34.800032 -0.750062 90)
			(size 0.508 2.4892)
			(layers "F.Cu" "F.Mask" "F.Paste")
			(net "PE_TX1_DR4_P")
		)
		(pad "A93" smd rect
			(at 35.599878 -0.750062 90)
			(size 0.508 2.4892)
			(layers "F.Cu" "F.Mask" "F.Paste")
			(net "GND")
		)
		(pad "A94" smd rect
			(at 36.399978 -0.750062 90)
			(size 0.508 2.4892)
			(layers "F.Cu" "F.Mask" "F.Paste")
			(net "GND")
		)
		(pad "A95" smd rect
			(at 37.200078 -0.750062 90)
			(size 0.508 2.4892)
			(layers "F.Cu" "F.Mask" "F.Paste")
			(net "PE_TX2_DR4_N")
		)
		(pad "A96" smd rect
			(at 37.999924 -0.750062 90)
			(size 0.508 2.4892)
			(layers "F.Cu" "F.Mask" "F.Paste")
			(net "PE_TX2_DR4_P")
		)
		(pad "A97" smd rect
			(at 38.800024 -0.750062 90)
			(size 0.508 2.4892)
			(layers "F.Cu" "F.Mask" "F.Paste")
			(net "GND")
		)
		(pad "A98" smd rect
			(at 39.600124 -0.750062 90)
			(size 0.508 2.4892)
			(layers "F.Cu" "F.Mask" "F.Paste")
			(net "TRAY_ID_R")
		)
		(pad "A99" smd rect
			(at 40.39997 -0.750062 90)
			(size 0.508 2.4892)
			(layers "F.Cu" "F.Mask" "F.Paste")
			(net "SD_LATCH_RELEASE_R")
		)
		(pad "A100" smd rect
			(at 41.20007 -0.750062 90)
			(size 0.508 2.4892)
			(layers "F.Cu" "F.Mask" "F.Paste")
			(net "PCIE_MATED#_B")
		)
		(pad "B1" smd rect
			(at -41.20007 -1.131062 90)
			(size 0.508 2.4892)
			(drill
				(offset 0 0.381)
			)
			(layers "F.Cu" "F.Mask" "F.Paste")
			(net "ATTN_LED_DR14_N")
		)
		(pad "B2" smd rect
			(at -40.39997 -1.131062 90)
			(size 0.508 2.4892)
			(drill
				(offset 0 0.381)
			)
			(layers "F.Cu" "F.Mask" "F.Paste")
			(net "SSD14_PWREN")
		)
		(pad "B3" smd rect
			(at -39.600124 -1.131062 90)
			(size 0.508 2.4892)
			(drill
				(offset 0 0.381)
			)
			(layers "F.Cu" "F.Mask" "F.Paste")
			(net "GND")
		)
		(pad "B4" smd rect
			(at -38.800024 -1.131062 90)
			(size 0.508 2.4892)
			(drill
				(offset 0 0.381)
			)
			(layers "F.Cu" "F.Mask" "F.Paste")
			(net "PE_RX1_DR14_N")
		)
		(pad "B5" smd rect
			(at -37.999924 -1.131062 90)
			(size 0.508 2.4892)
			(drill
				(offset 0 0.381)
			)
			(layers "F.Cu" "F.Mask" "F.Paste")
			(net "PE_RX1_DR14_P")
		)
		(pad "B6" smd rect
			(at -37.200078 -1.131062 90)
			(size 0.508 2.4892)
			(drill
				(offset 0 0.381)
			)
			(layers "F.Cu" "F.Mask" "F.Paste")
			(net "GND")
		)
		(pad "B7" smd rect
			(at -36.399978 -1.131062 90)
			(size 0.508 2.4892)
			(drill
				(offset 0 0.381)
			)
			(layers "F.Cu" "F.Mask" "F.Paste")
			(net "GND")
		)
		(pad "B8" smd rect
			(at -35.599878 -1.131062 90)
			(size 0.508 2.4892)
			(drill
				(offset 0 0.381)
			)
			(layers "F.Cu" "F.Mask" "F.Paste")
			(net "PE_RX2_DR14_N")
		)
		(pad "B9" smd rect
			(at -34.800032 -1.131062 90)
			(size 0.508 2.4892)
			(drill
				(offset 0 0.381)
			)
			(layers "F.Cu" "F.Mask" "F.Paste")
			(net "PE_RX2_DR14_P")
		)
		(pad "B10" smd rect
			(at -33.999932 -1.131062 90)
			(size 0.508 2.4892)
			(drill
				(offset 0 0.381)
			)
			(layers "F.Cu" "F.Mask" "F.Paste")
			(net "GND")
		)
		(pad "B11" smd rect
			(at -33.200086 -1.131062 90)
			(size 0.508 2.4892)
			(drill
				(offset 0 0.381)
			)
			(layers "F.Cu" "F.Mask" "F.Paste")
			(net "GND")
		)
		(pad "B12" smd rect
			(at -32.399986 -1.131062 90)
			(size 0.508 2.4892)
			(drill
				(offset 0 0.381)
			)
			(layers "F.Cu" "F.Mask" "F.Paste")
			(net "PE_RX3_DR14_N")
		)
		(pad "B13" smd rect
			(at -31.599886 -1.131062 90)
			(size 0.508 2.4892)
			(drill
				(offset 0 0.381)
			)
			(layers "F.Cu" "F.Mask" "F.Paste")
			(net "PE_RX3_DR14_P")
		)
		(pad "B14" smd rect
			(at -30.80004 -1.131062 90)
			(size 0.508 2.4892)
			(drill
				(offset 0 0.381)
			)
			(layers "F.Cu" "F.Mask" "F.Paste")
			(net "GND")
		)
		(pad "B15" smd rect
			(at -29.99994 -1.131062 90)
			(size 0.508 2.4892)
			(drill
				(offset 0 0.381)
			)
			(layers "F.Cu" "F.Mask" "F.Paste")
			(net "GND")
		)
		(pad "B16" smd rect
			(at -29.200094 -1.131062 90)
			(size 0.508 2.4892)
			(drill
				(offset 0 0.381)
			)
			(layers "F.Cu" "F.Mask" "F.Paste")
			(net "PE_RX4_DR14_N")
		)
		(pad "B17" smd rect
			(at -28.399994 -1.131062 90)
			(size 0.508 2.4892)
			(drill
				(offset 0 0.381)
			)
			(layers "F.Cu" "F.Mask" "F.Paste")
			(net "PE_RX4_DR14_P")
		)
		(pad "B18" smd rect
			(at -27.599894 -1.131062 90)
			(size 0.508 2.4892)
			(drill
				(offset 0 0.381)
			)
			(layers "F.Cu" "F.Mask" "F.Paste")
			(net "GND")
		)
		(pad "B19" smd rect
			(at -26.800048 -1.131062 90)
			(size 0.508 2.4892)
			(drill
				(offset 0 0.381)
			)
			(layers "F.Cu" "F.Mask" "F.Paste")
			(net "GND")
		)
		(pad "B20" smd rect
			(at -25.999948 -1.131062 90)
			(size 0.508 2.4892)
			(drill
				(offset 0 0.381)
			)
			(layers "F.Cu" "F.Mask" "F.Paste")
			(net "PE_RX1_DR13_N")
		)
		(pad "B21" smd rect
			(at -25.200102 -1.131062 90)
			(size 0.508 2.4892)
			(drill
				(offset 0 0.381)
			)
			(layers "F.Cu" "F.Mask" "F.Paste")
			(net "PE_RX1_DR13_P")
		)
		(pad "B22" smd rect
			(at -24.400002 -1.131062 90)
			(size 0.508 2.4892)
			(drill
				(offset 0 0.381)
			)
			(layers "F.Cu" "F.Mask" "F.Paste")
			(net "GND")
		)
		(pad "B23" smd rect
			(at -23.599902 -1.131062 90)
			(size 0.508 2.4892)
			(drill
				(offset 0 0.381)
			)
			(layers "F.Cu" "F.Mask" "F.Paste")
			(net "GND")
		)
		(pad "B24" smd rect
			(at -22.800056 -1.131062 90)
			(size 0.508 2.4892)
			(drill
				(offset 0 0.381)
			)
			(layers "F.Cu" "F.Mask" "F.Paste")
			(net "PE_RX2_DR13_N")
		)
		(pad "B25" smd rect
			(at -21.999956 -1.131062 90)
			(size 0.508 2.4892)
			(drill
				(offset 0 0.381)
			)
			(layers "F.Cu" "F.Mask" "F.Paste")
			(net "PE_RX2_DR13_P")
		)
		(pad "B26" smd rect
			(at -21.20011 -1.131062 90)
			(size 0.508 2.4892)
			(drill
				(offset 0 0.381)
			)
			(layers "F.Cu" "F.Mask" "F.Paste")
			(net "GND")
		)
		(pad "B27" smd rect
			(at -20.40001 -1.131062 90)
			(size 0.508 2.4892)
			(drill
				(offset 0 0.381)
			)
			(layers "F.Cu" "F.Mask" "F.Paste")
			(net "GND")
		)
		(pad "B28" smd rect
			(at -19.59991 -1.131062 90)
			(size 0.508 2.4892)
			(drill
				(offset 0 0.381)
			)
			(layers "F.Cu" "F.Mask" "F.Paste")
			(net "PE_RX3_DR13_N")
		)
		(pad "B29" smd rect
			(at -18.800064 -1.131062 90)
			(size 0.508 2.4892)
			(drill
				(offset 0 0.381)
			)
			(layers "F.Cu" "F.Mask" "F.Paste")
			(net "PE_RX3_DR13_P")
		)
		(pad "B30" smd rect
			(at -17.999964 -1.131062 90)
			(size 0.508 2.4892)
			(drill
				(offset 0 0.381)
			)
			(layers "F.Cu" "F.Mask" "F.Paste")
			(net "GND")
		)
		(pad "B31" smd rect
			(at -17.200118 -1.131062 90)
			(size 0.508 2.4892)
			(drill
				(offset 0 0.381)
			)
			(layers "F.Cu" "F.Mask" "F.Paste")
			(net "GND")
		)
		(pad "B32" smd rect
			(at -16.400018 -1.131062 90)
			(size 0.508 2.4892)
			(drill
				(offset 0 0.381)
			)
			(layers "F.Cu" "F.Mask" "F.Paste")
			(net "PE_RX4_DR13_N")
		)
		(pad "B33" smd rect
			(at -15.599918 -1.131062 90)
			(size 0.508 2.4892)
			(drill
				(offset 0 0.381)
			)
			(layers "F.Cu" "F.Mask" "F.Paste")
			(net "PE_RX4_DR13_P")
		)
		(pad "B34" smd rect
			(at -14.800072 -1.131062 90)
			(size 0.508 2.4892)
			(drill
				(offset 0 0.381)
			)
			(layers "F.Cu" "F.Mask" "F.Paste")
			(net "GND")
		)
		(pad "B35" smd rect
			(at -13.999972 -1.131062 90)
			(size 0.508 2.4892)
			(drill
				(offset 0 0.381)
			)
			(layers "F.Cu" "F.Mask" "F.Paste")
			(net "GND")
		)
		(pad "B36" smd rect
			(at -13.200126 -1.131062 90)
			(size 0.508 2.4892)
			(drill
				(offset 0 0.381)
			)
			(layers "F.Cu" "F.Mask" "F.Paste")
			(net "PE_RX1_DR9_N")
		)
		(pad "B37" smd rect
			(at -12.400026 -1.131062 90)
			(size 0.508 2.4892)
			(drill
				(offset 0 0.381)
			)
			(layers "F.Cu" "F.Mask" "F.Paste")
			(net "PE_RX1_DR9_P")
		)
		(pad "B38" smd rect
			(at -11.599926 -1.131062 90)
			(size 0.508 2.4892)
			(drill
				(offset 0 0.381)
			)
			(layers "F.Cu" "F.Mask" "F.Paste")
			(net "GND")
		)
		(pad "B39" smd rect
			(at -10.80008 -1.131062 90)
			(size 0.508 2.4892)
			(drill
				(offset 0 0.381)
			)
			(layers "F.Cu" "F.Mask" "F.Paste")
			(net "GND")
		)
		(pad "B40" smd rect
			(at -9.99998 -1.131062 90)
			(size 0.508 2.4892)
			(drill
				(offset 0 0.381)
			)
			(layers "F.Cu" "F.Mask" "F.Paste")
			(net "PE_RX2_DR9_N")
		)
		(pad "B41" smd rect
			(at -9.19988 -1.131062 90)
			(size 0.508 2.4892)
			(drill
				(offset 0 0.381)
			)
			(layers "F.Cu" "F.Mask" "F.Paste")
			(net "PE_RX2_DR9_P")
		)
		(pad "B42" smd rect
			(at -8.400034 -1.131062 90)
			(size 0.508 2.4892)
			(drill
				(offset 0 0.381)
			)
			(layers "F.Cu" "F.Mask" "F.Paste")
			(net "GND")
		)
		(pad "B43" smd rect
			(at -7.599934 -1.131062 90)
			(size 0.508 2.4892)
			(drill
				(offset 0 0.381)
			)
			(layers "F.Cu" "F.Mask" "F.Paste")
			(net "SSD14_PERST_N")
		)
		(pad "B44" smd rect
			(at -6.800088 -1.131062 90)
			(size 0.508 2.4892)
			(drill
				(offset 0 0.381)
			)
			(layers "F.Cu" "F.Mask" "F.Paste")
			(net "SSD4_PERST_N")
		)
		(pad "B45" smd rect
			(at -2.800096 -1.131062 90)
			(size 0.508 2.4892)
			(drill
				(offset 0 0.381)
			)
			(layers "F.Cu" "F.Mask" "F.Paste")
			(net "GND")
		)
		(pad "B46" smd rect
			(at -1.999996 -1.131062 90)
			(size 0.508 2.4892)
			(drill
				(offset 0 0.381)
			)
			(layers "F.Cu" "F.Mask" "F.Paste")
			(net "PE_RX3_DR9_N")
		)
		(pad "B47" smd rect
			(at -1.199896 -1.131062 90)
			(size 0.508 2.4892)
			(drill
				(offset 0 0.381)
			)
			(layers "F.Cu" "F.Mask" "F.Paste")
			(net "PE_RX3_DR9_P")
		)
		(pad "B48" smd rect
			(at -0.40005 -1.131062 90)
			(size 0.508 2.4892)
			(drill
				(offset 0 0.381)
			)
			(layers "F.Cu" "F.Mask" "F.Paste")
			(net "GND")
		)
		(pad "B49" smd rect
			(at 0.40005 -1.131062 90)
			(size 0.508 2.4892)
			(drill
				(offset 0 0.381)
			)
			(layers "F.Cu" "F.Mask" "F.Paste")
			(net "GND")
		)
		(pad "B50" smd rect
			(at 1.199896 -1.131062 90)
			(size 0.508 2.4892)
			(drill
				(offset 0 0.381)
			)
			(layers "F.Cu" "F.Mask" "F.Paste")
			(net "PE_RX4_DR9_N")
		)
		(pad "B51" smd rect
			(at 1.999996 -1.131062 90)
			(size 0.508 2.4892)
			(drill
				(offset 0 0.381)
			)
			(layers "F.Cu" "F.Mask" "F.Paste")
			(net "PE_RX4_DR9_P")
		)
		(pad "B52" smd rect
			(at 2.800096 -1.131062 90)
			(size 0.508 2.4892)
			(drill
				(offset 0 0.381)
			)
			(layers "F.Cu" "F.Mask" "F.Paste")
			(net "GND")
		)
		(pad "B53" smd rect
			(at 3.599942 -1.131062 90)
			(size 0.508 2.4892)
			(drill
				(offset 0 0.381)
			)
			(layers "F.Cu" "F.Mask" "F.Paste")
			(net "SSD4_CLK0_OE_R_N")
		)
		(pad "B54" smd rect
			(at 4.400042 -1.131062 90)
			(size 0.508 2.4892)
			(drill
				(offset 0 0.381)
			)
			(layers "F.Cu" "F.Mask" "F.Paste")
			(net "ATTN_LED_DR4_N")
		)
		(pad "B55" smd rect
			(at 5.199888 -1.131062 90)
			(size 0.508 2.4892)
			(drill
				(offset 0 0.381)
			)
			(layers "F.Cu" "F.Mask" "F.Paste")
			(net "SSD4_PWREN")
		)
		(pad "B56" smd rect
			(at 5.999988 -1.131062 90)
			(size 0.508 2.4892)
			(drill
				(offset 0 0.381)
			)
			(layers "F.Cu" "F.Mask" "F.Paste")
			(net "GND")
		)
		(pad "B57" smd rect
			(at 6.800088 -1.131062 90)
			(size 0.508 2.4892)
			(drill
				(offset 0 0.381)
			)
			(layers "F.Cu" "F.Mask" "F.Paste")
			(net "PE_RX1_DR8_N")
		)
		(pad "B58" smd rect
			(at 7.599934 -1.131062 90)
			(size 0.508 2.4892)
			(drill
				(offset 0 0.381)
			)
			(layers "F.Cu" "F.Mask" "F.Paste")
			(net "PE_RX1_DR8_P")
		)
		(pad "B59" smd rect
			(at 8.400034 -1.131062 90)
			(size 0.508 2.4892)
			(drill
				(offset 0 0.381)
			)
			(layers "F.Cu" "F.Mask" "F.Paste")
			(net "GND")
		)
		(pad "B60" smd rect
			(at 9.19988 -1.131062 90)
			(size 0.508 2.4892)
			(drill
				(offset 0 0.381)
			)
			(layers "F.Cu" "F.Mask" "F.Paste")
			(net "GND")
		)
		(pad "B61" smd rect
			(at 9.99998 -1.131062 90)
			(size 0.508 2.4892)
			(drill
				(offset 0 0.381)
			)
			(layers "F.Cu" "F.Mask" "F.Paste")
			(net "PE_RX2_DR8_N")
		)
		(pad "B62" smd rect
			(at 10.80008 -1.131062 90)
			(size 0.508 2.4892)
			(drill
				(offset 0 0.381)
			)
			(layers "F.Cu" "F.Mask" "F.Paste")
			(net "PE_RX2_DR8_P")
		)
		(pad "B63" smd rect
			(at 11.599926 -1.131062 90)
			(size 0.508 2.4892)
			(drill
				(offset 0 0.381)
			)
			(layers "F.Cu" "F.Mask" "F.Paste")
			(net "GND")
		)
		(pad "B64" smd rect
			(at 12.400026 -1.131062 90)
			(size 0.508 2.4892)
			(drill
				(offset 0 0.381)
			)
			(layers "F.Cu" "F.Mask" "F.Paste")
			(net "GND")
		)
		(pad "B65" smd rect
			(at 13.200126 -1.131062 90)
			(size 0.508 2.4892)
			(drill
				(offset 0 0.381)
			)
			(layers "F.Cu" "F.Mask" "F.Paste")
			(net "PE_RX3_DR8_N")
		)
		(pad "B66" smd rect
			(at 13.999972 -1.131062 90)
			(size 0.508 2.4892)
			(drill
				(offset 0 0.381)
			)
			(layers "F.Cu" "F.Mask" "F.Paste")
			(net "PE_RX3_DR8_P")
		)
		(pad "B67" smd rect
			(at 14.800072 -1.131062 90)
			(size 0.508 2.4892)
			(drill
				(offset 0 0.381)
			)
			(layers "F.Cu" "F.Mask" "F.Paste")
			(net "GND")
		)
		(pad "B68" smd rect
			(at 15.599918 -1.131062 90)
			(size 0.508 2.4892)
			(drill
				(offset 0 0.381)
			)
			(layers "F.Cu" "F.Mask" "F.Paste")
			(net "GND")
		)
		(pad "B69" smd rect
			(at 16.400018 -1.131062 90)
			(size 0.508 2.4892)
			(drill
				(offset 0 0.381)
			)
			(layers "F.Cu" "F.Mask" "F.Paste")
			(net "PE_RX4_DR8_N")
		)
		(pad "B70" smd rect
			(at 17.200118 -1.131062 90)
			(size 0.508 2.4892)
			(drill
				(offset 0 0.381)
			)
			(layers "F.Cu" "F.Mask" "F.Paste")
			(net "PE_RX4_DR8_P")
		)
		(pad "B71" smd rect
			(at 17.999964 -1.131062 90)
			(size 0.508 2.4892)
			(drill
				(offset 0 0.381)
			)
			(layers "F.Cu" "F.Mask" "F.Paste")
			(net "GND")
		)
		(pad "B72" smd rect
			(at 18.800064 -1.131062 90)
			(size 0.508 2.4892)
			(drill
				(offset 0 0.381)
			)
			(layers "F.Cu" "F.Mask" "F.Paste")
			(net "GND")
		)
		(pad "B73" smd rect
			(at 19.59991 -1.131062 90)
			(size 0.508 2.4892)
			(drill
				(offset 0 0.381)
			)
			(layers "F.Cu" "F.Mask" "F.Paste")
			(net "PE_RX1_DR12_N")
		)
		(pad "B74" smd rect
			(at 20.40001 -1.131062 90)
			(size 0.508 2.4892)
			(drill
				(offset 0 0.381)
			)
			(layers "F.Cu" "F.Mask" "F.Paste")
			(net "PE_RX1_DR12_P")
		)
		(pad "B75" smd rect
			(at 21.20011 -1.131062 90)
			(size 0.508 2.4892)
			(drill
				(offset 0 0.381)
			)
			(layers "F.Cu" "F.Mask" "F.Paste")
			(net "GND")
		)
		(pad "B76" smd rect
			(at 21.999956 -1.131062 90)
			(size 0.508 2.4892)
			(drill
				(offset 0 0.381)
			)
			(layers "F.Cu" "F.Mask" "F.Paste")
			(net "GND")
		)
		(pad "B77" smd rect
			(at 22.800056 -1.131062 90)
			(size 0.508 2.4892)
			(drill
				(offset 0 0.381)
			)
			(layers "F.Cu" "F.Mask" "F.Paste")
			(net "PE_RX2_DR12_N")
		)
		(pad "B78" smd rect
			(at 23.599902 -1.131062 90)
			(size 0.508 2.4892)
			(drill
				(offset 0 0.381)
			)
			(layers "F.Cu" "F.Mask" "F.Paste")
			(net "PE_RX2_DR12_P")
		)
		(pad "B79" smd rect
			(at 24.400002 -1.131062 90)
			(size 0.508 2.4892)
			(drill
				(offset 0 0.381)
			)
			(layers "F.Cu" "F.Mask" "F.Paste")
			(net "GND")
		)
		(pad "B80" smd rect
			(at 25.200102 -1.131062 90)
			(size 0.508 2.4892)
			(drill
				(offset 0 0.381)
			)
			(layers "F.Cu" "F.Mask" "F.Paste")
			(net "GND")
		)
		(pad "B81" smd rect
			(at 25.999948 -1.131062 90)
			(size 0.508 2.4892)
			(drill
				(offset 0 0.381)
			)
			(layers "F.Cu" "F.Mask" "F.Paste")
			(net "PE_RX3_DR12_N")
		)
		(pad "B82" smd rect
			(at 26.800048 -1.131062 90)
			(size 0.508 2.4892)
			(drill
				(offset 0 0.381)
			)
			(layers "F.Cu" "F.Mask" "F.Paste")
			(net "PE_RX3_DR12_P")
		)
		(pad "B83" smd rect
			(at 27.599894 -1.131062 90)
			(size 0.508 2.4892)
			(drill
				(offset 0 0.381)
			)
			(layers "F.Cu" "F.Mask" "F.Paste")
			(net "GND")
		)
		(pad "B84" smd rect
			(at 28.399994 -1.131062 90)
			(size 0.508 2.4892)
			(drill
				(offset 0 0.381)
			)
			(layers "F.Cu" "F.Mask" "F.Paste")
			(net "GND")
		)
		(pad "B85" smd rect
			(at 29.200094 -1.131062 90)
			(size 0.508 2.4892)
			(drill
				(offset 0 0.381)
			)
			(layers "F.Cu" "F.Mask" "F.Paste")
			(net "PE_RX4_DR12_N")
		)
		(pad "B86" smd rect
			(at 29.99994 -1.131062 90)
			(size 0.508 2.4892)
			(drill
				(offset 0 0.381)
			)
			(layers "F.Cu" "F.Mask" "F.Paste")
			(net "PE_RX4_DR12_P")
		)
		(pad "B87" smd rect
			(at 30.80004 -1.131062 90)
			(size 0.508 2.4892)
			(drill
				(offset 0 0.381)
			)
			(layers "F.Cu" "F.Mask" "F.Paste")
			(net "GND")
		)
		(pad "B88" smd rect
			(at 31.599886 -1.131062 90)
			(size 0.508 2.4892)
			(drill
				(offset 0 0.381)
			)
			(layers "F.Cu" "F.Mask" "F.Paste")
			(net "SSD8_CLK0_OE_R_N")
		)
		(pad "B89" smd rect
			(at 32.399986 -1.131062 90)
			(size 0.508 2.4892)
			(drill
				(offset 0 0.381)
			)
			(layers "F.Cu" "F.Mask" "F.Paste")
			(net "ATTN_LED_DR8_N")
		)
		(pad "B90" smd rect
			(at 33.200086 -1.131062 90)
			(size 0.508 2.4892)
			(drill
				(offset 0 0.381)
			)
			(layers "F.Cu" "F.Mask" "F.Paste")
			(net "SSD8_PWREN")
		)
		(pad "B91" smd rect
			(at 33.999932 -1.131062 90)
			(size 0.508 2.4892)
			(drill
				(offset 0 0.381)
			)
			(layers "F.Cu" "F.Mask" "F.Paste")
			(net "SSD8_PERST_N")
		)
		(pad "B92" smd rect
			(at 34.800032 -1.131062 90)
			(size 0.508 2.4892)
			(drill
				(offset 0 0.381)
			)
			(layers "F.Cu" "F.Mask" "F.Paste")
			(net "GND")
		)
		(pad "B93" smd rect
			(at 35.599878 -1.131062 90)
			(size 0.508 2.4892)
			(drill
				(offset 0 0.381)
			)
			(layers "F.Cu" "F.Mask" "F.Paste")
			(net "PE_RX1_DR4_N")
		)
		(pad "B94" smd rect
			(at 36.399978 -1.131062 90)
			(size 0.508 2.4892)
			(drill
				(offset 0 0.381)
			)
			(layers "F.Cu" "F.Mask" "F.Paste")
			(net "PE_RX1_DR4_P")
		)
		(pad "B95" smd rect
			(at 37.200078 -1.131062 90)
			(size 0.508 2.4892)
			(drill
				(offset 0 0.381)
			)
			(layers "F.Cu" "F.Mask" "F.Paste")
			(net "GND")
		)
		(pad "B96" smd rect
			(at 37.999924 -1.131062 90)
			(size 0.508 2.4892)
			(drill
				(offset 0 0.381)
			)
			(layers "F.Cu" "F.Mask" "F.Paste")
			(net "GND")
		)
		(pad "B97" smd rect
			(at 38.800024 -1.131062 90)
			(size 0.508 2.4892)
			(drill
				(offset 0 0.381)
			)
			(layers "F.Cu" "F.Mask" "F.Paste")
			(net "PE_RX2_DR4_N")
		)
		(pad "B98" smd rect
			(at 39.600124 -1.131062 90)
			(size 0.508 2.4892)
			(drill
				(offset 0 0.381)
			)
			(layers "F.Cu" "F.Mask" "F.Paste")
			(net "PE_RX2_DR4_P")
		)
		(pad "B99" smd rect
			(at 40.39997 -1.131062 90)
			(size 0.508 2.4892)
			(drill
				(offset 0 0.381)
			)
			(layers "F.Cu" "F.Mask" "F.Paste")
			(net "GND")
		)
		(pad "B100" smd rect
			(at 41.20007 -1.131062 90)
			(size 0.508 2.4892)
			(drill
				(offset 0 0.381)
			)
			(layers "F.Cu" "F.Mask" "F.Paste")
			(net "I2C_MUX_RESET_PEB")
		)
		(zone
			(layers "F.Cu" "B.Cu" "In1.Cu" "In2.Cu" "In3.Cu" "In4.Cu" "In5.Cu" "In6.Cu")
			(hatch none 0.5)
			(connect_pads
				(clearance 0)
			)
			(min_thickness 0.25)
			(keepout
				(tracks not_allowed)
				(vias allowed)
				(pads allowed)
				(copperpour not_allowed)
				(footprints allowed)
			)
			(placement
				(enabled no)
				(sheetname "")
			)
			(fill
				(thermal_gap 0.5)
				(thermal_bridge_width 0.5)
				(island_removal_mode 0)
			)
			(polygon
				(pts
					(arc
						(start 4.409694 -241.142012)
						(mid 1.590294 -241.142012)
						(end 4.409694 -241.142012)
					)
				)
			)
		)
		(zone
			(layers "F.Cu" "B.Cu" "In1.Cu" "In2.Cu" "In3.Cu" "In4.Cu" "In5.Cu" "In6.Cu")
			(hatch none 0.5)
			(connect_pads
				(clearance 0)
			)
			(min_thickness 0.25)
			(keepout
				(tracks not_allowed)
				(vias allowed)
				(pads allowed)
				(copperpour not_allowed)
				(footprints allowed)
			)
			(placement
				(enabled no)
				(sheetname "")
			)
			(fill
				(thermal_gap 0.5)
				(thermal_bridge_width 0.5)
				(island_removal_mode 0)
			)
			(polygon
				(pts
					(arc
						(start 4.409694 -145.142204)
						(mid 1.590294 -145.142204)
						(end 4.409694 -145.142204)
					)
				)
			)
		)
	)
	(footprint ""
		(layer "F.Cu")
		(at 43.2816 -402.7678)
		(property "Reference" "R9251"
			(at 0 0 0)
			(layer "F.SilkS")
			(hide yes)
			(effects
				(font
					(size 1.27 1.27)
				)
			)
		)
		(property "Value" "2R2010F-GP"
			(at 0.0762 -4.5466 0)
			(unlocked yes)
			(layer "F.Fab")
			(hide yes)
			(effects
				(font
					(size 1.016 1.016)
					(thickness 0.1524)
				)
			)
		)
		(property "Device Type" "R2010H26"
			(at 0.0762 -6.1468 0)
			(unlocked yes)
			(layer "F.Fab")
			(hide yes)
			(effects
				(font
					(size 1.016 1.016)
					(thickness 0.1524)
				)
			)
		)
		(duplicate_pad_numbers_are_jumpers no)
		(fp_line
			(start -3.302 -1.651)
			(end -3.302 1.651)
			(stroke
				(width 0.1524)
				(type default)
			)
			(layer "F.SilkS")
		)
		(fp_line
			(start -3.302 1.651)
			(end 3.302 1.651)
			(stroke
				(width 0.1524)
				(type default)
			)
			(layer "F.SilkS")
		)
		(fp_line
			(start 3.302 -1.651)
			(end -3.302 -1.651)
			(stroke
				(width 0.1524)
				(type default)
			)
			(layer "F.SilkS")
		)
		(fp_line
			(start 3.302 1.651)
			(end 3.302 -1.651)
			(stroke
				(width 0.1524)
				(type default)
			)
			(layer "F.SilkS")
		)
		(fp_rect
			(start -3.3782 1.7272)
			(end 3.3782 -1.7272)
			(stroke
				(width 0)
				(type default)
			)
			(fill no)
			(layer "F.CrtYd")
		)
		(fp_poly
			(pts
				(xy 3.3782 -1.7272) (xy -3.3782 -1.7272) (xy -3.3782 1.7272) (xy 3.3782 1.7272)
			)
			(stroke
				(width 0)
				(type default)
			)
			(fill no)
			(layer "F.Fab")
		)
		(pad "1" smd rect
			(at -2.3495 0)
			(size 1.143 2.794)
			(layers "F.Cu" "F.Mask" "F.Paste")
			(net "P12V_SSD6")
		)
		(pad "2" smd rect
			(at 2.3495 0)
			(size 1.143 2.794)
			(layers "F.Cu" "F.Mask" "F.Paste")
			(net "12V_PRECH_SSD6")
		)
	)
	(footprint ""
		(layer "F.Cu")
		(at 93.599 -218.44 180)
		(property "Reference" "C9428"
			(at 0 0 180)
			(layer "F.SilkS")
			(hide yes)
			(effects
				(font
					(size 1.27 1.27)
				)
			)
		)
		(property "Value" "SCD1U16V2KX-3GP"
			(at 1.1811 -2.7051 180)
			(unlocked yes)
			(layer "F.Fab")
			(hide yes)
			(effects
				(font
					(size 1.016 1.016)
					(thickness 0.1524)
				)
			)
		)
		(property "Device Type" "C402H22"
			(at 1.1811 -4.2291 180)
			(unlocked yes)
			(layer "F.Fab")
			(hide yes)
			(effects
				(font
					(size 1.016 1.016)
					(thickness 0.1524)
				)
			)
		)
		(duplicate_pad_numbers_are_jumpers no)
		(fp_rect
			(start -0.4318 0.9525)
			(end 0.4318 -0.9525)
			(stroke
				(width 0)
				(type default)
			)
			(fill no)
			(layer "F.CrtYd")
		)
		(fp_rect
			(start -0.4318 0.9525)
			(end 0.4318 -0.9525)
			(stroke
				(width 0)
				(type default)
			)
			(fill no)
			(layer "F.Fab")
		)
		(pad "1" smd custom
			(at 0 -0.4445 180)
			(size 0.1524 0.1524)
			(layers "F.Cu" "F.Mask" "F.Paste")
			(net "VDD_DIFF_3")
			(options
				(clearance outline)
				(anchor circle)
			)
			(primitives
				(gr_poly
					(pts
						(arc
							(start 0.3048 -0.2032)
							(mid 0.275042 -0.275042)
							(end 0.2032 -0.3048)
						)
						(arc
							(start -0.2032 -0.3048)
							(mid -0.275042 -0.275042)
							(end -0.3048 -0.2032)
						)
						(arc
							(start -0.3048 0.2032)
							(mid -0.275042 0.275042)
							(end -0.2032 0.3048)
						)
						(arc
							(start 0.2032 0.3048)
							(mid 0.275042 0.275042)
							(end 0.3048 0.2032)
						)
					)
					(width 0)
					(fill yes)
				)
			)
		)
		(pad "2" smd custom
			(at 0 0.4445 180)
			(size 0.1524 0.1524)
			(layers "F.Cu" "F.Mask" "F.Paste")
			(net "GND")
			(options
				(clearance outline)
				(anchor circle)
			)
			(primitives
				(gr_poly
					(pts
						(arc
							(start 0.3048 -0.2032)
							(mid 0.275042 -0.275042)
							(end 0.2032 -0.3048)
						)
						(arc
							(start -0.2032 -0.3048)
							(mid -0.275042 -0.275042)
							(end -0.3048 -0.2032)
						)
						(arc
							(start -0.3048 0.2032)
							(mid -0.275042 0.275042)
							(end -0.2032 0.3048)
						)
						(arc
							(start 0.2032 0.3048)
							(mid 0.275042 0.275042)
							(end 0.3048 0.2032)
						)
					)
					(width 0)
					(fill yes)
				)
			)
		)
	)
	(footprint ""
		(layer "F.Cu")
		(at 209.423 -44.704 180)
		(property "Reference" "R329"
			(at 0 0 180)
			(layer "F.SilkS")
			(hide yes)
			(effects
				(font
					(size 1.27 1.27)
				)
			)
		)
		(property "Value" "4K7R2J-2-GP"
			(at 0.064008 -3.993896 180)
			(unlocked yes)
			(layer "F.Fab")
			(hide yes)
			(effects
				(font
					(size 1.016 1.016)
					(thickness 0.1524)
				)
			)
		)
		(property "Device Type" "R402H16"
			(at 0.064008 -5.517896 180)
			(unlocked yes)
			(layer "F.Fab")
			(hide yes)
			(effects
				(font
					(size 1.016 1.016)
					(thickness 0.1524)
				)
			)
		)
		(duplicate_pad_numbers_are_jumpers no)
		(fp_line
			(start 0.508 -0.9398)
			(end -0.508 -0.9398)
			(stroke
				(width 0.1524)
				(type default)
			)
			(layer "F.SilkS")
		)
		(fp_line
			(start -0.508 -0.9398)
			(end -0.508 0.9398)
			(stroke
				(width 0.1524)
				(type default)
			)
			(layer "F.SilkS")
		)
		(fp_rect
			(start -0.508 0.9398)
			(end 0.508 -0.9398)
			(stroke
				(width 0)
				(type default)
			)
			(fill no)
			(layer "F.CrtYd")
		)
		(fp_rect
			(start -0.508 0.9398)
			(end 0.508 -0.9398)
			(stroke
				(width 0)
				(type default)
			)
			(fill no)
			(layer "F.Fab")
		)
		(pad "1" smd custom
			(at 0 -0.4445 180)
			(size 0.1397 0.1397)
			(layers "F.Cu" "F.Mask" "F.Paste")
			(net "P3V3")
			(options
				(clearance outline)
				(anchor circle)
			)
			(primitives
				(gr_poly
					(pts
						(arc
							(start -0.1778 -0.2794)
							(mid -0.249642 -0.249642)
							(end -0.2794 -0.1778)
						)
						(arc
							(start -0.2794 0.1778)
							(mid -0.249642 0.249642)
							(end -0.1778 0.2794)
						)
						(arc
							(start 0.1778 0.2794)
							(mid 0.249642 0.249642)
							(end 0.2794 0.1778)
						)
						(arc
							(start 0.2794 -0.1778)
							(mid 0.249642 -0.249642)
							(end 0.1778 -0.2794)
						)
					)
					(width 0)
					(fill yes)
				)
			)
		)
		(pad "2" smd custom
			(at 0 0.4445 180)
			(size 0.1397 0.1397)
			(layers "F.Cu" "F.Mask" "F.Paste")
			(net "I2C_B_TMP3_A1")
			(options
				(clearance outline)
				(anchor circle)
			)
			(primitives
				(gr_poly
					(pts
						(arc
							(start -0.1778 -0.2794)
							(mid -0.249642 -0.249642)
							(end -0.2794 -0.1778)
						)
						(arc
							(start -0.2794 0.1778)
							(mid -0.249642 0.249642)
							(end -0.1778 0.2794)
						)
						(arc
							(start 0.1778 0.2794)
							(mid 0.249642 0.249642)
							(end 0.2794 0.1778)
						)
						(arc
							(start 0.2794 -0.1778)
							(mid 0.249642 -0.249642)
							(end 0.1778 -0.2794)
						)
					)
					(width 0)
					(fill yes)
				)
			)
		)
	)
	(footprint ""
		(layer "F.Cu")
		(at 220.0148 -292.481)
		(property "Reference" "PC1191"
			(at 0 0 0)
			(layer "F.SilkS")
			(hide yes)
			(effects
				(font
					(size 1.27 1.27)
				)
			)
		)
		(property "Value" "SC22U25V6KX-GP-U"
			(at -2.860802 -5.279644 0)
			(unlocked yes)
			(layer "F.Fab")
			(hide yes)
			(effects
				(font
					(size 1.016 1.016)
					(thickness 0.1524)
				)
			)
		)
		(property "Device Type" "C1206-TO0D3H75"
			(at -2.860802 -6.803644 0)
			(unlocked yes)
			(layer "F.Fab")
			(hide yes)
			(effects
				(font
					(size 1.016 1.016)
					(thickness 0.1524)
				)
			)
		)
		(duplicate_pad_numbers_are_jumpers no)
		(fp_line
			(start -1.3081 -2.3749)
			(end 1.3081 -2.3749)
			(stroke
				(width 0.1524)
				(type default)
			)
			(layer "F.SilkS")
		)
		(fp_line
			(start -1.3081 2.3749)
			(end -1.3081 -2.3749)
			(stroke
				(width 0.1524)
				(type default)
			)
			(layer "F.SilkS")
		)
		(fp_line
			(start 1.3081 -2.3749)
			(end 1.3081 2.3749)
			(stroke
				(width 0.1524)
				(type default)
			)
			(layer "F.SilkS")
		)
		(fp_line
			(start 1.3081 2.3749)
			(end -1.3081 2.3749)
			(stroke
				(width 0.1524)
				(type default)
			)
			(layer "F.SilkS")
		)
		(fp_rect
			(start -0.8001 1.6002)
			(end 0.8001 -1.6002)
			(stroke
				(width 0)
				(type default)
			)
			(fill no)
			(layer "F.CrtYd")
		)
		(fp_poly
			(pts
				(xy -1.5621 2.4511) (xy -1.5621 1.6002) (xy 0.8001 1.6002) (xy 0.8001 -1.6002) (xy -0.8001 -1.6002)
				(xy -0.8001 1.5875) (xy -1.5621 1.5875) (xy -1.5621 -2.4511) (xy 1.5621 -2.4511) (xy 1.5621 2.4511)
			)
			(stroke
				(width 0)
				(type default)
			)
			(fill no)
			(layer "F.CrtYd")
		)
		(fp_rect
			(start -1.5621 2.4511)
			(end 1.5621 -2.4511)
			(stroke
				(width 0)
				(type default)
			)
			(fill no)
			(layer "F.Fab")
		)
		(pad "1" smd rect
			(at 0 -1.392936)
			(size 2.1082 1.4478)
			(layers "F.Cu" "F.Mask" "F.Paste")
			(net "P12V_SSD2")
		)
		(pad "2" smd rect
			(at 0 1.392936)
			(size 2.1082 1.4478)
			(layers "F.Cu" "F.Mask" "F.Paste")
			(net "GND")
		)
	)
	(footprint ""
		(layer "F.Cu")
		(at 34.7218 -400.558 180)
		(property "Reference" "PC1242"
			(at 0 0 180)
			(layer "F.SilkS")
			(hide yes)
			(effects
				(font
					(size 1.27 1.27)
				)
			)
		)
		(property "Value" "SCD1U50V3KX-GP"
			(at 0 -2.8194 180)
			(unlocked yes)
			(layer "F.Fab")
			(hide yes)
			(effects
				(font
					(size 1.016 1.016)
					(thickness 0.1524)
				)
			)
		)
		(property "Device Type" "C603H36"
			(at 0 -4.3434 180)
			(unlocked yes)
			(layer "F.Fab")
			(hide yes)
			(effects
				(font
					(size 1.016 1.016)
					(thickness 0.1524)
				)
			)
		)
		(duplicate_pad_numbers_are_jumpers no)
		(fp_line
			(start 0.508 0)
			(end -0.508 0)
			(stroke
				(width 0.2032)
				(type default)
			)
			(layer "F.SilkS")
		)
		(fp_rect
			(start -0.5842 1.3335)
			(end 0.5842 -1.3335)
			(stroke
				(width 0)
				(type default)
			)
			(fill no)
			(layer "F.CrtYd")
		)
		(fp_rect
			(start -0.5842 1.3335)
			(end 0.5842 -1.3335)
			(stroke
				(width 0)
				(type default)
			)
			(fill no)
			(layer "F.Fab")
		)
		(pad "1" smd custom
			(at 0 -0.762 180)
			(size 0.2159 0.2159)
			(layers "F.Cu" "F.Mask" "F.Paste")
			(net "P12V_SSD6")
			(options
				(clearance outline)
				(anchor circle)
			)
			(primitives
				(gr_poly
					(pts
						(arc
							(start -0.3302 -0.4318)
							(mid -0.402042 -0.402042)
							(end -0.4318 -0.3302)
						)
						(arc
							(start -0.4318 0.3302)
							(mid -0.402042 0.402042)
							(end -0.3302 0.4318)
						)
						(arc
							(start 0.3302 0.4318)
							(mid 0.402042 0.402042)
							(end 0.4318 0.3302)
						)
						(arc
							(start 0.4318 -0.3302)
							(mid 0.402042 -0.402042)
							(end 0.3302 -0.4318)
						)
					)
					(width 0)
					(fill yes)
				)
			)
		)
		(pad "2" smd custom
			(at 0 0.762 180)
			(size 0.2159 0.2159)
			(layers "F.Cu" "F.Mask" "F.Paste")
			(net "GND")
			(options
				(clearance outline)
				(anchor circle)
			)
			(primitives
				(gr_poly
					(pts
						(arc
							(start -0.3302 -0.4318)
							(mid -0.402042 -0.402042)
							(end -0.4318 -0.3302)
						)
						(arc
							(start -0.4318 0.3302)
							(mid -0.402042 0.402042)
							(end -0.3302 0.4318)
						)
						(arc
							(start 0.3302 0.4318)
							(mid 0.402042 0.402042)
							(end 0.4318 0.3302)
						)
						(arc
							(start 0.4318 -0.3302)
							(mid 0.402042 -0.402042)
							(end 0.3302 -0.4318)
						)
					)
					(width 0)
					(fill yes)
				)
			)
		)
	)
	(footprint ""
		(layer "F.Cu")
		(at 91.948 -203.708)
		(property "Reference" "C9429"
			(at 0 0 0)
			(layer "F.SilkS")
			(hide yes)
			(effects
				(font
					(size 1.27 1.27)
				)
			)
		)
		(property "Value" "SCD1U16V2KX-3GP"
			(at 1.1811 -2.7051 0)
			(unlocked yes)
			(layer "F.Fab")
			(hide yes)
			(effects
				(font
					(size 1.016 1.016)
					(thickness 0.1524)
				)
			)
		)
		(property "Device Type" "C402H22"
			(at 1.1811 -4.2291 0)
			(unlocked yes)
			(layer "F.Fab")
			(hide yes)
			(effects
				(font
					(size 1.016 1.016)
					(thickness 0.1524)
				)
			)
		)
		(duplicate_pad_numbers_are_jumpers no)
		(fp_rect
			(start -0.4318 0.9525)
			(end 0.4318 -0.9525)
			(stroke
				(width 0)
				(type default)
			)
			(fill no)
			(layer "F.CrtYd")
		)
		(fp_rect
			(start -0.4318 0.9525)
			(end 0.4318 -0.9525)
			(stroke
				(width 0)
				(type default)
			)
			(fill no)
			(layer "F.Fab")
		)
		(pad "1" smd custom
			(at 0 -0.4445)
			(size 0.1524 0.1524)
			(layers "F.Cu" "F.Mask" "F.Paste")
			(net "VDD_DIFF_3")
			(options
				(clearance outline)
				(anchor circle)
			)
			(primitives
				(gr_poly
					(pts
						(arc
							(start 0.3048 -0.2032)
							(mid 0.275042 -0.275042)
							(end 0.2032 -0.3048)
						)
						(arc
							(start -0.2032 -0.3048)
							(mid -0.275042 -0.275042)
							(end -0.3048 -0.2032)
						)
						(arc
							(start -0.3048 0.2032)
							(mid -0.275042 0.275042)
							(end -0.2032 0.3048)
						)
						(arc
							(start 0.2032 0.3048)
							(mid 0.275042 0.275042)
							(end 0.3048 0.2032)
						)
					)
					(width 0)
					(fill yes)
				)
			)
		)
		(pad "2" smd custom
			(at 0 0.4445)
			(size 0.1524 0.1524)
			(layers "F.Cu" "F.Mask" "F.Paste")
			(net "GND")
			(options
				(clearance outline)
				(anchor circle)
			)
			(primitives
				(gr_poly
					(pts
						(arc
							(start 0.3048 -0.2032)
							(mid 0.275042 -0.275042)
							(end 0.2032 -0.3048)
						)
						(arc
							(start -0.2032 -0.3048)
							(mid -0.275042 -0.275042)
							(end -0.3048 -0.2032)
						)
						(arc
							(start -0.3048 0.2032)
							(mid -0.275042 0.275042)
							(end -0.2032 0.3048)
						)
						(arc
							(start 0.2032 0.3048)
							(mid 0.275042 0.275042)
							(end 0.3048 0.2032)
						)
					)
					(width 0)
					(fill yes)
				)
			)
		)
	)
	(footprint ""
		(layer "F.Cu")
		(at 37.6936 -212.8774)
		(property "Reference" "R580"
			(at 0 0 0)
			(layer "F.SilkS")
			(hide yes)
			(effects
				(font
					(size 1.27 1.27)
				)
			)
		)
		(property "Value" "300KR2F-GP"
			(at 0.064008 -3.993896 0)
			(unlocked yes)
			(layer "F.Fab")
			(hide yes)
			(effects
				(font
					(size 1.016 1.016)
					(thickness 0.1524)
				)
			)
		)
		(property "Device Type" "R402H16"
			(at 0.064008 -5.517896 0)
			(unlocked yes)
			(layer "F.Fab")
			(hide yes)
			(effects
				(font
					(size 1.016 1.016)
					(thickness 0.1524)
				)
			)
		)
		(duplicate_pad_numbers_are_jumpers no)
		(fp_line
			(start -0.508 -0.9398)
			(end -0.508 0.9398)
			(stroke
				(width 0.1524)
				(type default)
			)
			(layer "F.SilkS")
		)
		(fp_line
			(start 0.508 -0.9398)
			(end -0.508 -0.9398)
			(stroke
				(width 0.1524)
				(type default)
			)
			(layer "F.SilkS")
		)
		(fp_rect
			(start -0.508 0.9398)
			(end 0.508 -0.9398)
			(stroke
				(width 0)
				(type default)
			)
			(fill no)
			(layer "F.CrtYd")
		)
		(fp_rect
			(start -0.508 0.9398)
			(end 0.508 -0.9398)
			(stroke
				(width 0)
				(type default)
			)
			(fill no)
			(layer "F.Fab")
		)
		(pad "1" smd custom
			(at 0 -0.4445)
			(size 0.1397 0.1397)
			(layers "F.Cu" "F.Mask" "F.Paste")
			(net "SW_SSD12_N")
			(options
				(clearance outline)
				(anchor circle)
			)
			(primitives
				(gr_poly
					(pts
						(arc
							(start -0.1778 -0.2794)
							(mid -0.249642 -0.249642)
							(end -0.2794 -0.1778)
						)
						(arc
							(start -0.2794 0.1778)
							(mid -0.249642 0.249642)
							(end -0.1778 0.2794)
						)
						(arc
							(start 0.1778 0.2794)
							(mid 0.249642 0.249642)
							(end 0.2794 0.1778)
						)
						(arc
							(start 0.2794 -0.1778)
							(mid 0.249642 -0.249642)
							(end 0.1778 -0.2794)
						)
					)
					(width 0)
					(fill yes)
				)
			)
		)
		(pad "2" smd custom
			(at 0 0.4445)
			(size 0.1397 0.1397)
			(layers "F.Cu" "F.Mask" "F.Paste")
			(net "P12V")
			(options
				(clearance outline)
				(anchor circle)
			)
			(primitives
				(gr_poly
					(pts
						(arc
							(start -0.1778 -0.2794)
							(mid -0.249642 -0.249642)
							(end -0.2794 -0.1778)
						)
						(arc
							(start -0.2794 0.1778)
							(mid -0.249642 0.249642)
							(end -0.1778 0.2794)
						)
						(arc
							(start 0.1778 0.2794)
							(mid 0.249642 0.249642)
							(end 0.2794 0.1778)
						)
						(arc
							(start 0.2794 -0.1778)
							(mid 0.249642 -0.249642)
							(end 0.1778 -0.2794)
						)
					)
					(width 0)
					(fill yes)
				)
			)
		)
	)
	(footprint ""
		(layer "F.Cu")
		(at 77.5208 -305.6255 180)
		(property "Reference" "R9965"
			(at 0 0 180)
			(layer "F.SilkS")
			(hide yes)
			(effects
				(font
					(size 1.27 1.27)
				)
			)
		)
		(property "Value" "56R2F-1-GP"
			(at 0.064008 -3.993896 180)
			(unlocked yes)
			(layer "F.Fab")
			(hide yes)
			(effects
				(font
					(size 1.016 1.016)
					(thickness 0.1524)
				)
			)
		)
		(property "Device Type" "R402H16"
			(at 0.064008 -5.517896 180)
			(unlocked yes)
			(layer "F.Fab")
			(hide yes)
			(effects
				(font
					(size 1.016 1.016)
					(thickness 0.1524)
				)
			)
		)
		(duplicate_pad_numbers_are_jumpers no)
		(fp_line
			(start 0.508 -0.9398)
			(end -0.508 -0.9398)
			(stroke
				(width 0.1524)
				(type default)
			)
			(layer "F.SilkS")
		)
		(fp_line
			(start -0.508 -0.9398)
			(end -0.508 0.9398)
			(stroke
				(width 0.1524)
				(type default)
			)
			(layer "F.SilkS")
		)
		(fp_rect
			(start -0.508 0.9398)
			(end 0.508 -0.9398)
			(stroke
				(width 0)
				(type default)
			)
			(fill no)
			(layer "F.CrtYd")
		)
		(fp_rect
			(start -0.508 0.9398)
			(end 0.508 -0.9398)
			(stroke
				(width 0)
				(type default)
			)
			(fill no)
			(layer "F.Fab")
		)
		(pad "1" smd custom
			(at 0 -0.4445 180)
			(size 0.1397 0.1397)
			(layers "F.Cu" "F.Mask" "F.Paste")
			(net "PE_100M_CLK3_P")
			(options
				(clearance outline)
				(anchor circle)
			)
			(primitives
				(gr_poly
					(pts
						(arc
							(start -0.1778 -0.2794)
							(mid -0.249642 -0.249642)
							(end -0.2794 -0.1778)
						)
						(arc
							(start -0.2794 0.1778)
							(mid -0.249642 0.249642)
							(end -0.1778 0.2794)
						)
						(arc
							(start 0.1778 0.2794)
							(mid 0.249642 0.249642)
							(end 0.2794 0.1778)
						)
						(arc
							(start 0.2794 -0.1778)
							(mid 0.249642 -0.249642)
							(end 0.1778 -0.2794)
						)
					)
					(width 0)
					(fill yes)
				)
			)
		)
		(pad "2" smd custom
			(at 0 0.4445 180)
			(size 0.1397 0.1397)
			(layers "F.Cu" "F.Mask" "F.Paste")
			(net "GND")
			(options
				(clearance outline)
				(anchor circle)
			)
			(primitives
				(gr_poly
					(pts
						(arc
							(start -0.1778 -0.2794)
							(mid -0.249642 -0.249642)
							(end -0.2794 -0.1778)
						)
						(arc
							(start -0.2794 0.1778)
							(mid -0.249642 0.249642)
							(end -0.1778 0.2794)
						)
						(arc
							(start 0.1778 0.2794)
							(mid 0.249642 0.249642)
							(end 0.2794 0.1778)
						)
						(arc
							(start 0.2794 -0.1778)
							(mid 0.249642 -0.249642)
							(end 0.1778 -0.2794)
						)
					)
					(width 0)
					(fill yes)
				)
			)
		)
	)
	(footprint ""
		(layer "F.Cu")
		(at 25.7048 -410.6418 90)
		(property "Reference" "R9844"
			(at 0 0 90)
			(layer "F.SilkS")
			(hide yes)
			(effects
				(font
					(size 1.27 1.27)
				)
			)
		)
		(property "Value" "2K2R5F-GP"
			(at 0 -8.9535 90)
			(unlocked yes)
			(layer "F.Fab")
			(hide yes)
			(effects
				(font
					(size 1.27 1.016)
					(thickness 0.1524)
				)
			)
		)
		(property "Device Type" "R805H24"
			(at 0 -10.6299 90)
			(unlocked yes)
			(layer "F.Fab")
			(hide yes)
			(effects
				(font
					(size 1.27 1.016)
					(thickness 0.1524)
				)
			)
		)
		(duplicate_pad_numbers_are_jumpers no)
		(fp_line
			(start 0.889 -1.7018)
			(end -0.889 -1.7018)
			(stroke
				(width 0.1524)
				(type default)
			)
			(layer "F.SilkS")
		)
		(fp_line
			(start 0.889 -1.7018)
			(end 0.889 -0.381)
			(stroke
				(width 0.1524)
				(type default)
			)
			(layer "F.SilkS")
		)
		(fp_line
			(start -0.889 -1.7018)
			(end -0.889 0.2794)
			(stroke
				(width 0.1524)
				(type default)
			)
			(layer "F.SilkS")
		)
		(fp_line
			(start -0.889 0.0762)
			(end -0.889 1.7018)
			(stroke
				(width 0.1524)
				(type default)
			)
			(layer "F.SilkS")
		)
		(fp_line
			(start 0.889 1.7018)
			(end 0.889 -0.508)
			(stroke
				(width 0.1524)
				(type default)
			)
			(layer "F.SilkS")
		)
		(fp_line
			(start -0.889 1.7018)
			(end 0.889 1.7018)
			(stroke
				(width 0.1524)
				(type default)
			)
			(layer "F.SilkS")
		)
		(fp_poly
			(pts
				(xy 0.9652 -1.778) (xy 0.9652 1.778) (xy -0.9652 1.778) (xy -0.9652 -1.778)
			)
			(stroke
				(width 0)
				(type default)
			)
			(fill no)
			(layer "F.CrtYd")
		)
		(fp_rect
			(start -0.9652 1.778)
			(end 0.9652 -1.778)
			(stroke
				(width 0)
				(type default)
			)
			(fill no)
			(layer "F.Fab")
		)
		(pad "1" smd rect
			(at 0 -0.9652 90)
			(size 1.397 1.143)
			(layers "F.Cu" "F.Mask" "F.Paste")
			(net "P12V_SSD10")
		)
		(pad "2" smd rect
			(at 0 0.9652 90)
			(size 1.397 1.143)
			(layers "F.Cu" "F.Mask" "F.Paste")
			(net "P12V_MOST10_GATE_D")
		)
	)
	(footprint ""
		(layer "F.Cu")
		(at 39.116 -411.734)
		(property "Reference" "R9751"
			(at 0 0 0)
			(layer "F.SilkS")
			(hide yes)
			(effects
				(font
					(size 1.27 1.27)
				)
			)
		)
		(property "Value" "4K7R2J-2-GP"
			(at 0.064008 -3.993896 0)
			(unlocked yes)
			(layer "F.Fab")
			(hide yes)
			(effects
				(font
					(size 1.016 1.016)
					(thickness 0.1524)
				)
			)
		)
		(property "Device Type" "R402H16"
			(at 0.064008 -5.517896 0)
			(unlocked yes)
			(layer "F.Fab")
			(hide yes)
			(effects
				(font
					(size 1.016 1.016)
					(thickness 0.1524)
				)
			)
		)
		(duplicate_pad_numbers_are_jumpers no)
		(fp_line
			(start -0.508 -0.9398)
			(end -0.508 0.9398)
			(stroke
				(width 0.1524)
				(type default)
			)
			(layer "F.SilkS")
		)
		(fp_line
			(start 0.508 -0.9398)
			(end -0.508 -0.9398)
			(stroke
				(width 0.1524)
				(type default)
			)
			(layer "F.SilkS")
		)
		(fp_rect
			(start -0.508 0.9398)
			(end 0.508 -0.9398)
			(stroke
				(width 0)
				(type default)
			)
			(fill no)
			(layer "F.CrtYd")
		)
		(fp_rect
			(start -0.508 0.9398)
			(end 0.508 -0.9398)
			(stroke
				(width 0)
				(type default)
			)
			(fill no)
			(layer "F.Fab")
		)
		(pad "1" smd custom
			(at 0 -0.4445)
			(size 0.1397 0.1397)
			(layers "F.Cu" "F.Mask" "F.Paste")
			(net "P3V3")
			(options
				(clearance outline)
				(anchor circle)
			)
			(primitives
				(gr_poly
					(pts
						(arc
							(start -0.1778 -0.2794)
							(mid -0.249642 -0.249642)
							(end -0.2794 -0.1778)
						)
						(arc
							(start -0.2794 0.1778)
							(mid -0.249642 0.249642)
							(end -0.1778 0.2794)
						)
						(arc
							(start 0.1778 0.2794)
							(mid 0.249642 0.249642)
							(end 0.2794 0.1778)
						)
						(arc
							(start 0.2794 -0.1778)
							(mid 0.249642 -0.249642)
							(end 0.1778 -0.2794)
						)
					)
					(width 0)
					(fill yes)
				)
			)
		)
		(pad "2" smd custom
			(at 0 0.4445)
			(size 0.1397 0.1397)
			(layers "F.Cu" "F.Mask" "F.Paste")
			(net "SSD10_PWREN")
			(options
				(clearance outline)
				(anchor circle)
			)
			(primitives
				(gr_poly
					(pts
						(arc
							(start -0.1778 -0.2794)
							(mid -0.249642 -0.249642)
							(end -0.2794 -0.1778)
						)
						(arc
							(start -0.2794 0.1778)
							(mid -0.249642 0.249642)
							(end -0.1778 0.2794)
						)
						(arc
							(start 0.1778 0.2794)
							(mid 0.249642 0.249642)
							(end 0.2794 0.1778)
						)
						(arc
							(start 0.2794 -0.1778)
							(mid 0.249642 -0.249642)
							(end 0.1778 -0.2794)
						)
					)
					(width 0)
					(fill yes)
				)
			)
		)
	)
	(footprint ""
		(layer "F.Cu")
		(at 37.1856 -35.052)
		(property "Reference" "R9842"
			(at 0 0 0)
			(layer "F.SilkS")
			(hide yes)
			(effects
				(font
					(size 1.27 1.27)
				)
			)
		)
		(property "Value" "0R2J-2-GP"
			(at 0.064008 -3.993896 0)
			(unlocked yes)
			(layer "F.Fab")
			(hide yes)
			(effects
				(font
					(size 1.016 1.016)
					(thickness 0.1524)
				)
			)
		)
		(property "Device Type" "R402H16"
			(at 0.064008 -5.517896 0)
			(unlocked yes)
			(layer "F.Fab")
			(hide yes)
			(effects
				(font
					(size 1.016 1.016)
					(thickness 0.1524)
				)
			)
		)
		(duplicate_pad_numbers_are_jumpers no)
		(fp_line
			(start -0.508 -0.9398)
			(end -0.508 0.9398)
			(stroke
				(width 0.1524)
				(type default)
			)
			(layer "F.SilkS")
		)
		(fp_line
			(start 0.508 -0.9398)
			(end -0.508 -0.9398)
			(stroke
				(width 0.1524)
				(type default)
			)
			(layer "F.SilkS")
		)
		(fp_rect
			(start -0.508 0.9398)
			(end 0.508 -0.9398)
			(stroke
				(width 0)
				(type default)
			)
			(fill no)
			(layer "F.CrtYd")
		)
		(fp_rect
			(start -0.508 0.9398)
			(end 0.508 -0.9398)
			(stroke
				(width 0)
				(type default)
			)
			(fill no)
			(layer "F.Fab")
		)
		(pad "1" smd custom
			(at 0 -0.4445)
			(size 0.1397 0.1397)
			(layers "F.Cu" "F.Mask" "F.Paste")
			(net "ATTN_LED_DR9_R")
			(options
				(clearance outline)
				(anchor circle)
			)
			(primitives
				(gr_poly
					(pts
						(arc
							(start -0.1778 -0.2794)
							(mid -0.249642 -0.249642)
							(end -0.2794 -0.1778)
						)
						(arc
							(start -0.2794 0.1778)
							(mid -0.249642 0.249642)
							(end -0.1778 0.2794)
						)
						(arc
							(start 0.1778 0.2794)
							(mid 0.249642 0.249642)
							(end 0.2794 0.1778)
						)
						(arc
							(start 0.2794 -0.1778)
							(mid 0.249642 -0.249642)
							(end 0.1778 -0.2794)
						)
					)
					(width 0)
					(fill yes)
				)
			)
		)
		(pad "2" smd custom
			(at 0 0.4445)
			(size 0.1397 0.1397)
			(layers "F.Cu" "F.Mask" "F.Paste")
			(net "ATTN_LED_DR9_N")
			(options
				(clearance outline)
				(anchor circle)
			)
			(primitives
				(gr_poly
					(pts
						(arc
							(start -0.1778 -0.2794)
							(mid -0.249642 -0.249642)
							(end -0.2794 -0.1778)
						)
						(arc
							(start -0.2794 0.1778)
							(mid -0.249642 0.249642)
							(end -0.1778 0.2794)
						)
						(arc
							(start 0.1778 0.2794)
							(mid 0.249642 0.249642)
							(end 0.2794 0.1778)
						)
						(arc
							(start 0.2794 -0.1778)
							(mid 0.249642 -0.249642)
							(end 0.1778 -0.2794)
						)
					)
					(width 0)
					(fill yes)
				)
			)
		)
	)
	(footprint ""
		(layer "F.Cu")
		(at 108.966 -308.229)
		(property "Reference" "R9451"
			(at 0 0 0)
			(layer "F.SilkS")
			(hide yes)
			(effects
				(font
					(size 1.27 1.27)
				)
			)
		)
		(property "Value" "4K7R2J-2-GP"
			(at 0.064008 -3.993896 0)
			(unlocked yes)
			(layer "F.Fab")
			(hide yes)
			(effects
				(font
					(size 1.016 1.016)
					(thickness 0.1524)
				)
			)
		)
		(property "Device Type" "R402H16"
			(at 0.064008 -5.517896 0)
			(unlocked yes)
			(layer "F.Fab")
			(hide yes)
			(effects
				(font
					(size 1.016 1.016)
					(thickness 0.1524)
				)
			)
		)
		(duplicate_pad_numbers_are_jumpers no)
		(fp_line
			(start -0.508 -0.9398)
			(end -0.508 0.9398)
			(stroke
				(width 0.1524)
				(type default)
			)
			(layer "F.SilkS")
		)
		(fp_line
			(start 0.508 -0.9398)
			(end -0.508 -0.9398)
			(stroke
				(width 0.1524)
				(type default)
			)
			(layer "F.SilkS")
		)
		(fp_rect
			(start -0.508 0.9398)
			(end 0.508 -0.9398)
			(stroke
				(width 0)
				(type default)
			)
			(fill no)
			(layer "F.CrtYd")
		)
		(fp_rect
			(start -0.508 0.9398)
			(end 0.508 -0.9398)
			(stroke
				(width 0)
				(type default)
			)
			(fill no)
			(layer "F.Fab")
		)
		(pad "1" smd custom
			(at 0 -0.4445)
			(size 0.1397 0.1397)
			(layers "F.Cu" "F.Mask" "F.Paste")
			(net "P3V3")
			(options
				(clearance outline)
				(anchor circle)
			)
			(primitives
				(gr_poly
					(pts
						(arc
							(start -0.1778 -0.2794)
							(mid -0.249642 -0.249642)
							(end -0.2794 -0.1778)
						)
						(arc
							(start -0.2794 0.1778)
							(mid -0.249642 0.249642)
							(end -0.1778 0.2794)
						)
						(arc
							(start 0.1778 0.2794)
							(mid 0.249642 0.249642)
							(end 0.2794 0.1778)
						)
						(arc
							(start 0.2794 -0.1778)
							(mid 0.249642 -0.249642)
							(end 0.1778 -0.2794)
						)
					)
					(width 0)
					(fill yes)
				)
			)
		)
		(pad "2" smd custom
			(at 0 0.4445)
			(size 0.1397 0.1397)
			(layers "F.Cu" "F.Mask" "F.Paste")
			(net "SSD_PRSNT_NET1")
			(options
				(clearance outline)
				(anchor circle)
			)
			(primitives
				(gr_poly
					(pts
						(arc
							(start -0.1778 -0.2794)
							(mid -0.249642 -0.249642)
							(end -0.2794 -0.1778)
						)
						(arc
							(start -0.2794 0.1778)
							(mid -0.249642 0.249642)
							(end -0.1778 0.2794)
						)
						(arc
							(start 0.1778 0.2794)
							(mid 0.249642 0.249642)
							(end 0.2794 0.1778)
						)
						(arc
							(start 0.2794 -0.1778)
							(mid 0.249642 -0.249642)
							(end 0.1778 -0.2794)
						)
					)
					(width 0)
					(fill yes)
				)
			)
		)
	)
	(footprint ""
		(layer "F.Cu")
		(at 19.5834 -469.3666)
		(property "Reference" "SR1141"
			(at 0 0 0)
			(layer "F.SilkS")
			(hide yes)
			(effects
				(font
					(size 1.27 1.27)
				)
			)
		)
		(property "Value" "4K7R2F-GP"
			(at 0.064008 -3.993896 0)
			(unlocked yes)
			(layer "F.Fab")
			(hide yes)
			(effects
				(font
					(size 1.016 1.016)
					(thickness 0.1524)
				)
			)
		)
		(property "Device Type" "R402H16"
			(at 0.064008 -5.517896 0)
			(unlocked yes)
			(layer "F.Fab")
			(hide yes)
			(effects
				(font
					(size 1.016 1.016)
					(thickness 0.1524)
				)
			)
		)
		(duplicate_pad_numbers_are_jumpers no)
		(fp_line
			(start -0.508 -0.9398)
			(end -0.508 0.9398)
			(stroke
				(width 0.1524)
				(type default)
			)
			(layer "F.SilkS")
		)
		(fp_line
			(start 0.508 -0.9398)
			(end -0.508 -0.9398)
			(stroke
				(width 0.1524)
				(type default)
			)
			(layer "F.SilkS")
		)
		(fp_rect
			(start -0.508 0.9398)
			(end 0.508 -0.9398)
			(stroke
				(width 0)
				(type default)
			)
			(fill no)
			(layer "F.CrtYd")
		)
		(fp_rect
			(start -0.508 0.9398)
			(end 0.508 -0.9398)
			(stroke
				(width 0)
				(type default)
			)
			(fill no)
			(layer "F.Fab")
		)
		(pad "1" smd custom
			(at 0 -0.4445)
			(size 0.1397 0.1397)
			(layers "F.Cu" "F.Mask" "F.Paste")
			(net "P3V3")
			(options
				(clearance outline)
				(anchor circle)
			)
			(primitives
				(gr_poly
					(pts
						(arc
							(start -0.1778 -0.2794)
							(mid -0.249642 -0.249642)
							(end -0.2794 -0.1778)
						)
						(arc
							(start -0.2794 0.1778)
							(mid -0.249642 0.249642)
							(end -0.1778 0.2794)
						)
						(arc
							(start 0.1778 0.2794)
							(mid 0.249642 0.249642)
							(end 0.2794 0.1778)
						)
						(arc
							(start 0.2794 -0.1778)
							(mid 0.249642 -0.249642)
							(end 0.1778 -0.2794)
						)
					)
					(width 0)
					(fill yes)
				)
			)
		)
		(pad "2" smd custom
			(at 0 0.4445)
			(size 0.1397 0.1397)
			(layers "F.Cu" "F.Mask" "F.Paste")
			(net "SSD10_CLK0_OE_MOS_N")
			(options
				(clearance outline)
				(anchor circle)
			)
			(primitives
				(gr_poly
					(pts
						(arc
							(start -0.1778 -0.2794)
							(mid -0.249642 -0.249642)
							(end -0.2794 -0.1778)
						)
						(arc
							(start -0.2794 0.1778)
							(mid -0.249642 0.249642)
							(end -0.1778 0.2794)
						)
						(arc
							(start 0.1778 0.2794)
							(mid 0.249642 0.249642)
							(end 0.2794 0.1778)
						)
						(arc
							(start 0.2794 -0.1778)
							(mid 0.249642 -0.249642)
							(end 0.1778 -0.2794)
						)
					)
					(width 0)
					(fill yes)
				)
			)
		)
	)
	(footprint ""
		(layer "F.Cu")
		(at 201.381106 -491.110778)
		(property "Reference" "C382"
			(at 0 0 0)
			(layer "F.SilkS")
			(hide yes)
			(effects
				(font
					(size 1.27 1.27)
				)
			)
		)
		(property "Value" "SCD1U25V2KX-2-GP"
			(at 1.1811 -2.7051 0)
			(unlocked yes)
			(layer "F.Fab")
			(hide yes)
			(effects
				(font
					(size 1.016 1.016)
					(thickness 0.1524)
				)
			)
		)
		(property "Device Type" "C402H22"
			(at 1.1811 -4.2291 0)
			(unlocked yes)
			(layer "F.Fab")
			(hide yes)
			(effects
				(font
					(size 1.016 1.016)
					(thickness 0.1524)
				)
			)
		)
		(duplicate_pad_numbers_are_jumpers no)
		(fp_rect
			(start -0.4318 0.9525)
			(end 0.4318 -0.9525)
			(stroke
				(width 0)
				(type default)
			)
			(fill no)
			(layer "F.CrtYd")
		)
		(fp_rect
			(start -0.4318 0.9525)
			(end 0.4318 -0.9525)
			(stroke
				(width 0)
				(type default)
			)
			(fill no)
			(layer "F.Fab")
		)
		(pad "1" smd custom
			(at 0 -0.4445)
			(size 0.1524 0.1524)
			(layers "F.Cu" "F.Mask" "F.Paste")
			(net "P12V")
			(options
				(clearance outline)
				(anchor circle)
			)
			(primitives
				(gr_poly
					(pts
						(arc
							(start 0.3048 -0.2032)
							(mid 0.275042 -0.275042)
							(end 0.2032 -0.3048)
						)
						(arc
							(start -0.2032 -0.3048)
							(mid -0.275042 -0.275042)
							(end -0.3048 -0.2032)
						)
						(arc
							(start -0.3048 0.2032)
							(mid -0.275042 0.275042)
							(end -0.2032 0.3048)
						)
						(arc
							(start 0.2032 0.3048)
							(mid 0.275042 0.275042)
							(end 0.3048 0.2032)
						)
					)
					(width 0)
					(fill yes)
				)
			)
		)
		(pad "2" smd custom
			(at 0 0.4445)
			(size 0.1524 0.1524)
			(layers "F.Cu" "F.Mask" "F.Paste")
			(net "SW_SSD0_N")
			(options
				(clearance outline)
				(anchor circle)
			)
			(primitives
				(gr_poly
					(pts
						(arc
							(start 0.3048 -0.2032)
							(mid 0.275042 -0.275042)
							(end 0.2032 -0.3048)
						)
						(arc
							(start -0.2032 -0.3048)
							(mid -0.275042 -0.275042)
							(end -0.3048 -0.2032)
						)
						(arc
							(start -0.3048 0.2032)
							(mid -0.275042 0.275042)
							(end -0.2032 0.3048)
						)
						(arc
							(start 0.2032 0.3048)
							(mid 0.275042 0.275042)
							(end 0.3048 0.2032)
						)
					)
					(width 0)
					(fill yes)
				)
			)
		)
	)
	(footprint ""
		(layer "F.Cu")
		(at 39.243 -137.922 180)
		(property "Reference" "R9920"
			(at 0 0 180)
			(layer "F.SilkS")
			(hide yes)
			(effects
				(font
					(size 1.27 1.27)
				)
			)
		)
		(property "Value" "47KR2J-2-GP"
			(at 0.064008 -3.993896 180)
			(unlocked yes)
			(layer "F.Fab")
			(hide yes)
			(effects
				(font
					(size 1.016 1.016)
					(thickness 0.1524)
				)
			)
		)
		(property "Device Type" "R402H16"
			(at 0.064008 -5.517896 180)
			(unlocked yes)
			(layer "F.Fab")
			(hide yes)
			(effects
				(font
					(size 1.016 1.016)
					(thickness 0.1524)
				)
			)
		)
		(duplicate_pad_numbers_are_jumpers no)
		(fp_line
			(start 0.508 -0.9398)
			(end -0.508 -0.9398)
			(stroke
				(width 0.1524)
				(type default)
			)
			(layer "F.SilkS")
		)
		(fp_line
			(start -0.508 -0.9398)
			(end -0.508 0.9398)
			(stroke
				(width 0.1524)
				(type default)
			)
			(layer "F.SilkS")
		)
		(fp_rect
			(start -0.508 0.9398)
			(end 0.508 -0.9398)
			(stroke
				(width 0)
				(type default)
			)
			(fill no)
			(layer "F.CrtYd")
		)
		(fp_rect
			(start -0.508 0.9398)
			(end 0.508 -0.9398)
			(stroke
				(width 0)
				(type default)
			)
			(fill no)
			(layer "F.Fab")
		)
		(pad "1" smd custom
			(at 0 -0.4445 180)
			(size 0.1397 0.1397)
			(layers "F.Cu" "F.Mask" "F.Paste")
			(net "P3V3")
			(options
				(clearance outline)
				(anchor circle)
			)
			(primitives
				(gr_poly
					(pts
						(arc
							(start -0.1778 -0.2794)
							(mid -0.249642 -0.249642)
							(end -0.2794 -0.1778)
						)
						(arc
							(start -0.2794 0.1778)
							(mid -0.249642 0.249642)
							(end -0.1778 0.2794)
						)
						(arc
							(start 0.1778 0.2794)
							(mid 0.249642 0.249642)
							(end 0.2794 0.1778)
						)
						(arc
							(start 0.2794 -0.1778)
							(mid 0.249642 -0.249642)
							(end 0.1778 -0.2794)
						)
					)
					(width 0)
					(fill yes)
				)
			)
		)
		(pad "2" smd custom
			(at 0 0.4445 180)
			(size 0.1397 0.1397)
			(layers "F.Cu" "F.Mask" "F.Paste")
			(net "ATTN_LED_DR8_N")
			(options
				(clearance outline)
				(anchor circle)
			)
			(primitives
				(gr_poly
					(pts
						(arc
							(start -0.1778 -0.2794)
							(mid -0.249642 -0.249642)
							(end -0.2794 -0.1778)
						)
						(arc
							(start -0.2794 0.1778)
							(mid -0.249642 0.249642)
							(end -0.1778 0.2794)
						)
						(arc
							(start 0.1778 0.2794)
							(mid 0.249642 0.249642)
							(end 0.2794 0.1778)
						)
						(arc
							(start 0.2794 -0.1778)
							(mid 0.249642 -0.249642)
							(end 0.1778 -0.2794)
						)
					)
					(width 0)
					(fill yes)
				)
			)
		)
	)
	(footprint ""
		(layer "F.Cu")
		(at 37.2364 -91.5162 180)
		(property "Reference" "PC1197"
			(at 0 0 180)
			(layer "F.SilkS")
			(hide yes)
			(effects
				(font
					(size 1.27 1.27)
				)
			)
		)
		(property "Value" "SCD1U50V3KX-GP"
			(at 0 -2.8194 180)
			(unlocked yes)
			(layer "F.Fab")
			(hide yes)
			(effects
				(font
					(size 1.016 1.016)
					(thickness 0.1524)
				)
			)
		)
		(property "Device Type" "C603H36"
			(at 0 -4.3434 180)
			(unlocked yes)
			(layer "F.Fab")
			(hide yes)
			(effects
				(font
					(size 1.016 1.016)
					(thickness 0.1524)
				)
			)
		)
		(duplicate_pad_numbers_are_jumpers no)
		(fp_line
			(start 0.508 0)
			(end -0.508 0)
			(stroke
				(width 0.2032)
				(type default)
			)
			(layer "F.SilkS")
		)
		(fp_rect
			(start -0.5842 1.3335)
			(end 0.5842 -1.3335)
			(stroke
				(width 0)
				(type default)
			)
			(fill no)
			(layer "F.CrtYd")
		)
		(fp_rect
			(start -0.5842 1.3335)
			(end 0.5842 -1.3335)
			(stroke
				(width 0)
				(type default)
			)
			(fill no)
			(layer "F.Fab")
		)
		(pad "1" smd custom
			(at 0 -0.762 180)
			(size 0.2159 0.2159)
			(layers "F.Cu" "F.Mask" "F.Paste")
			(net "P12V_SSD9")
			(options
				(clearance outline)
				(anchor circle)
			)
			(primitives
				(gr_poly
					(pts
						(arc
							(start -0.3302 -0.4318)
							(mid -0.402042 -0.402042)
							(end -0.4318 -0.3302)
						)
						(arc
							(start -0.4318 0.3302)
							(mid -0.402042 0.402042)
							(end -0.3302 0.4318)
						)
						(arc
							(start 0.3302 0.4318)
							(mid 0.402042 0.402042)
							(end 0.4318 0.3302)
						)
						(arc
							(start 0.4318 -0.3302)
							(mid 0.402042 -0.402042)
							(end 0.3302 -0.4318)
						)
					)
					(width 0)
					(fill yes)
				)
			)
		)
		(pad "2" smd custom
			(at 0 0.762 180)
			(size 0.2159 0.2159)
			(layers "F.Cu" "F.Mask" "F.Paste")
			(net "GND")
			(options
				(clearance outline)
				(anchor circle)
			)
			(primitives
				(gr_poly
					(pts
						(arc
							(start -0.3302 -0.4318)
							(mid -0.402042 -0.402042)
							(end -0.4318 -0.3302)
						)
						(arc
							(start -0.4318 0.3302)
							(mid -0.402042 0.402042)
							(end -0.3302 0.4318)
						)
						(arc
							(start 0.3302 0.4318)
							(mid 0.402042 0.402042)
							(end 0.4318 0.3302)
						)
						(arc
							(start 0.4318 -0.3302)
							(mid 0.402042 -0.402042)
							(end 0.3302 -0.4318)
						)
					)
					(width 0)
					(fill yes)
				)
			)
		)
	)
	(footprint ""
		(layer "F.Cu")
		(at 228.981 -428.752)
		(property "Reference" "PR9083"
			(at 0 0 0)
			(layer "F.SilkS")
			(hide yes)
			(effects
				(font
					(size 1.27 1.27)
				)
			)
		)
		(property "Value" "2D2R3-1-U-GP"
			(at -0.0254 -2.5146 0)
			(unlocked yes)
			(layer "F.Fab")
			(hide yes)
			(effects
				(font
					(size 1.016 1.016)
					(thickness 0.1524)
				)
			)
		)
		(property "Device Type" "R603H22"
			(at -0.0254 -4.0386 0)
			(unlocked yes)
			(layer "F.Fab")
			(hide yes)
			(effects
				(font
					(size 1.016 1.016)
					(thickness 0.1524)
				)
			)
		)
		(duplicate_pad_numbers_are_jumpers no)
		(fp_line
			(start -0.4826 0)
			(end -0.2032 0)
			(stroke
				(width 0.2032)
				(type default)
			)
			(layer "F.SilkS")
		)
		(fp_line
			(start 0.2032 0)
			(end 0.4826 0)
			(stroke
				(width 0.2032)
				(type default)
			)
			(layer "F.SilkS")
		)
		(fp_rect
			(start -0.5842 1.3335)
			(end 0.5842 -1.3335)
			(stroke
				(width 0)
				(type default)
			)
			(fill no)
			(layer "F.CrtYd")
		)
		(fp_rect
			(start -0.5842 1.3335)
			(end 0.5842 -1.3335)
			(stroke
				(width 0)
				(type default)
			)
			(fill no)
			(layer "F.Fab")
		)
		(pad "1" smd custom
			(at 0 -0.762)
			(size 0.2159 0.2159)
			(layers "F.Cu" "F.Mask" "F.Paste")
			(net "P3V3_VCC")
			(options
				(clearance outline)
				(anchor circle)
			)
			(primitives
				(gr_poly
					(pts
						(arc
							(start -0.3302 -0.4318)
							(mid -0.402042 -0.402042)
							(end -0.4318 -0.3302)
						)
						(arc
							(start -0.4318 0.3302)
							(mid -0.402042 0.402042)
							(end -0.3302 0.4318)
						)
						(arc
							(start 0.3302 0.4318)
							(mid 0.402042 0.402042)
							(end 0.4318 0.3302)
						)
						(arc
							(start 0.4318 -0.3302)
							(mid 0.402042 -0.402042)
							(end 0.3302 -0.4318)
						)
					)
					(width 0)
					(fill yes)
				)
			)
		)
		(pad "2" smd custom
			(at 0 0.762)
			(size 0.2159 0.2159)
			(layers "F.Cu" "F.Mask" "F.Paste")
			(net "P12V")
			(options
				(clearance outline)
				(anchor circle)
			)
			(primitives
				(gr_poly
					(pts
						(arc
							(start -0.3302 -0.4318)
							(mid -0.402042 -0.402042)
							(end -0.4318 -0.3302)
						)
						(arc
							(start -0.4318 0.3302)
							(mid -0.402042 0.402042)
							(end -0.3302 0.4318)
						)
						(arc
							(start 0.3302 0.4318)
							(mid 0.402042 0.402042)
							(end 0.4318 0.3302)
						)
						(arc
							(start 0.4318 -0.3302)
							(mid 0.402042 -0.402042)
							(end 0.3302 -0.4318)
						)
					)
					(width 0)
					(fill yes)
				)
			)
		)
	)
	(footprint ""
		(layer "F.Cu")
		(at 98.806 -116.586 90)
		(property "Reference" "R9430"
			(at 0 0 90)
			(layer "F.SilkS")
			(hide yes)
			(effects
				(font
					(size 1.27 1.27)
				)
			)
		)
		(property "Value" "4K7R2J-2-GP"
			(at 0.064008 -3.993896 90)
			(unlocked yes)
			(layer "F.Fab")
			(hide yes)
			(effects
				(font
					(size 1.016 1.016)
					(thickness 0.1524)
				)
			)
		)
		(property "Device Type" "R402H16"
			(at 0.064008 -5.517896 90)
			(unlocked yes)
			(layer "F.Fab")
			(hide yes)
			(effects
				(font
					(size 1.016 1.016)
					(thickness 0.1524)
				)
			)
		)
		(duplicate_pad_numbers_are_jumpers no)
		(fp_line
			(start 0.508 -0.9398)
			(end -0.508 -0.9398)
			(stroke
				(width 0.1524)
				(type default)
			)
			(layer "F.SilkS")
		)
		(fp_line
			(start -0.508 -0.9398)
			(end -0.508 0.9398)
			(stroke
				(width 0.1524)
				(type default)
			)
			(layer "F.SilkS")
		)
		(fp_rect
			(start -0.508 0.9398)
			(end 0.508 -0.9398)
			(stroke
				(width 0)
				(type default)
			)
			(fill no)
			(layer "F.CrtYd")
		)
		(fp_rect
			(start -0.508 0.9398)
			(end 0.508 -0.9398)
			(stroke
				(width 0)
				(type default)
			)
			(fill no)
			(layer "F.Fab")
		)
		(pad "1" smd custom
			(at 0 -0.4445 90)
			(size 0.1397 0.1397)
			(layers "F.Cu" "F.Mask" "F.Paste")
			(net "P3V3")
			(options
				(clearance outline)
				(anchor circle)
			)
			(primitives
				(gr_poly
					(pts
						(arc
							(start -0.1778 -0.2794)
							(mid -0.249642 -0.249642)
							(end -0.2794 -0.1778)
						)
						(arc
							(start -0.2794 0.1778)
							(mid -0.249642 0.249642)
							(end -0.1778 0.2794)
						)
						(arc
							(start 0.1778 0.2794)
							(mid 0.249642 0.249642)
							(end 0.2794 0.1778)
						)
						(arc
							(start 0.2794 -0.1778)
							(mid 0.249642 -0.249642)
							(end 0.1778 -0.2794)
						)
					)
					(width 0)
					(fill yes)
				)
			)
		)
		(pad "2" smd custom
			(at 0 0.4445 90)
			(size 0.1397 0.1397)
			(layers "F.Cu" "F.Mask" "F.Paste")
			(net "SSD_PRSNT_NET8")
			(options
				(clearance outline)
				(anchor circle)
			)
			(primitives
				(gr_poly
					(pts
						(arc
							(start -0.1778 -0.2794)
							(mid -0.249642 -0.249642)
							(end -0.2794 -0.1778)
						)
						(arc
							(start -0.2794 0.1778)
							(mid -0.249642 0.249642)
							(end -0.1778 0.2794)
						)
						(arc
							(start 0.1778 0.2794)
							(mid 0.249642 0.249642)
							(end 0.2794 0.1778)
						)
						(arc
							(start 0.2794 -0.1778)
							(mid 0.249642 -0.249642)
							(end 0.1778 -0.2794)
						)
					)
					(width 0)
					(fill yes)
				)
			)
		)
	)
	(footprint ""
		(layer "F.Cu")
		(at 90.17 -318.643)
		(property "Reference" "R9610"
			(at 0 0 0)
			(layer "F.SilkS")
			(hide yes)
			(effects
				(font
					(size 1.27 1.27)
				)
			)
		)
		(property "Value" "10R2F-L-GP"
			(at 0.064008 -3.993896 0)
			(unlocked yes)
			(layer "F.Fab")
			(hide yes)
			(effects
				(font
					(size 1.016 1.016)
					(thickness 0.1524)
				)
			)
		)
		(property "Device Type" "R402H14"
			(at 0.064008 -5.517896 0)
			(unlocked yes)
			(layer "F.Fab")
			(hide yes)
			(effects
				(font
					(size 1.016 1.016)
					(thickness 0.1524)
				)
			)
		)
		(duplicate_pad_numbers_are_jumpers no)
		(fp_line
			(start -0.508 -0.9398)
			(end -0.508 0.9398)
			(stroke
				(width 0.1524)
				(type default)
			)
			(layer "F.SilkS")
		)
		(fp_line
			(start 0.508 -0.9398)
			(end -0.508 -0.9398)
			(stroke
				(width 0.1524)
				(type default)
			)
			(layer "F.SilkS")
		)
		(fp_rect
			(start -0.508 0.9398)
			(end 0.508 -0.9398)
			(stroke
				(width 0)
				(type default)
			)
			(fill no)
			(layer "F.CrtYd")
		)
		(fp_rect
			(start -0.508 0.9398)
			(end 0.508 -0.9398)
			(stroke
				(width 0)
				(type default)
			)
			(fill no)
			(layer "F.Fab")
		)
		(pad "1" smd custom
			(at 0 -0.4445)
			(size 0.1397 0.1397)
			(layers "F.Cu" "F.Mask" "F.Paste")
			(net "SSD_PRSNT_NET11")
			(options
				(clearance outline)
				(anchor circle)
			)
			(primitives
				(gr_poly
					(pts
						(arc
							(start -0.1778 -0.2794)
							(mid -0.249642 -0.249642)
							(end -0.2794 -0.1778)
						)
						(arc
							(start -0.2794 0.1778)
							(mid -0.249642 0.249642)
							(end -0.1778 0.2794)
						)
						(arc
							(start 0.1778 0.2794)
							(mid 0.249642 0.249642)
							(end 0.2794 0.1778)
						)
						(arc
							(start 0.2794 -0.1778)
							(mid 0.249642 -0.249642)
							(end 0.1778 -0.2794)
						)
					)
					(width 0)
					(fill yes)
				)
			)
		)
		(pad "2" smd custom
			(at 0 0.4445)
			(size 0.1397 0.1397)
			(layers "F.Cu" "F.Mask" "F.Paste")
			(net "SSD_PRSNT11")
			(options
				(clearance outline)
				(anchor circle)
			)
			(primitives
				(gr_poly
					(pts
						(arc
							(start -0.1778 -0.2794)
							(mid -0.249642 -0.249642)
							(end -0.2794 -0.1778)
						)
						(arc
							(start -0.2794 0.1778)
							(mid -0.249642 0.249642)
							(end -0.1778 0.2794)
						)
						(arc
							(start 0.1778 0.2794)
							(mid 0.249642 0.249642)
							(end 0.2794 0.1778)
						)
						(arc
							(start 0.2794 -0.1778)
							(mid 0.249642 -0.249642)
							(end 0.1778 -0.2794)
						)
					)
					(width 0)
					(fill yes)
				)
			)
		)
	)
	(footprint ""
		(layer "F.Cu")
		(at 36.6776 -212.8774 180)
		(property "Reference" "C394"
			(at 0 0 180)
			(layer "F.SilkS")
			(hide yes)
			(effects
				(font
					(size 1.27 1.27)
				)
			)
		)
		(property "Value" "SCD1U25V2KX-2-GP"
			(at 1.1811 -2.7051 180)
			(unlocked yes)
			(layer "F.Fab")
			(hide yes)
			(effects
				(font
					(size 1.016 1.016)
					(thickness 0.1524)
				)
			)
		)
		(property "Device Type" "C402H22"
			(at 1.1811 -4.2291 180)
			(unlocked yes)
			(layer "F.Fab")
			(hide yes)
			(effects
				(font
					(size 1.016 1.016)
					(thickness 0.1524)
				)
			)
		)
		(duplicate_pad_numbers_are_jumpers no)
		(fp_rect
			(start -0.4318 0.9525)
			(end 0.4318 -0.9525)
			(stroke
				(width 0)
				(type default)
			)
			(fill no)
			(layer "F.CrtYd")
		)
		(fp_rect
			(start -0.4318 0.9525)
			(end 0.4318 -0.9525)
			(stroke
				(width 0)
				(type default)
			)
			(fill no)
			(layer "F.Fab")
		)
		(pad "1" smd custom
			(at 0 -0.4445 180)
			(size 0.1524 0.1524)
			(layers "F.Cu" "F.Mask" "F.Paste")
			(net "P12V")
			(options
				(clearance outline)
				(anchor circle)
			)
			(primitives
				(gr_poly
					(pts
						(arc
							(start 0.3048 -0.2032)
							(mid 0.275042 -0.275042)
							(end 0.2032 -0.3048)
						)
						(arc
							(start -0.2032 -0.3048)
							(mid -0.275042 -0.275042)
							(end -0.3048 -0.2032)
						)
						(arc
							(start -0.3048 0.2032)
							(mid -0.275042 0.275042)
							(end -0.2032 0.3048)
						)
						(arc
							(start 0.2032 0.3048)
							(mid 0.275042 0.275042)
							(end 0.3048 0.2032)
						)
					)
					(width 0)
					(fill yes)
				)
			)
		)
		(pad "2" smd custom
			(at 0 0.4445 180)
			(size 0.1524 0.1524)
			(layers "F.Cu" "F.Mask" "F.Paste")
			(net "SW_SSD12_N")
			(options
				(clearance outline)
				(anchor circle)
			)
			(primitives
				(gr_poly
					(pts
						(arc
							(start 0.3048 -0.2032)
							(mid 0.275042 -0.275042)
							(end 0.2032 -0.3048)
						)
						(arc
							(start -0.2032 -0.3048)
							(mid -0.275042 -0.275042)
							(end -0.3048 -0.2032)
						)
						(arc
							(start -0.3048 0.2032)
							(mid -0.275042 0.275042)
							(end -0.2032 0.3048)
						)
						(arc
							(start 0.2032 0.3048)
							(mid 0.275042 0.275042)
							(end 0.3048 0.2032)
						)
					)
					(width 0)
					(fill yes)
				)
			)
		)
	)
	(footprint ""
		(layer "F.Cu")
		(at 209.296 -194.183 180)
		(property "Reference" "Q11"
			(at 0 0 180)
			(layer "F.SilkS")
			(hide yes)
			(effects
				(font
					(size 1.27 1.27)
				)
			)
		)
		(property "Value" "2N7002A-7-GP"
			(at 0.127 -8.9662 180)
			(unlocked yes)
			(layer "F.Fab")
			(hide yes)
			(effects
				(font
					(size 1.016 1.016)
					(thickness 0.1524)
				)
			)
		)
		(property "Device Type" "SOT23DGS2D4H48"
			(at 0.127 -10.4902 180)
			(unlocked yes)
			(layer "F.Fab")
			(hide yes)
			(effects
				(font
					(size 1.016 1.016)
					(thickness 0.1524)
				)
			)
		)
		(duplicate_pad_numbers_are_jumpers no)
		(fp_line
			(start 1.651 1.778)
			(end 1.651 -1.778)
			(stroke
				(width 0.1524)
				(type default)
			)
			(layer "F.SilkS")
		)
		(fp_line
			(start 1.651 -1.778)
			(end -1.651 -1.778)
			(stroke
				(width 0.1524)
				(type default)
			)
			(layer "F.SilkS")
		)
		(fp_line
			(start -1.651 1.778)
			(end 1.651 1.778)
			(stroke
				(width 0.1524)
				(type default)
			)
			(layer "F.SilkS")
		)
		(fp_line
			(start -1.651 -1.778)
			(end -1.651 1.778)
			(stroke
				(width 0.1524)
				(type default)
			)
			(layer "F.SilkS")
		)
		(fp_poly
			(pts
				(xy -1.778 1.8796) (xy -1.778 -1.8796) (xy 1.778 -1.8796) (xy 1.778 1.8796)
			)
			(stroke
				(width 0)
				(type default)
			)
			(fill no)
			(layer "F.CrtYd")
		)
		(fp_poly
			(pts
				(xy -1.778 1.8796) (xy -1.778 -1.8796) (xy 1.778 -1.8796) (xy 1.778 1.8796)
			)
			(stroke
				(width 0)
				(type default)
			)
			(fill no)
			(layer "F.Fab")
		)
		(pad "D" smd custom
			(at 0 -0.9525 180)
			(size 0.1905 0.1905)
			(layers "F.Cu" "F.Mask" "F.Paste")
			(net "SW_SSD3_R")
			(options
				(clearance outline)
				(anchor circle)
			)
			(primitives
				(gr_poly
					(pts
						(arc
							(start -0.1778 0.5715)
							(mid -0.321484 0.511984)
							(end -0.381 0.3683)
						)
						(arc
							(start -0.381 -0.3683)
							(mid -0.321484 -0.511984)
							(end -0.1778 -0.5715)
						)
						(arc
							(start 0.1778 -0.5715)
							(mid 0.321484 -0.511984)
							(end 0.381 -0.3683)
						)
						(arc
							(start 0.381 0.3683)
							(mid 0.321484 0.511984)
							(end 0.1778 0.5715)
						)
					)
					(width 0)
					(fill yes)
				)
			)
		)
		(pad "G" smd custom
			(at -0.98425 0.9525 180)
			(size 0.1905 0.1905)
			(layers "F.Cu" "F.Mask" "F.Paste")
			(net "SSD3_PWREN")
			(options
				(clearance outline)
				(anchor circle)
			)
			(primitives
				(gr_poly
					(pts
						(arc
							(start -0.1778 0.5715)
							(mid -0.321484 0.511984)
							(end -0.381 0.3683)
						)
						(arc
							(start -0.381 -0.3683)
							(mid -0.321484 -0.511984)
							(end -0.1778 -0.5715)
						)
						(arc
							(start 0.1778 -0.5715)
							(mid 0.321484 -0.511984)
							(end 0.381 -0.3683)
						)
						(arc
							(start 0.381 0.3683)
							(mid 0.321484 0.511984)
							(end 0.1778 0.5715)
						)
					)
					(width 0)
					(fill yes)
				)
			)
		)
		(pad "S" smd custom
			(at 0.98425 0.9525 180)
			(size 0.1905 0.1905)
			(layers "F.Cu" "F.Mask" "F.Paste")
			(net "GND")
			(options
				(clearance outline)
				(anchor circle)
			)
			(primitives
				(gr_poly
					(pts
						(arc
							(start -0.1778 0.5715)
							(mid -0.321484 0.511984)
							(end -0.381 0.3683)
						)
						(arc
							(start -0.381 -0.3683)
							(mid -0.321484 -0.511984)
							(end -0.1778 -0.5715)
						)
						(arc
							(start 0.1778 -0.5715)
							(mid 0.321484 -0.511984)
							(end 0.381 -0.3683)
						)
						(arc
							(start 0.381 0.3683)
							(mid 0.321484 0.511984)
							(end 0.1778 0.5715)
						)
					)
					(width 0)
					(fill yes)
				)
			)
		)
	)
	(footprint ""
		(layer "F.Cu")
		(at 230.632 -449.199 -90)
		(property "Reference" "R9783"
			(at 0 0 270)
			(layer "F.SilkS")
			(hide yes)
			(effects
				(font
					(size 1.27 1.27)
				)
			)
		)
		(property "Value" "0R2J-2-GP"
			(at 0.064008 -3.993896 270)
			(unlocked yes)
			(layer "F.Fab")
			(hide yes)
			(effects
				(font
					(size 1.016 1.016)
					(thickness 0.1524)
				)
			)
		)
		(property "Device Type" "R402H16"
			(at 0.064008 -5.517896 270)
			(unlocked yes)
			(layer "F.Fab")
			(hide yes)
			(effects
				(font
					(size 1.016 1.016)
					(thickness 0.1524)
				)
			)
		)
		(duplicate_pad_numbers_are_jumpers no)
		(fp_line
			(start -0.508 -0.9398)
			(end -0.508 0.9398)
			(stroke
				(width 0.1524)
				(type default)
			)
			(layer "F.SilkS")
		)
		(fp_line
			(start 0.508 -0.9398)
			(end -0.508 -0.9398)
			(stroke
				(width 0.1524)
				(type default)
			)
			(layer "F.SilkS")
		)
		(fp_rect
			(start -0.508 0.9398)
			(end 0.508 -0.9398)
			(stroke
				(width 0)
				(type default)
			)
			(fill no)
			(layer "F.CrtYd")
		)
		(fp_rect
			(start -0.508 0.9398)
			(end 0.508 -0.9398)
			(stroke
				(width 0)
				(type default)
			)
			(fill no)
			(layer "F.Fab")
		)
		(pad "1" smd custom
			(at 0 -0.4445 270)
			(size 0.1397 0.1397)
			(layers "F.Cu" "F.Mask" "F.Paste")
			(net "SSD_ACT_DR0_R")
			(options
				(clearance outline)
				(anchor circle)
			)
			(primitives
				(gr_poly
					(pts
						(arc
							(start -0.1778 -0.2794)
							(mid -0.249642 -0.249642)
							(end -0.2794 -0.1778)
						)
						(arc
							(start -0.2794 0.1778)
							(mid -0.249642 0.249642)
							(end -0.1778 0.2794)
						)
						(arc
							(start 0.1778 0.2794)
							(mid 0.249642 0.249642)
							(end 0.2794 0.1778)
						)
						(arc
							(start 0.2794 -0.1778)
							(mid 0.249642 -0.249642)
							(end 0.1778 -0.2794)
						)
					)
					(width 0)
					(fill yes)
				)
			)
		)
		(pad "2" smd custom
			(at 0 0.4445 270)
			(size 0.1397 0.1397)
			(layers "F.Cu" "F.Mask" "F.Paste")
			(net "SSD_ACT_DR0")
			(options
				(clearance outline)
				(anchor circle)
			)
			(primitives
				(gr_poly
					(pts
						(arc
							(start -0.1778 -0.2794)
							(mid -0.249642 -0.249642)
							(end -0.2794 -0.1778)
						)
						(arc
							(start -0.2794 0.1778)
							(mid -0.249642 0.249642)
							(end -0.1778 0.2794)
						)
						(arc
							(start 0.1778 0.2794)
							(mid 0.249642 0.249642)
							(end 0.2794 0.1778)
						)
						(arc
							(start 0.2794 -0.1778)
							(mid 0.249642 -0.249642)
							(end 0.1778 -0.2794)
						)
					)
					(width 0)
					(fill yes)
				)
			)
		)
	)
	(footprint ""
		(layer "F.Cu")
		(at 229.3112 -299.8724)
		(property "Reference" "R9243"
			(at 0 0 0)
			(layer "F.SilkS")
			(hide yes)
			(effects
				(font
					(size 1.27 1.27)
				)
			)
		)
		(property "Value" "2R2010F-GP"
			(at 0.0762 -4.5466 0)
			(unlocked yes)
			(layer "F.Fab")
			(hide yes)
			(effects
				(font
					(size 1.016 1.016)
					(thickness 0.1524)
				)
			)
		)
		(property "Device Type" "R2010H26"
			(at 0.0762 -6.1468 0)
			(unlocked yes)
			(layer "F.Fab")
			(hide yes)
			(effects
				(font
					(size 1.016 1.016)
					(thickness 0.1524)
				)
			)
		)
		(duplicate_pad_numbers_are_jumpers no)
		(fp_line
			(start -3.302 -1.651)
			(end -3.302 1.651)
			(stroke
				(width 0.1524)
				(type default)
			)
			(layer "F.SilkS")
		)
		(fp_line
			(start -3.302 1.651)
			(end 3.302 1.651)
			(stroke
				(width 0.1524)
				(type default)
			)
			(layer "F.SilkS")
		)
		(fp_line
			(start 3.302 -1.651)
			(end -3.302 -1.651)
			(stroke
				(width 0.1524)
				(type default)
			)
			(layer "F.SilkS")
		)
		(fp_line
			(start 3.302 1.651)
			(end 3.302 -1.651)
			(stroke
				(width 0.1524)
				(type default)
			)
			(layer "F.SilkS")
		)
		(fp_rect
			(start -3.3782 1.7272)
			(end 3.3782 -1.7272)
			(stroke
				(width 0)
				(type default)
			)
			(fill no)
			(layer "F.CrtYd")
		)
		(fp_poly
			(pts
				(xy 3.3782 -1.7272) (xy -3.3782 -1.7272) (xy -3.3782 1.7272) (xy 3.3782 1.7272)
			)
			(stroke
				(width 0)
				(type default)
			)
			(fill no)
			(layer "F.Fab")
		)
		(pad "1" smd rect
			(at -2.3495 0)
			(size 1.143 2.794)
			(layers "F.Cu" "F.Mask" "F.Paste")
			(net "P12V_SSD2")
		)
		(pad "2" smd rect
			(at 2.3495 0)
			(size 1.143 2.794)
			(layers "F.Cu" "F.Mask" "F.Paste")
			(net "12V_PRECH_SSD2")
		)
	)
	(footprint ""
		(layer "F.Cu")
		(at 96.52 -296.545)
		(property "Reference" "R9067"
			(at 0 0 0)
			(layer "F.SilkS")
			(hide yes)
			(effects
				(font
					(size 1.27 1.27)
				)
			)
		)
		(property "Value" "27R2F-GP"
			(at 0.064008 -3.993896 0)
			(unlocked yes)
			(layer "F.Fab")
			(hide yes)
			(effects
				(font
					(size 1.016 1.016)
					(thickness 0.1524)
				)
			)
		)
		(property "Device Type" "R402H16"
			(at 0.064008 -5.517896 0)
			(unlocked yes)
			(layer "F.Fab")
			(hide yes)
			(effects
				(font
					(size 1.016 1.016)
					(thickness 0.1524)
				)
			)
		)
		(duplicate_pad_numbers_are_jumpers no)
		(fp_line
			(start -0.508 -0.9398)
			(end -0.508 0.9398)
			(stroke
				(width 0.1524)
				(type default)
			)
			(layer "F.SilkS")
		)
		(fp_line
			(start 0.508 -0.9398)
			(end -0.508 -0.9398)
			(stroke
				(width 0.1524)
				(type default)
			)
			(layer "F.SilkS")
		)
		(fp_rect
			(start -0.508 0.9398)
			(end 0.508 -0.9398)
			(stroke
				(width 0)
				(type default)
			)
			(fill no)
			(layer "F.CrtYd")
		)
		(fp_rect
			(start -0.508 0.9398)
			(end 0.508 -0.9398)
			(stroke
				(width 0)
				(type default)
			)
			(fill no)
			(layer "F.Fab")
		)
		(pad "1" smd custom
			(at 0 -0.4445)
			(size 0.1397 0.1397)
			(layers "F.Cu" "F.Mask" "F.Paste")
			(net "PE_CLK_100M_DR2_2_R_N")
			(options
				(clearance outline)
				(anchor circle)
			)
			(primitives
				(gr_poly
					(pts
						(arc
							(start -0.1778 -0.2794)
							(mid -0.249642 -0.249642)
							(end -0.2794 -0.1778)
						)
						(arc
							(start -0.2794 0.1778)
							(mid -0.249642 0.249642)
							(end -0.1778 0.2794)
						)
						(arc
							(start 0.1778 0.2794)
							(mid 0.249642 0.249642)
							(end 0.2794 0.1778)
						)
						(arc
							(start 0.2794 -0.1778)
							(mid 0.249642 -0.249642)
							(end 0.1778 -0.2794)
						)
					)
					(width 0)
					(fill yes)
				)
			)
		)
		(pad "2" smd custom
			(at 0 0.4445)
			(size 0.1397 0.1397)
			(layers "F.Cu" "F.Mask" "F.Paste")
			(net "PE_CLK100M_DR2_2_N")
			(options
				(clearance outline)
				(anchor circle)
			)
			(primitives
				(gr_poly
					(pts
						(arc
							(start -0.1778 -0.2794)
							(mid -0.249642 -0.249642)
							(end -0.2794 -0.1778)
						)
						(arc
							(start -0.2794 0.1778)
							(mid -0.249642 0.249642)
							(end -0.1778 0.2794)
						)
						(arc
							(start 0.1778 0.2794)
							(mid 0.249642 0.249642)
							(end 0.2794 0.1778)
						)
						(arc
							(start 0.2794 -0.1778)
							(mid 0.249642 -0.249642)
							(end 0.1778 -0.2794)
						)
					)
					(width 0)
					(fill yes)
				)
			)
		)
	)
	(footprint ""
		(layer "F.Cu")
		(at 90.932 -17.526 180)
		(property "Reference" "R362"
			(at 0 0 180)
			(layer "F.SilkS")
			(hide yes)
			(effects
				(font
					(size 1.27 1.27)
				)
			)
		)
		(property "Value" "4K7R2F-GP"
			(at 0.064008 -3.993896 180)
			(unlocked yes)
			(layer "F.Fab")
			(hide yes)
			(effects
				(font
					(size 1.016 1.016)
					(thickness 0.1524)
				)
			)
		)
		(property "Device Type" "R402H16"
			(at 0.064008 -5.517896 180)
			(unlocked yes)
			(layer "F.Fab")
			(hide yes)
			(effects
				(font
					(size 1.016 1.016)
					(thickness 0.1524)
				)
			)
		)
		(duplicate_pad_numbers_are_jumpers no)
		(fp_line
			(start 0.508 -0.9398)
			(end -0.508 -0.9398)
			(stroke
				(width 0.1524)
				(type default)
			)
			(layer "F.SilkS")
		)
		(fp_line
			(start -0.508 -0.9398)
			(end -0.508 0.9398)
			(stroke
				(width 0.1524)
				(type default)
			)
			(layer "F.SilkS")
		)
		(fp_rect
			(start -0.508 0.9398)
			(end 0.508 -0.9398)
			(stroke
				(width 0)
				(type default)
			)
			(fill no)
			(layer "F.CrtYd")
		)
		(fp_rect
			(start -0.508 0.9398)
			(end 0.508 -0.9398)
			(stroke
				(width 0)
				(type default)
			)
			(fill no)
			(layer "F.Fab")
		)
		(pad "1" smd custom
			(at 0 -0.4445 180)
			(size 0.1397 0.1397)
			(layers "F.Cu" "F.Mask" "F.Paste")
			(net "P3V3")
			(options
				(clearance outline)
				(anchor circle)
			)
			(primitives
				(gr_poly
					(pts
						(arc
							(start -0.1778 -0.2794)
							(mid -0.249642 -0.249642)
							(end -0.2794 -0.1778)
						)
						(arc
							(start -0.2794 0.1778)
							(mid -0.249642 0.249642)
							(end -0.1778 0.2794)
						)
						(arc
							(start 0.1778 0.2794)
							(mid 0.249642 0.249642)
							(end 0.2794 0.1778)
						)
						(arc
							(start 0.2794 -0.1778)
							(mid 0.249642 -0.249642)
							(end 0.1778 -0.2794)
						)
					)
					(width 0)
					(fill yes)
				)
			)
		)
		(pad "2" smd custom
			(at 0 0.4445 180)
			(size 0.1397 0.1397)
			(layers "F.Cu" "F.Mask" "F.Paste")
			(net "VOL_SEN_ALERT")
			(options
				(clearance outline)
				(anchor circle)
			)
			(primitives
				(gr_poly
					(pts
						(arc
							(start -0.1778 -0.2794)
							(mid -0.249642 -0.249642)
							(end -0.2794 -0.1778)
						)
						(arc
							(start -0.2794 0.1778)
							(mid -0.249642 0.249642)
							(end -0.1778 0.2794)
						)
						(arc
							(start 0.1778 0.2794)
							(mid 0.249642 0.249642)
							(end 0.2794 0.1778)
						)
						(arc
							(start 0.2794 -0.1778)
							(mid 0.249642 -0.249642)
							(end 0.1778 -0.2794)
						)
					)
					(width 0)
					(fill yes)
				)
			)
		)
	)
	(footprint ""
		(layer "F.Cu")
		(at 14.224 -478.155)
		(property "Reference" "R406"
			(at 0 0 0)
			(layer "F.SilkS")
			(hide yes)
			(effects
				(font
					(size 1.27 1.27)
				)
			)
		)
		(property "Value" "10KR2F-2-GP"
			(at 0.064008 -3.993896 0)
			(unlocked yes)
			(layer "F.Fab")
			(hide yes)
			(effects
				(font
					(size 1.016 1.016)
					(thickness 0.1524)
				)
			)
		)
		(property "Device Type" "R402H16"
			(at 0.064008 -5.517896 0)
			(unlocked yes)
			(layer "F.Fab")
			(hide yes)
			(effects
				(font
					(size 1.016 1.016)
					(thickness 0.1524)
				)
			)
		)
		(duplicate_pad_numbers_are_jumpers no)
		(fp_line
			(start -0.508 -0.9398)
			(end -0.508 0.9398)
			(stroke
				(width 0.1524)
				(type default)
			)
			(layer "F.SilkS")
		)
		(fp_line
			(start 0.508 -0.9398)
			(end -0.508 -0.9398)
			(stroke
				(width 0.1524)
				(type default)
			)
			(layer "F.SilkS")
		)
		(fp_rect
			(start -0.508 0.9398)
			(end 0.508 -0.9398)
			(stroke
				(width 0)
				(type default)
			)
			(fill no)
			(layer "F.CrtYd")
		)
		(fp_rect
			(start -0.508 0.9398)
			(end 0.508 -0.9398)
			(stroke
				(width 0)
				(type default)
			)
			(fill no)
			(layer "F.Fab")
		)
		(pad "1" smd custom
			(at 0 -0.4445)
			(size 0.1397 0.1397)
			(layers "F.Cu" "F.Mask" "F.Paste")
			(net "P3V3")
			(options
				(clearance outline)
				(anchor circle)
			)
			(primitives
				(gr_poly
					(pts
						(arc
							(start -0.1778 -0.2794)
							(mid -0.249642 -0.249642)
							(end -0.2794 -0.1778)
						)
						(arc
							(start -0.2794 0.1778)
							(mid -0.249642 0.249642)
							(end -0.1778 0.2794)
						)
						(arc
							(start 0.1778 0.2794)
							(mid 0.249642 0.249642)
							(end 0.2794 0.1778)
						)
						(arc
							(start 0.2794 -0.1778)
							(mid 0.249642 -0.249642)
							(end 0.1778 -0.2794)
						)
					)
					(width 0)
					(fill yes)
				)
			)
		)
		(pad "2" smd custom
			(at 0 0.4445)
			(size 0.1397 0.1397)
			(layers "F.Cu" "F.Mask" "F.Paste")
			(net "DPB_HW_REVISION")
			(options
				(clearance outline)
				(anchor circle)
			)
			(primitives
				(gr_poly
					(pts
						(arc
							(start -0.1778 -0.2794)
							(mid -0.249642 -0.249642)
							(end -0.2794 -0.1778)
						)
						(arc
							(start -0.2794 0.1778)
							(mid -0.249642 0.249642)
							(end -0.1778 0.2794)
						)
						(arc
							(start 0.1778 0.2794)
							(mid 0.249642 0.249642)
							(end 0.2794 0.1778)
						)
						(arc
							(start 0.2794 -0.1778)
							(mid 0.249642 -0.249642)
							(end 0.1778 -0.2794)
						)
					)
					(width 0)
					(fill yes)
				)
			)
		)
	)
	(footprint ""
		(layer "F.Cu")
		(at 200.250806 -498.514878 180)
		(property "Reference" "R9777"
			(at 0 0 180)
			(layer "F.SilkS")
			(hide yes)
			(effects
				(font
					(size 1.27 1.27)
				)
			)
		)
		(property "Value" "47KR2J-2-GP"
			(at 0.064008 -3.993896 180)
			(unlocked yes)
			(layer "F.Fab")
			(hide yes)
			(effects
				(font
					(size 1.016 1.016)
					(thickness 0.1524)
				)
			)
		)
		(property "Device Type" "R402H16"
			(at 0.064008 -5.517896 180)
			(unlocked yes)
			(layer "F.Fab")
			(hide yes)
			(effects
				(font
					(size 1.016 1.016)
					(thickness 0.1524)
				)
			)
		)
		(duplicate_pad_numbers_are_jumpers no)
		(fp_line
			(start 0.508 -0.9398)
			(end -0.508 -0.9398)
			(stroke
				(width 0.1524)
				(type default)
			)
			(layer "F.SilkS")
		)
		(fp_line
			(start -0.508 -0.9398)
			(end -0.508 0.9398)
			(stroke
				(width 0.1524)
				(type default)
			)
			(layer "F.SilkS")
		)
		(fp_poly
			(pts
				(xy -0.508 0.9398) (xy 0.508 0.9398) (xy 0.508 -0.9398) (xy -0.508 -0.9398)
			)
			(stroke
				(width 0)
				(type default)
			)
			(fill no)
			(layer "F.CrtYd")
		)
		(fp_rect
			(start -0.508 0.9398)
			(end 0.508 -0.9398)
			(stroke
				(width 0)
				(type default)
			)
			(fill no)
			(layer "F.Fab")
		)
		(pad "1" smd custom
			(at 0 -0.4445 180)
			(size 0.1397 0.1397)
			(layers "F.Cu" "F.Mask" "F.Paste")
			(net "P12V")
			(options
				(clearance outline)
				(anchor circle)
			)
			(primitives
				(gr_poly
					(pts
						(arc
							(start -0.1778 -0.2794)
							(mid -0.249642 -0.249642)
							(end -0.2794 -0.1778)
						)
						(arc
							(start -0.2794 0.1778)
							(mid -0.249642 0.249642)
							(end -0.1778 0.2794)
						)
						(arc
							(start 0.1778 0.2794)
							(mid 0.249642 0.249642)
							(end 0.2794 0.1778)
						)
						(arc
							(start 0.2794 -0.1778)
							(mid 0.249642 -0.249642)
							(end 0.1778 -0.2794)
						)
					)
					(width 0)
					(fill yes)
				)
			)
		)
		(pad "2" smd custom
			(at 0 0.4445 180)
			(size 0.1397 0.1397)
			(layers "F.Cu" "F.Mask" "F.Paste")
			(net "P12V_MOST0_GATE")
			(options
				(clearance outline)
				(anchor circle)
			)
			(primitives
				(gr_poly
					(pts
						(arc
							(start -0.1778 -0.2794)
							(mid -0.249642 -0.249642)
							(end -0.2794 -0.1778)
						)
						(arc
							(start -0.2794 0.1778)
							(mid -0.249642 0.249642)
							(end -0.1778 0.2794)
						)
						(arc
							(start 0.1778 0.2794)
							(mid 0.249642 0.249642)
							(end 0.2794 0.1778)
						)
						(arc
							(start 0.2794 -0.1778)
							(mid 0.249642 -0.249642)
							(end 0.1778 -0.2794)
						)
					)
					(width 0)
					(fill yes)
				)
			)
		)
	)
	(footprint ""
		(layer "F.Cu")
		(at 25.4508 -208.7118)
		(property "Reference" "PC1250"
			(at 0 0 0)
			(layer "F.SilkS")
			(hide yes)
			(effects
				(font
					(size 1.27 1.27)
				)
			)
		)
		(property "Value" "SC22U25V6KX-GP-U"
			(at -2.860802 -5.279644 0)
			(unlocked yes)
			(layer "F.Fab")
			(hide yes)
			(effects
				(font
					(size 1.016 1.016)
					(thickness 0.1524)
				)
			)
		)
		(property "Device Type" "C1206-TO0D3H75"
			(at -2.860802 -6.803644 0)
			(unlocked yes)
			(layer "F.Fab")
			(hide yes)
			(effects
				(font
					(size 1.016 1.016)
					(thickness 0.1524)
				)
			)
		)
		(duplicate_pad_numbers_are_jumpers no)
		(fp_line
			(start -1.3081 -2.3749)
			(end 1.3081 -2.3749)
			(stroke
				(width 0.1524)
				(type default)
			)
			(layer "F.SilkS")
		)
		(fp_line
			(start -1.3081 2.3749)
			(end -1.3081 -2.3749)
			(stroke
				(width 0.1524)
				(type default)
			)
			(layer "F.SilkS")
		)
		(fp_line
			(start 1.3081 -2.3749)
			(end 1.3081 2.3749)
			(stroke
				(width 0.1524)
				(type default)
			)
			(layer "F.SilkS")
		)
		(fp_line
			(start 1.3081 2.3749)
			(end -1.3081 2.3749)
			(stroke
				(width 0.1524)
				(type default)
			)
			(layer "F.SilkS")
		)
		(fp_rect
			(start -0.8001 1.6002)
			(end 0.8001 -1.6002)
			(stroke
				(width 0)
				(type default)
			)
			(fill no)
			(layer "F.CrtYd")
		)
		(fp_poly
			(pts
				(xy -1.5621 2.4511) (xy -1.5621 1.6002) (xy 0.8001 1.6002) (xy 0.8001 -1.6002) (xy -0.8001 -1.6002)
				(xy -0.8001 1.5875) (xy -1.5621 1.5875) (xy -1.5621 -2.4511) (xy 1.5621 -2.4511) (xy 1.5621 2.4511)
			)
			(stroke
				(width 0)
				(type default)
			)
			(fill no)
			(layer "F.CrtYd")
		)
		(fp_rect
			(start -1.5621 2.4511)
			(end 1.5621 -2.4511)
			(stroke
				(width 0)
				(type default)
			)
			(fill no)
			(layer "F.Fab")
		)
		(pad "1" smd rect
			(at 0 -1.392936)
			(size 2.1082 1.4478)
			(layers "F.Cu" "F.Mask" "F.Paste")
			(net "P12V_SSD12")
		)
		(pad "2" smd rect
			(at 0 1.392936)
			(size 2.1082 1.4478)
			(layers "F.Cu" "F.Mask" "F.Paste")
			(net "GND")
		)
	)
	(footprint ""
		(layer "F.Cu")
		(at 37.0078 -85.9536)
		(property "Reference" "PC1198"
			(at 0 0 0)
			(layer "F.SilkS")
			(hide yes)
			(effects
				(font
					(size 1.27 1.27)
				)
			)
		)
		(property "Value" "SCD01U50V2KX-1GP"
			(at 1.1811 -2.7051 0)
			(unlocked yes)
			(layer "F.Fab")
			(hide yes)
			(effects
				(font
					(size 1.016 1.016)
					(thickness 0.1524)
				)
			)
		)
		(property "Device Type" "C402H22"
			(at 1.1811 -4.2291 0)
			(unlocked yes)
			(layer "F.Fab")
			(hide yes)
			(effects
				(font
					(size 1.016 1.016)
					(thickness 0.1524)
				)
			)
		)
		(duplicate_pad_numbers_are_jumpers no)
		(fp_rect
			(start -0.4318 0.9525)
			(end 0.4318 -0.9525)
			(stroke
				(width 0)
				(type default)
			)
			(fill no)
			(layer "F.CrtYd")
		)
		(fp_rect
			(start -0.4318 0.9525)
			(end 0.4318 -0.9525)
			(stroke
				(width 0)
				(type default)
			)
			(fill no)
			(layer "F.Fab")
		)
		(pad "1" smd custom
			(at 0 -0.4445)
			(size 0.1524 0.1524)
			(layers "F.Cu" "F.Mask" "F.Paste")
			(net "P12V_SSD9")
			(options
				(clearance outline)
				(anchor circle)
			)
			(primitives
				(gr_poly
					(pts
						(arc
							(start 0.3048 -0.2032)
							(mid 0.275042 -0.275042)
							(end 0.2032 -0.3048)
						)
						(arc
							(start -0.2032 -0.3048)
							(mid -0.275042 -0.275042)
							(end -0.3048 -0.2032)
						)
						(arc
							(start -0.3048 0.2032)
							(mid -0.275042 0.275042)
							(end -0.2032 0.3048)
						)
						(arc
							(start 0.2032 0.3048)
							(mid 0.275042 0.275042)
							(end 0.3048 0.2032)
						)
					)
					(width 0)
					(fill yes)
				)
			)
		)
		(pad "2" smd custom
			(at 0 0.4445)
			(size 0.1524 0.1524)
			(layers "F.Cu" "F.Mask" "F.Paste")
			(net "GND")
			(options
				(clearance outline)
				(anchor circle)
			)
			(primitives
				(gr_poly
					(pts
						(arc
							(start 0.3048 -0.2032)
							(mid 0.275042 -0.275042)
							(end 0.2032 -0.3048)
						)
						(arc
							(start -0.2032 -0.3048)
							(mid -0.275042 -0.275042)
							(end -0.3048 -0.2032)
						)
						(arc
							(start -0.3048 0.2032)
							(mid -0.275042 0.275042)
							(end -0.2032 0.3048)
						)
						(arc
							(start 0.2032 0.3048)
							(mid 0.275042 0.275042)
							(end 0.3048 0.2032)
						)
					)
					(width 0)
					(fill yes)
				)
			)
		)
	)
	(footprint ""
		(layer "F.Cu")
		(at 223.901 -431.292 180)
		(property "Reference" "PR9080"
			(at 0 0 180)
			(layer "F.SilkS")
			(hide yes)
			(effects
				(font
					(size 1.27 1.27)
				)
			)
		)
		(property "Value" "0R2J-2-GP"
			(at 0.064008 -3.993896 180)
			(unlocked yes)
			(layer "F.Fab")
			(hide yes)
			(effects
				(font
					(size 1.016 1.016)
					(thickness 0.1524)
				)
			)
		)
		(property "Device Type" "R402H16"
			(at 0.064008 -5.517896 180)
			(unlocked yes)
			(layer "F.Fab")
			(hide yes)
			(effects
				(font
					(size 1.016 1.016)
					(thickness 0.1524)
				)
			)
		)
		(duplicate_pad_numbers_are_jumpers no)
		(fp_line
			(start 0.508 -0.9398)
			(end -0.508 -0.9398)
			(stroke
				(width 0.1524)
				(type default)
			)
			(layer "F.SilkS")
		)
		(fp_line
			(start -0.508 -0.9398)
			(end -0.508 0.9398)
			(stroke
				(width 0.1524)
				(type default)
			)
			(layer "F.SilkS")
		)
		(fp_rect
			(start -0.508 0.9398)
			(end 0.508 -0.9398)
			(stroke
				(width 0)
				(type default)
			)
			(fill no)
			(layer "F.CrtYd")
		)
		(fp_rect
			(start -0.508 0.9398)
			(end 0.508 -0.9398)
			(stroke
				(width 0)
				(type default)
			)
			(fill no)
			(layer "F.Fab")
		)
		(pad "1" smd custom
			(at 0 -0.4445 180)
			(size 0.1397 0.1397)
			(layers "F.Cu" "F.Mask" "F.Paste")
			(net "P3V3_VBST_RR")
			(options
				(clearance outline)
				(anchor circle)
			)
			(primitives
				(gr_poly
					(pts
						(arc
							(start -0.1778 -0.2794)
							(mid -0.249642 -0.249642)
							(end -0.2794 -0.1778)
						)
						(arc
							(start -0.2794 0.1778)
							(mid -0.249642 0.249642)
							(end -0.1778 0.2794)
						)
						(arc
							(start 0.1778 0.2794)
							(mid 0.249642 0.249642)
							(end 0.2794 0.1778)
						)
						(arc
							(start 0.2794 -0.1778)
							(mid 0.249642 -0.249642)
							(end 0.1778 -0.2794)
						)
					)
					(width 0)
					(fill yes)
				)
			)
		)
		(pad "2" smd custom
			(at 0 0.4445 180)
			(size 0.1397 0.1397)
			(layers "F.Cu" "F.Mask" "F.Paste")
			(net "P3V3_VBST")
			(options
				(clearance outline)
				(anchor circle)
			)
			(primitives
				(gr_poly
					(pts
						(arc
							(start -0.1778 -0.2794)
							(mid -0.249642 -0.249642)
							(end -0.2794 -0.1778)
						)
						(arc
							(start -0.2794 0.1778)
							(mid -0.249642 0.249642)
							(end -0.1778 0.2794)
						)
						(arc
							(start 0.1778 0.2794)
							(mid 0.249642 0.249642)
							(end 0.2794 0.1778)
						)
						(arc
							(start 0.2794 -0.1778)
							(mid 0.249642 -0.249642)
							(end 0.1778 -0.2794)
						)
					)
					(width 0)
					(fill yes)
				)
			)
		)
	)
	(footprint ""
		(layer "F.Cu")
		(at 12.192 -478.155 180)
		(property "Reference" "R9036"
			(at 0 0 180)
			(layer "F.SilkS")
			(hide yes)
			(effects
				(font
					(size 1.27 1.27)
				)
			)
		)
		(property "Value" "0R2J-2-GP"
			(at 0.064008 -3.993896 180)
			(unlocked yes)
			(layer "F.Fab")
			(hide yes)
			(effects
				(font
					(size 1.016 1.016)
					(thickness 0.1524)
				)
			)
		)
		(property "Device Type" "R402H16"
			(at 0.064008 -5.517896 180)
			(unlocked yes)
			(layer "F.Fab")
			(hide yes)
			(effects
				(font
					(size 1.016 1.016)
					(thickness 0.1524)
				)
			)
		)
		(duplicate_pad_numbers_are_jumpers no)
		(fp_line
			(start 0.508 -0.9398)
			(end -0.508 -0.9398)
			(stroke
				(width 0.1524)
				(type default)
			)
			(layer "F.SilkS")
		)
		(fp_line
			(start -0.508 -0.9398)
			(end -0.508 0.9398)
			(stroke
				(width 0.1524)
				(type default)
			)
			(layer "F.SilkS")
		)
		(fp_rect
			(start -0.508 0.9398)
			(end 0.508 -0.9398)
			(stroke
				(width 0)
				(type default)
			)
			(fill no)
			(layer "F.CrtYd")
		)
		(fp_rect
			(start -0.508 0.9398)
			(end 0.508 -0.9398)
			(stroke
				(width 0)
				(type default)
			)
			(fill no)
			(layer "F.Fab")
		)
		(pad "1" smd custom
			(at 0 -0.4445 180)
			(size 0.1397 0.1397)
			(layers "F.Cu" "F.Mask" "F.Paste")
			(net "SELF_TRAY_PRESENT_R")
			(options
				(clearance outline)
				(anchor circle)
			)
			(primitives
				(gr_poly
					(pts
						(arc
							(start -0.1778 -0.2794)
							(mid -0.249642 -0.249642)
							(end -0.2794 -0.1778)
						)
						(arc
							(start -0.2794 0.1778)
							(mid -0.249642 0.249642)
							(end -0.1778 0.2794)
						)
						(arc
							(start 0.1778 0.2794)
							(mid 0.249642 0.249642)
							(end 0.2794 0.1778)
						)
						(arc
							(start 0.2794 -0.1778)
							(mid 0.249642 -0.249642)
							(end 0.1778 -0.2794)
						)
					)
					(width 0)
					(fill yes)
				)
			)
		)
		(pad "2" smd custom
			(at 0 0.4445 180)
			(size 0.1397 0.1397)
			(layers "F.Cu" "F.Mask" "F.Paste")
			(net "SELF_TRAY_PRESENT")
			(options
				(clearance outline)
				(anchor circle)
			)
			(primitives
				(gr_poly
					(pts
						(arc
							(start -0.1778 -0.2794)
							(mid -0.249642 -0.249642)
							(end -0.2794 -0.1778)
						)
						(arc
							(start -0.2794 0.1778)
							(mid -0.249642 0.249642)
							(end -0.1778 0.2794)
						)
						(arc
							(start 0.1778 0.2794)
							(mid 0.249642 0.249642)
							(end 0.2794 0.1778)
						)
						(arc
							(start 0.2794 -0.1778)
							(mid 0.249642 -0.249642)
							(end 0.1778 -0.2794)
						)
					)
					(width 0)
					(fill yes)
				)
			)
		)
	)
	(footprint ""
		(layer "F.Cu")
		(at 207.391 -403.225 180)
		(property "Reference" "R9499"
			(at 0 0 180)
			(layer "F.SilkS")
			(hide yes)
			(effects
				(font
					(size 1.27 1.27)
				)
			)
		)
		(property "Value" "4K7R2J-2-GP"
			(at 0.064008 -3.993896 180)
			(unlocked yes)
			(layer "F.Fab")
			(hide yes)
			(effects
				(font
					(size 1.016 1.016)
					(thickness 0.1524)
				)
			)
		)
		(property "Device Type" "R402H16"
			(at 0.064008 -5.517896 180)
			(unlocked yes)
			(layer "F.Fab")
			(hide yes)
			(effects
				(font
					(size 1.016 1.016)
					(thickness 0.1524)
				)
			)
		)
		(duplicate_pad_numbers_are_jumpers no)
		(fp_line
			(start 0.508 -0.9398)
			(end -0.508 -0.9398)
			(stroke
				(width 0.1524)
				(type default)
			)
			(layer "F.SilkS")
		)
		(fp_line
			(start -0.508 -0.9398)
			(end -0.508 0.9398)
			(stroke
				(width 0.1524)
				(type default)
			)
			(layer "F.SilkS")
		)
		(fp_rect
			(start -0.508 0.9398)
			(end 0.508 -0.9398)
			(stroke
				(width 0)
				(type default)
			)
			(fill no)
			(layer "F.CrtYd")
		)
		(fp_rect
			(start -0.508 0.9398)
			(end 0.508 -0.9398)
			(stroke
				(width 0)
				(type default)
			)
			(fill no)
			(layer "F.Fab")
		)
		(pad "1" smd custom
			(at 0 -0.4445 180)
			(size 0.1397 0.1397)
			(layers "F.Cu" "F.Mask" "F.Paste")
			(net "P3V3")
			(options
				(clearance outline)
				(anchor circle)
			)
			(primitives
				(gr_poly
					(pts
						(arc
							(start -0.1778 -0.2794)
							(mid -0.249642 -0.249642)
							(end -0.2794 -0.1778)
						)
						(arc
							(start -0.2794 0.1778)
							(mid -0.249642 0.249642)
							(end -0.1778 0.2794)
						)
						(arc
							(start 0.1778 0.2794)
							(mid 0.249642 0.249642)
							(end 0.2794 0.1778)
						)
						(arc
							(start 0.2794 -0.1778)
							(mid 0.249642 -0.249642)
							(end 0.1778 -0.2794)
						)
					)
					(width 0)
					(fill yes)
				)
			)
		)
		(pad "2" smd custom
			(at 0 0.4445 180)
			(size 0.1397 0.1397)
			(layers "F.Cu" "F.Mask" "F.Paste")
			(net "SSD1_PWREN")
			(options
				(clearance outline)
				(anchor circle)
			)
			(primitives
				(gr_poly
					(pts
						(arc
							(start -0.1778 -0.2794)
							(mid -0.249642 -0.249642)
							(end -0.2794 -0.1778)
						)
						(arc
							(start -0.2794 0.1778)
							(mid -0.249642 0.249642)
							(end -0.1778 0.2794)
						)
						(arc
							(start 0.1778 0.2794)
							(mid 0.249642 0.249642)
							(end 0.2794 0.1778)
						)
						(arc
							(start 0.2794 -0.1778)
							(mid 0.249642 -0.249642)
							(end 0.1778 -0.2794)
						)
					)
					(width 0)
					(fill yes)
				)
			)
		)
	)
	(footprint ""
		(layer "F.Cu")
		(at 92.837 -19.431 -90)
		(property "Reference" "C357"
			(at 0 0 270)
			(layer "F.SilkS")
			(hide yes)
			(effects
				(font
					(size 1.27 1.27)
				)
			)
		)
		(property "Value" "SCD1U16V2KX-3GP"
			(at 1.1811 -2.7051 270)
			(unlocked yes)
			(layer "F.Fab")
			(hide yes)
			(effects
				(font
					(size 1.016 1.016)
					(thickness 0.1524)
				)
			)
		)
		(property "Device Type" "C402H22"
			(at 1.1811 -4.2291 270)
			(unlocked yes)
			(layer "F.Fab")
			(hide yes)
			(effects
				(font
					(size 1.016 1.016)
					(thickness 0.1524)
				)
			)
		)
		(duplicate_pad_numbers_are_jumpers no)
		(fp_rect
			(start -0.4318 0.9525)
			(end 0.4318 -0.9525)
			(stroke
				(width 0)
				(type default)
			)
			(fill no)
			(layer "F.CrtYd")
		)
		(fp_rect
			(start -0.4318 0.9525)
			(end 0.4318 -0.9525)
			(stroke
				(width 0)
				(type default)
			)
			(fill no)
			(layer "F.Fab")
		)
		(pad "1" smd custom
			(at 0 -0.4445 270)
			(size 0.1524 0.1524)
			(layers "F.Cu" "F.Mask" "F.Paste")
			(net "P12V_SENSE")
			(options
				(clearance outline)
				(anchor circle)
			)
			(primitives
				(gr_poly
					(pts
						(arc
							(start 0.3048 -0.2032)
							(mid 0.275042 -0.275042)
							(end 0.2032 -0.3048)
						)
						(arc
							(start -0.2032 -0.3048)
							(mid -0.275042 -0.275042)
							(end -0.3048 -0.2032)
						)
						(arc
							(start -0.3048 0.2032)
							(mid -0.275042 0.275042)
							(end -0.2032 0.3048)
						)
						(arc
							(start 0.2032 0.3048)
							(mid 0.275042 0.275042)
							(end 0.3048 0.2032)
						)
					)
					(width 0)
					(fill yes)
				)
			)
		)
		(pad "2" smd custom
			(at 0 0.4445 270)
			(size 0.1524 0.1524)
			(layers "F.Cu" "F.Mask" "F.Paste")
			(net "GND")
			(options
				(clearance outline)
				(anchor circle)
			)
			(primitives
				(gr_poly
					(pts
						(arc
							(start 0.3048 -0.2032)
							(mid 0.275042 -0.275042)
							(end 0.2032 -0.3048)
						)
						(arc
							(start -0.2032 -0.3048)
							(mid -0.275042 -0.275042)
							(end -0.3048 -0.2032)
						)
						(arc
							(start -0.3048 0.2032)
							(mid -0.275042 0.275042)
							(end -0.2032 0.3048)
						)
						(arc
							(start 0.2032 0.3048)
							(mid 0.275042 0.275042)
							(end 0.3048 0.2032)
						)
					)
					(width 0)
					(fill yes)
				)
			)
		)
	)
	(footprint ""
		(layer "F.Cu")
		(at 108.966 -208.026)
		(property "Reference" "R9490"
			(at 0 0 0)
			(layer "F.SilkS")
			(hide yes)
			(effects
				(font
					(size 1.27 1.27)
				)
			)
		)
		(property "Value" "4K7R2J-2-GP"
			(at 0.064008 -3.993896 0)
			(unlocked yes)
			(layer "F.Fab")
			(hide yes)
			(effects
				(font
					(size 1.016 1.016)
					(thickness 0.1524)
				)
			)
		)
		(property "Device Type" "R402H16"
			(at 0.064008 -5.517896 0)
			(unlocked yes)
			(layer "F.Fab")
			(hide yes)
			(effects
				(font
					(size 1.016 1.016)
					(thickness 0.1524)
				)
			)
		)
		(duplicate_pad_numbers_are_jumpers no)
		(fp_line
			(start -0.508 -0.9398)
			(end -0.508 0.9398)
			(stroke
				(width 0.1524)
				(type default)
			)
			(layer "F.SilkS")
		)
		(fp_line
			(start 0.508 -0.9398)
			(end -0.508 -0.9398)
			(stroke
				(width 0.1524)
				(type default)
			)
			(layer "F.SilkS")
		)
		(fp_rect
			(start -0.508 0.9398)
			(end 0.508 -0.9398)
			(stroke
				(width 0)
				(type default)
			)
			(fill no)
			(layer "F.CrtYd")
		)
		(fp_rect
			(start -0.508 0.9398)
			(end 0.508 -0.9398)
			(stroke
				(width 0)
				(type default)
			)
			(fill no)
			(layer "F.Fab")
		)
		(pad "1" smd custom
			(at 0 -0.4445)
			(size 0.1397 0.1397)
			(layers "F.Cu" "F.Mask" "F.Paste")
			(net "P3V3")
			(options
				(clearance outline)
				(anchor circle)
			)
			(primitives
				(gr_poly
					(pts
						(arc
							(start -0.1778 -0.2794)
							(mid -0.249642 -0.249642)
							(end -0.2794 -0.1778)
						)
						(arc
							(start -0.2794 0.1778)
							(mid -0.249642 0.249642)
							(end -0.1778 0.2794)
						)
						(arc
							(start 0.1778 0.2794)
							(mid 0.249642 0.249642)
							(end 0.2794 0.1778)
						)
						(arc
							(start 0.2794 -0.1778)
							(mid 0.249642 -0.249642)
							(end 0.1778 -0.2794)
						)
					)
					(width 0)
					(fill yes)
				)
			)
		)
		(pad "2" smd custom
			(at 0 0.4445)
			(size 0.1397 0.1397)
			(layers "F.Cu" "F.Mask" "F.Paste")
			(net "SSD3_CLK0_OE_N")
			(options
				(clearance outline)
				(anchor circle)
			)
			(primitives
				(gr_poly
					(pts
						(arc
							(start -0.1778 -0.2794)
							(mid -0.249642 -0.249642)
							(end -0.2794 -0.1778)
						)
						(arc
							(start -0.2794 0.1778)
							(mid -0.249642 0.249642)
							(end -0.1778 0.2794)
						)
						(arc
							(start 0.1778 0.2794)
							(mid 0.249642 0.249642)
							(end 0.2794 0.1778)
						)
						(arc
							(start 0.2794 -0.1778)
							(mid 0.249642 -0.249642)
							(end 0.1778 -0.2794)
						)
					)
					(width 0)
					(fill yes)
				)
			)
		)
	)
	(footprint ""
		(layer "F.Cu")
		(at 232.029 -430.53 -90)
		(property "Reference" "PR9090"
			(at 0 0 270)
			(layer "F.SilkS")
			(hide yes)
			(effects
				(font
					(size 1.27 1.27)
				)
			)
		)
		(property "Value" "33KR2F-2-GP"
			(at 0.064008 -3.993896 270)
			(unlocked yes)
			(layer "F.Fab")
			(hide yes)
			(effects
				(font
					(size 1.016 1.016)
					(thickness 0.1524)
				)
			)
		)
		(property "Device Type" "R402H16"
			(at 0.064008 -5.517896 270)
			(unlocked yes)
			(layer "F.Fab")
			(hide yes)
			(effects
				(font
					(size 1.016 1.016)
					(thickness 0.1524)
				)
			)
		)
		(duplicate_pad_numbers_are_jumpers no)
		(fp_line
			(start -0.508 -0.9398)
			(end -0.508 0.9398)
			(stroke
				(width 0.1524)
				(type default)
			)
			(layer "F.SilkS")
		)
		(fp_line
			(start 0.508 -0.9398)
			(end -0.508 -0.9398)
			(stroke
				(width 0.1524)
				(type default)
			)
			(layer "F.SilkS")
		)
		(fp_rect
			(start -0.508 0.9398)
			(end 0.508 -0.9398)
			(stroke
				(width 0)
				(type default)
			)
			(fill no)
			(layer "F.CrtYd")
		)
		(fp_rect
			(start -0.508 0.9398)
			(end 0.508 -0.9398)
			(stroke
				(width 0)
				(type default)
			)
			(fill no)
			(layer "F.Fab")
		)
		(pad "1" smd custom
			(at 0 -0.4445 270)
			(size 0.1397 0.1397)
			(layers "F.Cu" "F.Mask" "F.Paste")
			(net "P3V3_CC_R")
			(options
				(clearance outline)
				(anchor circle)
			)
			(primitives
				(gr_poly
					(pts
						(arc
							(start -0.1778 -0.2794)
							(mid -0.249642 -0.249642)
							(end -0.2794 -0.1778)
						)
						(arc
							(start -0.2794 0.1778)
							(mid -0.249642 0.249642)
							(end -0.1778 0.2794)
						)
						(arc
							(start 0.1778 0.2794)
							(mid 0.249642 0.249642)
							(end 0.2794 0.1778)
						)
						(arc
							(start 0.2794 -0.1778)
							(mid 0.249642 -0.249642)
							(end 0.1778 -0.2794)
						)
					)
					(width 0)
					(fill yes)
				)
			)
		)
		(pad "2" smd custom
			(at 0 0.4445 270)
			(size 0.1397 0.1397)
			(layers "F.Cu" "F.Mask" "F.Paste")
			(net "P3V3_VFB")
			(options
				(clearance outline)
				(anchor circle)
			)
			(primitives
				(gr_poly
					(pts
						(arc
							(start -0.1778 -0.2794)
							(mid -0.249642 -0.249642)
							(end -0.2794 -0.1778)
						)
						(arc
							(start -0.2794 0.1778)
							(mid -0.249642 0.249642)
							(end -0.1778 0.2794)
						)
						(arc
							(start 0.1778 0.2794)
							(mid 0.249642 0.249642)
							(end 0.2794 0.1778)
						)
						(arc
							(start 0.2794 -0.1778)
							(mid 0.249642 -0.249642)
							(end 0.1778 -0.2794)
						)
					)
					(width 0)
					(fill yes)
				)
			)
		)
	)
	(footprint ""
		(layer "F.Cu")
		(at 35.0012 -189.3824)
		(property "Reference" "PC1216"
			(at 0 0 0)
			(layer "F.SilkS")
			(hide yes)
			(effects
				(font
					(size 1.27 1.27)
				)
			)
		)
		(property "Value" "SC22U25V6KX-GP-U"
			(at -2.860802 -5.279644 0)
			(unlocked yes)
			(layer "F.Fab")
			(hide yes)
			(effects
				(font
					(size 1.016 1.016)
					(thickness 0.1524)
				)
			)
		)
		(property "Device Type" "C1206-TO0D3H75"
			(at -2.860802 -6.803644 0)
			(unlocked yes)
			(layer "F.Fab")
			(hide yes)
			(effects
				(font
					(size 1.016 1.016)
					(thickness 0.1524)
				)
			)
		)
		(duplicate_pad_numbers_are_jumpers no)
		(fp_line
			(start -1.3081 -2.3749)
			(end 1.3081 -2.3749)
			(stroke
				(width 0.1524)
				(type default)
			)
			(layer "F.SilkS")
		)
		(fp_line
			(start -1.3081 2.3749)
			(end -1.3081 -2.3749)
			(stroke
				(width 0.1524)
				(type default)
			)
			(layer "F.SilkS")
		)
		(fp_line
			(start 1.3081 -2.3749)
			(end 1.3081 2.3749)
			(stroke
				(width 0.1524)
				(type default)
			)
			(layer "F.SilkS")
		)
		(fp_line
			(start 1.3081 2.3749)
			(end -1.3081 2.3749)
			(stroke
				(width 0.1524)
				(type default)
			)
			(layer "F.SilkS")
		)
		(fp_rect
			(start -0.8001 1.6002)
			(end 0.8001 -1.6002)
			(stroke
				(width 0)
				(type default)
			)
			(fill no)
			(layer "F.CrtYd")
		)
		(fp_poly
			(pts
				(xy -1.5621 2.4511) (xy -1.5621 1.6002) (xy 0.8001 1.6002) (xy 0.8001 -1.6002) (xy -0.8001 -1.6002)
				(xy -0.8001 1.5875) (xy -1.5621 1.5875) (xy -1.5621 -2.4511) (xy 1.5621 -2.4511) (xy 1.5621 2.4511)
			)
			(stroke
				(width 0)
				(type default)
			)
			(fill no)
			(layer "F.CrtYd")
		)
		(fp_rect
			(start -1.5621 2.4511)
			(end 1.5621 -2.4511)
			(stroke
				(width 0)
				(type default)
			)
			(fill no)
			(layer "F.Fab")
		)
		(pad "1" smd rect
			(at 0 -1.392936)
			(size 2.1082 1.4478)
			(layers "F.Cu" "F.Mask" "F.Paste")
			(net "P12V_SSD8")
		)
		(pad "2" smd rect
			(at 0 1.392936)
			(size 2.1082 1.4478)
			(layers "F.Cu" "F.Mask" "F.Paste")
			(net "GND")
		)
	)
	(footprint ""
		(layer "F.Cu")
		(at 29.845 -115.443 90)
		(property "Reference" "R415"
			(at 0 0 90)
			(layer "F.SilkS")
			(hide yes)
			(effects
				(font
					(size 1.27 1.27)
				)
			)
		)
		(property "Value" "0R2J-2-GP"
			(at 0.064008 -3.993896 90)
			(unlocked yes)
			(layer "F.Fab")
			(hide yes)
			(effects
				(font
					(size 1.016 1.016)
					(thickness 0.1524)
				)
			)
		)
		(property "Device Type" "R402H16"
			(at 0.064008 -5.517896 90)
			(unlocked yes)
			(layer "F.Fab")
			(hide yes)
			(effects
				(font
					(size 1.016 1.016)
					(thickness 0.1524)
				)
			)
		)
		(duplicate_pad_numbers_are_jumpers no)
		(fp_line
			(start 0.508 -0.9398)
			(end -0.508 -0.9398)
			(stroke
				(width 0.1524)
				(type default)
			)
			(layer "F.SilkS")
		)
		(fp_line
			(start -0.508 -0.9398)
			(end -0.508 0.9398)
			(stroke
				(width 0.1524)
				(type default)
			)
			(layer "F.SilkS")
		)
		(fp_rect
			(start -0.508 0.9398)
			(end 0.508 -0.9398)
			(stroke
				(width 0)
				(type default)
			)
			(fill no)
			(layer "F.CrtYd")
		)
		(fp_rect
			(start -0.508 0.9398)
			(end 0.508 -0.9398)
			(stroke
				(width 0)
				(type default)
			)
			(fill no)
			(layer "F.Fab")
		)
		(pad "1" smd custom
			(at 0 -0.4445 90)
			(size 0.1397 0.1397)
			(layers "F.Cu" "F.Mask" "F.Paste")
			(net "SCL_DR13_R")
			(options
				(clearance outline)
				(anchor circle)
			)
			(primitives
				(gr_poly
					(pts
						(arc
							(start -0.1778 -0.2794)
							(mid -0.249642 -0.249642)
							(end -0.2794 -0.1778)
						)
						(arc
							(start -0.2794 0.1778)
							(mid -0.249642 0.249642)
							(end -0.1778 0.2794)
						)
						(arc
							(start 0.1778 0.2794)
							(mid 0.249642 0.249642)
							(end 0.2794 0.1778)
						)
						(arc
							(start 0.2794 -0.1778)
							(mid 0.249642 -0.249642)
							(end 0.1778 -0.2794)
						)
					)
					(width 0)
					(fill yes)
				)
			)
		)
		(pad "2" smd custom
			(at 0 0.4445 90)
			(size 0.1397 0.1397)
			(layers "F.Cu" "F.Mask" "F.Paste")
			(net "SCL_DR13")
			(options
				(clearance outline)
				(anchor circle)
			)
			(primitives
				(gr_poly
					(pts
						(arc
							(start -0.1778 -0.2794)
							(mid -0.249642 -0.249642)
							(end -0.2794 -0.1778)
						)
						(arc
							(start -0.2794 0.1778)
							(mid -0.249642 0.249642)
							(end -0.1778 0.2794)
						)
						(arc
							(start 0.1778 0.2794)
							(mid 0.249642 0.249642)
							(end 0.2794 0.1778)
						)
						(arc
							(start 0.2794 -0.1778)
							(mid 0.249642 -0.249642)
							(end 0.1778 -0.2794)
						)
					)
					(width 0)
					(fill yes)
				)
			)
		)
	)
	(footprint ""
		(layer "F.Cu")
		(at 89.789 -116.586 90)
		(property "Reference" "R9423"
			(at 0 0 90)
			(layer "F.SilkS")
			(hide yes)
			(effects
				(font
					(size 1.27 1.27)
				)
			)
		)
		(property "Value" "4K7R2J-2-GP"
			(at 0.064008 -3.993896 90)
			(unlocked yes)
			(layer "F.Fab")
			(hide yes)
			(effects
				(font
					(size 1.016 1.016)
					(thickness 0.1524)
				)
			)
		)
		(property "Device Type" "R402H16"
			(at 0.064008 -5.517896 90)
			(unlocked yes)
			(layer "F.Fab")
			(hide yes)
			(effects
				(font
					(size 1.016 1.016)
					(thickness 0.1524)
				)
			)
		)
		(duplicate_pad_numbers_are_jumpers no)
		(fp_line
			(start 0.508 -0.9398)
			(end -0.508 -0.9398)
			(stroke
				(width 0.1524)
				(type default)
			)
			(layer "F.SilkS")
		)
		(fp_line
			(start -0.508 -0.9398)
			(end -0.508 0.9398)
			(stroke
				(width 0.1524)
				(type default)
			)
			(layer "F.SilkS")
		)
		(fp_rect
			(start -0.508 0.9398)
			(end 0.508 -0.9398)
			(stroke
				(width 0)
				(type default)
			)
			(fill no)
			(layer "F.CrtYd")
		)
		(fp_rect
			(start -0.508 0.9398)
			(end 0.508 -0.9398)
			(stroke
				(width 0)
				(type default)
			)
			(fill no)
			(layer "F.Fab")
		)
		(pad "1" smd custom
			(at 0 -0.4445 90)
			(size 0.1397 0.1397)
			(layers "F.Cu" "F.Mask" "F.Paste")
			(net "P3V3")
			(options
				(clearance outline)
				(anchor circle)
			)
			(primitives
				(gr_poly
					(pts
						(arc
							(start -0.1778 -0.2794)
							(mid -0.249642 -0.249642)
							(end -0.2794 -0.1778)
						)
						(arc
							(start -0.2794 0.1778)
							(mid -0.249642 0.249642)
							(end -0.1778 0.2794)
						)
						(arc
							(start 0.1778 0.2794)
							(mid 0.249642 0.249642)
							(end 0.2794 0.1778)
						)
						(arc
							(start 0.2794 -0.1778)
							(mid 0.249642 -0.249642)
							(end 0.1778 -0.2794)
						)
					)
					(width 0)
					(fill yes)
				)
			)
		)
		(pad "2" smd custom
			(at 0 0.4445 90)
			(size 0.1397 0.1397)
			(layers "F.Cu" "F.Mask" "F.Paste")
			(net "SSD_PRSNT_NET13")
			(options
				(clearance outline)
				(anchor circle)
			)
			(primitives
				(gr_poly
					(pts
						(arc
							(start -0.1778 -0.2794)
							(mid -0.249642 -0.249642)
							(end -0.2794 -0.1778)
						)
						(arc
							(start -0.2794 0.1778)
							(mid -0.249642 0.249642)
							(end -0.1778 0.2794)
						)
						(arc
							(start 0.1778 0.2794)
							(mid 0.249642 0.249642)
							(end 0.2794 0.1778)
						)
						(arc
							(start 0.2794 -0.1778)
							(mid 0.249642 -0.249642)
							(end 0.1778 -0.2794)
						)
					)
					(width 0)
					(fill yes)
				)
			)
		)
	)
	(footprint ""
		(layer "F.Cu")
		(at 52.2224 -245.231158 -90)
		(property "Reference" "R9919"
			(at 0 0 270)
			(layer "F.SilkS")
			(hide yes)
			(effects
				(font
					(size 1.27 1.27)
				)
			)
		)
		(property "Value" "47KR2J-2-GP"
			(at 0.064008 -3.993896 270)
			(unlocked yes)
			(layer "F.Fab")
			(hide yes)
			(effects
				(font
					(size 1.016 1.016)
					(thickness 0.1524)
				)
			)
		)
		(property "Device Type" "R402H16"
			(at 0.064008 -5.517896 270)
			(unlocked yes)
			(layer "F.Fab")
			(hide yes)
			(effects
				(font
					(size 1.016 1.016)
					(thickness 0.1524)
				)
			)
		)
		(duplicate_pad_numbers_are_jumpers no)
		(fp_line
			(start -0.508 -0.9398)
			(end -0.508 0.9398)
			(stroke
				(width 0.1524)
				(type default)
			)
			(layer "F.SilkS")
		)
		(fp_line
			(start 0.508 -0.9398)
			(end -0.508 -0.9398)
			(stroke
				(width 0.1524)
				(type default)
			)
			(layer "F.SilkS")
		)
		(fp_rect
			(start -0.508 0.9398)
			(end 0.508 -0.9398)
			(stroke
				(width 0)
				(type default)
			)
			(fill no)
			(layer "F.CrtYd")
		)
		(fp_rect
			(start -0.508 0.9398)
			(end 0.508 -0.9398)
			(stroke
				(width 0)
				(type default)
			)
			(fill no)
			(layer "F.Fab")
		)
		(pad "1" smd custom
			(at 0 -0.4445 270)
			(size 0.1397 0.1397)
			(layers "F.Cu" "F.Mask" "F.Paste")
			(net "P3V3")
			(options
				(clearance outline)
				(anchor circle)
			)
			(primitives
				(gr_poly
					(pts
						(arc
							(start -0.1778 -0.2794)
							(mid -0.249642 -0.249642)
							(end -0.2794 -0.1778)
						)
						(arc
							(start -0.2794 0.1778)
							(mid -0.249642 0.249642)
							(end -0.1778 0.2794)
						)
						(arc
							(start 0.1778 0.2794)
							(mid 0.249642 0.249642)
							(end 0.2794 0.1778)
						)
						(arc
							(start 0.2794 -0.1778)
							(mid 0.249642 -0.249642)
							(end 0.1778 -0.2794)
						)
					)
					(width 0)
					(fill yes)
				)
			)
		)
		(pad "2" smd custom
			(at 0 0.4445 270)
			(size 0.1397 0.1397)
			(layers "F.Cu" "F.Mask" "F.Paste")
			(net "ATTN_LED_DR7_N")
			(options
				(clearance outline)
				(anchor circle)
			)
			(primitives
				(gr_poly
					(pts
						(arc
							(start -0.1778 -0.2794)
							(mid -0.249642 -0.249642)
							(end -0.2794 -0.1778)
						)
						(arc
							(start -0.2794 0.1778)
							(mid -0.249642 0.249642)
							(end -0.1778 0.2794)
						)
						(arc
							(start 0.1778 0.2794)
							(mid 0.249642 0.249642)
							(end 0.2794 0.1778)
						)
						(arc
							(start 0.2794 -0.1778)
							(mid 0.249642 -0.249642)
							(end 0.1778 -0.2794)
						)
					)
					(width 0)
					(fill yes)
				)
			)
		)
	)
	(footprint ""
		(layer "F.Cu")
		(at 208.534 -403.225)
		(property "Reference" "R9761"
			(at 0 0 0)
			(layer "F.SilkS")
			(hide yes)
			(effects
				(font
					(size 1.27 1.27)
				)
			)
		)
		(property "Value" "4K7R2J-2-GP"
			(at 0.064008 -3.993896 0)
			(unlocked yes)
			(layer "F.Fab")
			(hide yes)
			(effects
				(font
					(size 1.016 1.016)
					(thickness 0.1524)
				)
			)
		)
		(property "Device Type" "R402H16"
			(at 0.064008 -5.517896 0)
			(unlocked yes)
			(layer "F.Fab")
			(hide yes)
			(effects
				(font
					(size 1.016 1.016)
					(thickness 0.1524)
				)
			)
		)
		(duplicate_pad_numbers_are_jumpers no)
		(fp_line
			(start -0.508 -0.9398)
			(end -0.508 0.9398)
			(stroke
				(width 0.1524)
				(type default)
			)
			(layer "F.SilkS")
		)
		(fp_line
			(start 0.508 -0.9398)
			(end -0.508 -0.9398)
			(stroke
				(width 0.1524)
				(type default)
			)
			(layer "F.SilkS")
		)
		(fp_rect
			(start -0.508 0.9398)
			(end 0.508 -0.9398)
			(stroke
				(width 0)
				(type default)
			)
			(fill no)
			(layer "F.CrtYd")
		)
		(fp_rect
			(start -0.508 0.9398)
			(end 0.508 -0.9398)
			(stroke
				(width 0)
				(type default)
			)
			(fill no)
			(layer "F.Fab")
		)
		(pad "1" smd custom
			(at 0 -0.4445)
			(size 0.1397 0.1397)
			(layers "F.Cu" "F.Mask" "F.Paste")
			(net "SSD1_PWREN")
			(options
				(clearance outline)
				(anchor circle)
			)
			(primitives
				(gr_poly
					(pts
						(arc
							(start -0.1778 -0.2794)
							(mid -0.249642 -0.249642)
							(end -0.2794 -0.1778)
						)
						(arc
							(start -0.2794 0.1778)
							(mid -0.249642 0.249642)
							(end -0.1778 0.2794)
						)
						(arc
							(start 0.1778 0.2794)
							(mid 0.249642 0.249642)
							(end 0.2794 0.1778)
						)
						(arc
							(start 0.2794 -0.1778)
							(mid 0.249642 -0.249642)
							(end 0.1778 -0.2794)
						)
					)
					(width 0)
					(fill yes)
				)
			)
		)
		(pad "2" smd custom
			(at 0 0.4445)
			(size 0.1397 0.1397)
			(layers "F.Cu" "F.Mask" "F.Paste")
			(net "GND")
			(options
				(clearance outline)
				(anchor circle)
			)
			(primitives
				(gr_poly
					(pts
						(arc
							(start -0.1778 -0.2794)
							(mid -0.249642 -0.249642)
							(end -0.2794 -0.1778)
						)
						(arc
							(start -0.2794 0.1778)
							(mid -0.249642 0.249642)
							(end -0.1778 0.2794)
						)
						(arc
							(start 0.1778 0.2794)
							(mid 0.249642 0.249642)
							(end 0.2794 0.1778)
						)
						(arc
							(start 0.2794 -0.1778)
							(mid 0.249642 -0.249642)
							(end 0.1778 -0.2794)
						)
					)
					(width 0)
					(fill yes)
				)
			)
		)
	)
	(footprint ""
		(layer "F.Cu")
		(at 219.329 -140.58011 90)
		(property "Reference" "SR1127"
			(at 0 0 90)
			(layer "F.SilkS")
			(hide yes)
			(effects
				(font
					(size 1.27 1.27)
				)
			)
		)
		(property "Value" "4K7R2F-GP"
			(at 0.064008 -3.993896 90)
			(unlocked yes)
			(layer "F.Fab")
			(hide yes)
			(effects
				(font
					(size 1.016 1.016)
					(thickness 0.1524)
				)
			)
		)
		(property "Device Type" "R402H16"
			(at 0.064008 -5.517896 90)
			(unlocked yes)
			(layer "F.Fab")
			(hide yes)
			(effects
				(font
					(size 1.016 1.016)
					(thickness 0.1524)
				)
			)
		)
		(duplicate_pad_numbers_are_jumpers no)
		(fp_line
			(start 0.508 -0.9398)
			(end -0.508 -0.9398)
			(stroke
				(width 0.1524)
				(type default)
			)
			(layer "F.SilkS")
		)
		(fp_line
			(start -0.508 -0.9398)
			(end -0.508 0.9398)
			(stroke
				(width 0.1524)
				(type default)
			)
			(layer "F.SilkS")
		)
		(fp_rect
			(start -0.508 0.9398)
			(end 0.508 -0.9398)
			(stroke
				(width 0)
				(type default)
			)
			(fill no)
			(layer "F.CrtYd")
		)
		(fp_rect
			(start -0.508 0.9398)
			(end 0.508 -0.9398)
			(stroke
				(width 0)
				(type default)
			)
			(fill no)
			(layer "F.Fab")
		)
		(pad "1" smd custom
			(at 0 -0.4445 90)
			(size 0.1397 0.1397)
			(layers "F.Cu" "F.Mask" "F.Paste")
			(net "P3V3")
			(options
				(clearance outline)
				(anchor circle)
			)
			(primitives
				(gr_poly
					(pts
						(arc
							(start -0.1778 -0.2794)
							(mid -0.249642 -0.249642)
							(end -0.2794 -0.1778)
						)
						(arc
							(start -0.2794 0.1778)
							(mid -0.249642 0.249642)
							(end -0.1778 0.2794)
						)
						(arc
							(start 0.1778 0.2794)
							(mid 0.249642 0.249642)
							(end 0.2794 0.1778)
						)
						(arc
							(start 0.2794 -0.1778)
							(mid 0.249642 -0.249642)
							(end 0.1778 -0.2794)
						)
					)
					(width 0)
					(fill yes)
				)
			)
		)
		(pad "2" smd custom
			(at 0 0.4445 90)
			(size 0.1397 0.1397)
			(layers "F.Cu" "F.Mask" "F.Paste")
			(net "SSD3_CLK0_OE_MOS_N")
			(options
				(clearance outline)
				(anchor circle)
			)
			(primitives
				(gr_poly
					(pts
						(arc
							(start -0.1778 -0.2794)
							(mid -0.249642 -0.249642)
							(end -0.2794 -0.1778)
						)
						(arc
							(start -0.2794 0.1778)
							(mid -0.249642 0.249642)
							(end -0.1778 0.2794)
						)
						(arc
							(start 0.1778 0.2794)
							(mid 0.249642 0.249642)
							(end 0.2794 0.1778)
						)
						(arc
							(start 0.2794 -0.1778)
							(mid 0.249642 -0.249642)
							(end 0.1778 -0.2794)
						)
					)
					(width 0)
					(fill yes)
				)
			)
		)
	)
	(footprint ""
		(layer "F.Cu")
		(at 84.455 -301.371 90)
		(property "Reference" "R422"
			(at 0 0 90)
			(layer "F.SilkS")
			(hide yes)
			(effects
				(font
					(size 1.27 1.27)
				)
			)
		)
		(property "Value" "0R2J-2-GP"
			(at 0.064008 -3.993896 90)
			(unlocked yes)
			(layer "F.Fab")
			(hide yes)
			(effects
				(font
					(size 1.016 1.016)
					(thickness 0.1524)
				)
			)
		)
		(property "Device Type" "R402H16"
			(at 0.064008 -5.517896 90)
			(unlocked yes)
			(layer "F.Fab")
			(hide yes)
			(effects
				(font
					(size 1.016 1.016)
					(thickness 0.1524)
				)
			)
		)
		(duplicate_pad_numbers_are_jumpers no)
		(fp_line
			(start 0.508 -0.9398)
			(end -0.508 -0.9398)
			(stroke
				(width 0.1524)
				(type default)
			)
			(layer "F.SilkS")
		)
		(fp_line
			(start -0.508 -0.9398)
			(end -0.508 0.9398)
			(stroke
				(width 0.1524)
				(type default)
			)
			(layer "F.SilkS")
		)
		(fp_rect
			(start -0.508 0.9398)
			(end 0.508 -0.9398)
			(stroke
				(width 0)
				(type default)
			)
			(fill no)
			(layer "F.CrtYd")
		)
		(fp_rect
			(start -0.508 0.9398)
			(end 0.508 -0.9398)
			(stroke
				(width 0)
				(type default)
			)
			(fill no)
			(layer "F.Fab")
		)
		(pad "1" smd custom
			(at 0 -0.4445 90)
			(size 0.1397 0.1397)
			(layers "F.Cu" "F.Mask" "F.Paste")
			(net "BMC_I2C_SDA_BUF_9")
			(options
				(clearance outline)
				(anchor circle)
			)
			(primitives
				(gr_poly
					(pts
						(arc
							(start -0.1778 -0.2794)
							(mid -0.249642 -0.249642)
							(end -0.2794 -0.1778)
						)
						(arc
							(start -0.2794 0.1778)
							(mid -0.249642 0.249642)
							(end -0.1778 0.2794)
						)
						(arc
							(start 0.1778 0.2794)
							(mid 0.249642 0.249642)
							(end 0.2794 0.1778)
						)
						(arc
							(start 0.2794 -0.1778)
							(mid 0.249642 -0.249642)
							(end 0.1778 -0.2794)
						)
					)
					(width 0)
					(fill yes)
				)
			)
		)
		(pad "2" smd custom
			(at 0 0.4445 90)
			(size 0.1397 0.1397)
			(layers "F.Cu" "F.Mask" "F.Paste")
			(net "I2C_SDA_BUF_9_EU2_R")
			(options
				(clearance outline)
				(anchor circle)
			)
			(primitives
				(gr_poly
					(pts
						(arc
							(start -0.1778 -0.2794)
							(mid -0.249642 -0.249642)
							(end -0.2794 -0.1778)
						)
						(arc
							(start -0.2794 0.1778)
							(mid -0.249642 0.249642)
							(end -0.1778 0.2794)
						)
						(arc
							(start 0.1778 0.2794)
							(mid 0.249642 0.249642)
							(end 0.2794 0.1778)
						)
						(arc
							(start 0.2794 -0.1778)
							(mid 0.249642 -0.249642)
							(end 0.1778 -0.2794)
						)
					)
					(width 0)
					(fill yes)
				)
			)
		)
	)
	(footprint ""
		(layer "F.Cu")
		(at 221.0054 -301.5996 -90)
		(property "Reference" "R9792"
			(at 0 0 270)
			(layer "F.SilkS")
			(hide yes)
			(effects
				(font
					(size 1.27 1.27)
				)
			)
		)
		(property "Value" "2K2R5F-GP"
			(at 0 -8.9535 270)
			(unlocked yes)
			(layer "F.Fab")
			(hide yes)
			(effects
				(font
					(size 1.27 1.016)
					(thickness 0.1524)
				)
			)
		)
		(property "Device Type" "R805H24"
			(at 0 -10.6299 270)
			(unlocked yes)
			(layer "F.Fab")
			(hide yes)
			(effects
				(font
					(size 1.27 1.016)
					(thickness 0.1524)
				)
			)
		)
		(duplicate_pad_numbers_are_jumpers no)
		(fp_line
			(start -0.889 1.7018)
			(end 0.889 1.7018)
			(stroke
				(width 0.1524)
				(type default)
			)
			(layer "F.SilkS")
		)
		(fp_line
			(start 0.889 1.7018)
			(end 0.889 -0.508)
			(stroke
				(width 0.1524)
				(type default)
			)
			(layer "F.SilkS")
		)
		(fp_line
			(start -0.889 0.0762)
			(end -0.889 1.7018)
			(stroke
				(width 0.1524)
				(type default)
			)
			(layer "F.SilkS")
		)
		(fp_line
			(start -0.889 -1.7018)
			(end -0.889 0.2794)
			(stroke
				(width 0.1524)
				(type default)
			)
			(layer "F.SilkS")
		)
		(fp_line
			(start 0.889 -1.7018)
			(end 0.889 -0.381)
			(stroke
				(width 0.1524)
				(type default)
			)
			(layer "F.SilkS")
		)
		(fp_line
			(start 0.889 -1.7018)
			(end -0.889 -1.7018)
			(stroke
				(width 0.1524)
				(type default)
			)
			(layer "F.SilkS")
		)
		(fp_poly
			(pts
				(xy 0.9652 -1.778) (xy 0.9652 1.778) (xy -0.9652 1.778) (xy -0.9652 -1.778)
			)
			(stroke
				(width 0)
				(type default)
			)
			(fill no)
			(layer "F.CrtYd")
		)
		(fp_rect
			(start -0.9652 1.778)
			(end 0.9652 -1.778)
			(stroke
				(width 0)
				(type default)
			)
			(fill no)
			(layer "F.Fab")
		)
		(pad "1" smd rect
			(at 0 -0.9652 270)
			(size 1.397 1.143)
			(layers "F.Cu" "F.Mask" "F.Paste")
			(net "P12V_SSD2")
		)
		(pad "2" smd rect
			(at 0 0.9652 270)
			(size 1.397 1.143)
			(layers "F.Cu" "F.Mask" "F.Paste")
			(net "P12V_MOST2_GATE_D")
		)
	)
	(footprint ""
		(layer "F.Cu")
		(at 39.37 -347.48089 180)
		(property "Reference" "Q59"
			(at 0 0 180)
			(layer "F.SilkS")
			(hide yes)
			(effects
				(font
					(size 1.27 1.27)
				)
			)
		)
		(property "Value" "2N7002A-7-GP"
			(at 0.127 -8.9662 180)
			(unlocked yes)
			(layer "F.Fab")
			(hide yes)
			(effects
				(font
					(size 1.016 1.016)
					(thickness 0.1524)
				)
			)
		)
		(property "Device Type" "SOT23DGS2D4H48"
			(at 0.127 -10.4902 180)
			(unlocked yes)
			(layer "F.Fab")
			(hide yes)
			(effects
				(font
					(size 1.016 1.016)
					(thickness 0.1524)
				)
			)
		)
		(duplicate_pad_numbers_are_jumpers no)
		(fp_line
			(start 1.651 1.778)
			(end 1.651 -1.778)
			(stroke
				(width 0.1524)
				(type default)
			)
			(layer "F.SilkS")
		)
		(fp_line
			(start 1.651 -1.778)
			(end -1.651 -1.778)
			(stroke
				(width 0.1524)
				(type default)
			)
			(layer "F.SilkS")
		)
		(fp_line
			(start -1.651 1.778)
			(end 1.651 1.778)
			(stroke
				(width 0.1524)
				(type default)
			)
			(layer "F.SilkS")
		)
		(fp_line
			(start -1.651 -1.778)
			(end -1.651 1.778)
			(stroke
				(width 0.1524)
				(type default)
			)
			(layer "F.SilkS")
		)
		(fp_poly
			(pts
				(xy -1.778 1.8796) (xy -1.778 -1.8796) (xy 1.778 -1.8796) (xy 1.778 1.8796)
			)
			(stroke
				(width 0)
				(type default)
			)
			(fill no)
			(layer "F.CrtYd")
		)
		(fp_poly
			(pts
				(xy -1.778 1.8796) (xy -1.778 -1.8796) (xy 1.778 -1.8796) (xy 1.778 1.8796)
			)
			(stroke
				(width 0)
				(type default)
			)
			(fill no)
			(layer "F.Fab")
		)
		(pad "D" smd custom
			(at 0 -0.9525 180)
			(size 0.1905 0.1905)
			(layers "F.Cu" "F.Mask" "F.Paste")
			(net "SSD6_CLK0_OE_MOS_N")
			(options
				(clearance outline)
				(anchor circle)
			)
			(primitives
				(gr_poly
					(pts
						(arc
							(start -0.1778 0.5715)
							(mid -0.321484 0.511984)
							(end -0.381 0.3683)
						)
						(arc
							(start -0.381 -0.3683)
							(mid -0.321484 -0.511984)
							(end -0.1778 -0.5715)
						)
						(arc
							(start 0.1778 -0.5715)
							(mid 0.321484 -0.511984)
							(end 0.381 -0.3683)
						)
						(arc
							(start 0.381 0.3683)
							(mid 0.321484 0.511984)
							(end 0.1778 0.5715)
						)
					)
					(width 0)
					(fill yes)
				)
			)
		)
		(pad "G" smd custom
			(at -0.98425 0.9525 180)
			(size 0.1905 0.1905)
			(layers "F.Cu" "F.Mask" "F.Paste")
			(net "SSD6_CLK0_OE_R_N")
			(options
				(clearance outline)
				(anchor circle)
			)
			(primitives
				(gr_poly
					(pts
						(arc
							(start -0.1778 0.5715)
							(mid -0.321484 0.511984)
							(end -0.381 0.3683)
						)
						(arc
							(start -0.381 -0.3683)
							(mid -0.321484 -0.511984)
							(end -0.1778 -0.5715)
						)
						(arc
							(start 0.1778 -0.5715)
							(mid 0.321484 -0.511984)
							(end 0.381 -0.3683)
						)
						(arc
							(start 0.381 0.3683)
							(mid 0.321484 0.511984)
							(end 0.1778 0.5715)
						)
					)
					(width 0)
					(fill yes)
				)
			)
		)
		(pad "S" smd custom
			(at 0.98425 0.9525 180)
			(size 0.1905 0.1905)
			(layers "F.Cu" "F.Mask" "F.Paste")
			(net "GND")
			(options
				(clearance outline)
				(anchor circle)
			)
			(primitives
				(gr_poly
					(pts
						(arc
							(start -0.1778 0.5715)
							(mid -0.321484 0.511984)
							(end -0.381 0.3683)
						)
						(arc
							(start -0.381 -0.3683)
							(mid -0.321484 -0.511984)
							(end -0.1778 -0.5715)
						)
						(arc
							(start 0.1778 -0.5715)
							(mid 0.321484 -0.511984)
							(end 0.381 -0.3683)
						)
						(arc
							(start 0.381 0.3683)
							(mid 0.321484 0.511984)
							(end 0.1778 0.5715)
						)
					)
					(width 0)
					(fill yes)
				)
			)
		)
	)
	(footprint ""
		(layer "F.Cu")
		(at 8.50011 -71.499984)
		(property "Reference" "H9"
			(at 0 0 0)
			(layer "F.SilkS")
			(hide yes)
			(effects
				(font
					(size 1.27 1.27)
				)
			)
		)
		(property "Value" "GEN276X162R197X296-6-F-A-GP"
			(at -6.7183 4.1402 0)
			(unlocked yes)
			(layer "F.Fab")
			(hide yes)
			(effects
				(font
					(size 1.016 1.016)
					(thickness 0.1524)
				)
			)
		)
		(property "Device Type" "GEN276X162R197X296-6-F-A"
			(at -6.7183 2.6162 0)
			(unlocked yes)
			(layer "F.Fab")
			(hide yes)
			(effects
				(font
					(size 1.016 1.016)
					(thickness 0.1524)
				)
			)
		)
		(duplicate_pad_numbers_are_jumpers no)
		(fp_poly
			(pts
				(arc
					(start 2.723642 4.777232)
					(mid -0.000169 6.508462)
					(end -2.723896 4.776978)
				)
				(arc
					(start -2.723896 4.776978)
					(mid 0.000173 -5.499012)
					(end 2.723642 4.777232)
				)
			)
			(stroke
				(width 0)
				(type default)
			)
			(fill no)
			(layer "B.CrtYd")
		)
		(fp_poly
			(pts
				(arc
					(start 2.723642 4.777232)
					(mid -0.000169 6.508462)
					(end -2.723896 4.776978)
				)
				(arc
					(start -2.723896 4.776978)
					(mid 0.000173 -5.499012)
					(end 2.723642 4.777232)
				)
			)
			(stroke
				(width 0)
				(type default)
			)
			(fill no)
			(layer "F.CrtYd")
		)
		(fp_poly
			(pts
				(arc
					(start 2.723642 4.777232)
					(mid -0.000169 6.508462)
					(end -2.723896 4.776978)
				)
				(arc
					(start -2.723896 4.776978)
					(mid 0.000173 -5.499012)
					(end 2.723642 4.777232)
				)
			)
			(stroke
				(width 0)
				(type default)
			)
			(fill no)
			(layer "B.Fab")
		)
		(fp_poly
			(pts
				(arc
					(start 2.723642 4.777232)
					(mid -0.000169 6.508462)
					(end -2.723896 4.776978)
				)
				(arc
					(start -2.723896 4.776978)
					(mid 0.000173 -5.499012)
					(end 2.723642 4.777232)
				)
			)
			(stroke
				(width 0)
				(type default)
			)
			(fill no)
			(layer "F.Fab")
		)
		(pad "" np_thru_hole circle
			(at 0 0)
			(size 0.254 0.254)
			(drill 0.0254)
			(layers "*.Cu" "*.Mask")
			(clearance 3.135376)
			(thermal_gap 3.135376)
		)
		(pad "1" thru_hole circle
			(at 2.549906 0)
			(size 0.8636 0.8636)
			(drill 0.508)
			(layers "*.Cu" "*.Mask")
			(remove_unused_layers no)
			(net "GND")
			(clearance 0.8255)
			(thermal_gap 0.8255)
		)
		(pad "2" thru_hole circle
			(at 2.210054 -1.27)
			(size 0.8636 0.8636)
			(drill 0.508)
			(layers "*.Cu" "*.Mask")
			(remove_unused_layers no)
			(net "GND")
			(clearance 0.8255)
			(thermal_gap 0.8255)
		)
		(pad "3" thru_hole circle
			(at 1.27 -2.210054)
			(size 0.8636 0.8636)
			(drill 0.508)
			(layers "*.Cu" "*.Mask")
			(remove_unused_layers no)
			(net "GND")
			(clearance 0.8255)
			(thermal_gap 0.8255)
		)
		(pad "4" thru_hole circle
			(at -1.279906 -2.210054)
			(size 0.8636 0.8636)
			(drill 0.508)
			(layers "*.Cu" "*.Mask")
			(remove_unused_layers no)
			(net "GND")
			(clearance 0.8255)
			(thermal_gap 0.8255)
		)
		(pad "5" thru_hole circle
			(at -2.210054 -1.27)
			(size 0.8636 0.8636)
			(drill 0.508)
			(layers "*.Cu" "*.Mask")
			(remove_unused_layers no)
			(net "GND")
			(clearance 0.8255)
			(thermal_gap 0.8255)
		)
		(pad "6" thru_hole circle
			(at -2.549906 0)
			(size 0.8636 0.8636)
			(drill 0.508)
			(layers "*.Cu" "*.Mask")
			(remove_unused_layers no)
			(net "GND")
			(clearance 0.8255)
			(thermal_gap 0.8255)
		)
		(zone
			(layers "F.Cu" "B.Cu" "In1.Cu" "In2.Cu" "In3.Cu" "In4.Cu" "In5.Cu" "In6.Cu")
			(hatch none 0.5)
			(connect_pads
				(clearance 0)
			)
			(min_thickness 0.25)
			(keepout
				(tracks allowed)
				(vias not_allowed)
				(pads allowed)
				(copperpour not_allowed)
				(footprints allowed)
			)
			(placement
				(enabled no)
				(sheetname "")
			)
			(fill
				(thermal_gap 0.5)
				(thermal_bridge_width 0.5)
				(island_removal_mode 0)
			)
			(polygon
				(pts
					(arc
						(start 12.81811 -71.503032)
						(mid 4.18211 -71.503032)
						(end 12.81811 -71.503032)
					)
				)
			)
		)
		(zone
			(layers "F.Cu" "B.Cu" "In1.Cu" "In2.Cu" "In3.Cu" "In4.Cu" "In5.Cu" "In6.Cu")
			(hatch none 0.5)
			(connect_pads
				(clearance 0)
			)
			(min_thickness 0.25)
			(keepout
				(tracks not_allowed)
				(vias allowed)
				(pads allowed)
				(copperpour not_allowed)
				(footprints allowed)
			)
			(placement
				(enabled no)
				(sheetname "")
			)
			(fill
				(thermal_gap 0.5)
				(thermal_bridge_width 0.5)
				(island_removal_mode 0)
			)
			(polygon
				(pts
					(arc
						(start 10.83945 -69.89064)
						(mid 8.50019 -64.991537)
						(end 6.160516 -69.89064)
					)
					(arc
						(start 6.160516 -69.89064)
						(mid 6.406483 -70.331006)
						(end 6.491732 -70.828154)
					)
					(arc
						(start 6.491732 -71.499984)
						(mid 8.50011 -73.508362)
						(end 10.508234 -71.499984)
					)
					(arc
						(start 10.508234 -70.828154)
						(mid 10.593469 -70.331)
						(end 10.83945 -69.89064)
					)
				)
			)
		)
	)
	(footprint ""
		(layer "F.Cu")
		(at 24.003 -259.334 -90)
		(property "Reference" "R9477"
			(at 0 0 270)
			(layer "F.SilkS")
			(hide yes)
			(effects
				(font
					(size 1.27 1.27)
				)
			)
		)
		(property "Value" "330R2F-GP"
			(at 0.064008 -3.993896 270)
			(unlocked yes)
			(layer "F.Fab")
			(hide yes)
			(effects
				(font
					(size 1.016 1.016)
					(thickness 0.1524)
				)
			)
		)
		(property "Device Type" "R402H16"
			(at 0.064008 -5.517896 270)
			(unlocked yes)
			(layer "F.Fab")
			(hide yes)
			(effects
				(font
					(size 1.016 1.016)
					(thickness 0.1524)
				)
			)
		)
		(duplicate_pad_numbers_are_jumpers no)
		(fp_line
			(start -0.508 -0.9398)
			(end -0.508 0.9398)
			(stroke
				(width 0.1524)
				(type default)
			)
			(layer "F.SilkS")
		)
		(fp_line
			(start 0.508 -0.9398)
			(end -0.508 -0.9398)
			(stroke
				(width 0.1524)
				(type default)
			)
			(layer "F.SilkS")
		)
		(fp_rect
			(start -0.508 0.9398)
			(end 0.508 -0.9398)
			(stroke
				(width 0)
				(type default)
			)
			(fill no)
			(layer "F.CrtYd")
		)
		(fp_rect
			(start -0.508 0.9398)
			(end 0.508 -0.9398)
			(stroke
				(width 0)
				(type default)
			)
			(fill no)
			(layer "F.Fab")
		)
		(pad "1" smd custom
			(at 0 -0.4445 270)
			(size 0.1397 0.1397)
			(layers "F.Cu" "F.Mask" "F.Paste")
			(net "P3V3")
			(options
				(clearance outline)
				(anchor circle)
			)
			(primitives
				(gr_poly
					(pts
						(arc
							(start -0.1778 -0.2794)
							(mid -0.249642 -0.249642)
							(end -0.2794 -0.1778)
						)
						(arc
							(start -0.2794 0.1778)
							(mid -0.249642 0.249642)
							(end -0.1778 0.2794)
						)
						(arc
							(start 0.1778 0.2794)
							(mid 0.249642 0.249642)
							(end 0.2794 0.1778)
						)
						(arc
							(start 0.2794 -0.1778)
							(mid 0.249642 -0.249642)
							(end 0.1778 -0.2794)
						)
					)
					(width 0)
					(fill yes)
				)
			)
		)
		(pad "2" smd custom
			(at 0 0.4445 270)
			(size 0.1397 0.1397)
			(layers "F.Cu" "F.Mask" "F.Paste")
			(net "DRV_ATTN_12")
			(options
				(clearance outline)
				(anchor circle)
			)
			(primitives
				(gr_poly
					(pts
						(arc
							(start -0.1778 -0.2794)
							(mid -0.249642 -0.249642)
							(end -0.2794 -0.1778)
						)
						(arc
							(start -0.2794 0.1778)
							(mid -0.249642 0.249642)
							(end -0.1778 0.2794)
						)
						(arc
							(start 0.1778 0.2794)
							(mid 0.249642 0.249642)
							(end 0.2794 0.1778)
						)
						(arc
							(start 0.2794 -0.1778)
							(mid 0.249642 -0.249642)
							(end 0.1778 -0.2794)
						)
					)
					(width 0)
					(fill yes)
				)
			)
		)
	)
	(footprint ""
		(layer "F.Cu")
		(at 70.739 -145.542 90)
		(property "Reference" "SR966"
			(at 0 0 90)
			(layer "F.SilkS")
			(hide yes)
			(effects
				(font
					(size 1.27 1.27)
				)
			)
		)
		(property "Value" "2KR2F-3-GP"
			(at 0.064008 -3.993896 90)
			(unlocked yes)
			(layer "F.Fab")
			(hide yes)
			(effects
				(font
					(size 1.016 1.016)
					(thickness 0.1524)
				)
			)
		)
		(property "Device Type" "R402H16"
			(at 0.064008 -5.517896 90)
			(unlocked yes)
			(layer "F.Fab")
			(hide yes)
			(effects
				(font
					(size 1.016 1.016)
					(thickness 0.1524)
				)
			)
		)
		(duplicate_pad_numbers_are_jumpers no)
		(fp_line
			(start 0.508 -0.9398)
			(end -0.508 -0.9398)
			(stroke
				(width 0.1524)
				(type default)
			)
			(layer "F.SilkS")
		)
		(fp_line
			(start -0.508 -0.9398)
			(end -0.508 0.9398)
			(stroke
				(width 0.1524)
				(type default)
			)
			(layer "F.SilkS")
		)
		(fp_rect
			(start -0.508 0.9398)
			(end 0.508 -0.9398)
			(stroke
				(width 0)
				(type default)
			)
			(fill no)
			(layer "F.CrtYd")
		)
		(fp_rect
			(start -0.508 0.9398)
			(end 0.508 -0.9398)
			(stroke
				(width 0)
				(type default)
			)
			(fill no)
			(layer "F.Fab")
		)
		(pad "1" smd custom
			(at 0 -0.4445 90)
			(size 0.1397 0.1397)
			(layers "F.Cu" "F.Mask" "F.Paste")
			(net "P3V3")
			(options
				(clearance outline)
				(anchor circle)
			)
			(primitives
				(gr_poly
					(pts
						(arc
							(start -0.1778 -0.2794)
							(mid -0.249642 -0.249642)
							(end -0.2794 -0.1778)
						)
						(arc
							(start -0.2794 0.1778)
							(mid -0.249642 0.249642)
							(end -0.1778 0.2794)
						)
						(arc
							(start 0.1778 0.2794)
							(mid 0.249642 0.249642)
							(end 0.2794 0.1778)
						)
						(arc
							(start 0.2794 -0.1778)
							(mid 0.249642 -0.249642)
							(end 0.1778 -0.2794)
						)
					)
					(width 0)
					(fill yes)
				)
			)
		)
		(pad "2" smd custom
			(at 0 0.4445 90)
			(size 0.1397 0.1397)
			(layers "F.Cu" "F.Mask" "F.Paste")
			(net "SDA_DR9")
			(options
				(clearance outline)
				(anchor circle)
			)
			(primitives
				(gr_poly
					(pts
						(arc
							(start -0.1778 -0.2794)
							(mid -0.249642 -0.249642)
							(end -0.2794 -0.1778)
						)
						(arc
							(start -0.2794 0.1778)
							(mid -0.249642 0.249642)
							(end -0.1778 0.2794)
						)
						(arc
							(start 0.1778 0.2794)
							(mid 0.249642 0.249642)
							(end 0.2794 0.1778)
						)
						(arc
							(start 0.2794 -0.1778)
							(mid 0.249642 -0.249642)
							(end 0.1778 -0.2794)
						)
					)
					(width 0)
					(fill yes)
				)
			)
		)
	)
	(footprint ""
		(layer "F.Cu")
		(at 23.998174 -371.083332 -90)
		(property "Reference" "U208"
			(at 0 0 270)
			(layer "F.SilkS")
			(hide yes)
			(effects
				(font
					(size 1.27 1.27)
				)
			)
		)
		(property "Value" "SN74LVC1G08DCKR-GP"
			(at -2.3368 -8.6868 270)
			(unlocked yes)
			(layer "F.Fab")
			(hide yes)
			(effects
				(font
					(size 1.016 1.016)
					(thickness 0.1524)
				)
			)
		)
		(property "Device Type" "SC70-5H44"
			(at -2.3114 -10.414 270)
			(unlocked yes)
			(layer "F.Fab")
			(hide yes)
			(effects
				(font
					(size 1.016 1.016)
					(thickness 0.1524)
				)
			)
		)
		(duplicate_pad_numbers_are_jumpers no)
		(fp_line
			(start -1.27 1.7018)
			(end -1.27 -1.7018)
			(stroke
				(width 0.1524)
				(type default)
			)
			(layer "F.SilkS")
		)
		(fp_line
			(start 1.27 1.7018)
			(end -1.27 1.7018)
			(stroke
				(width 0.1524)
				(type default)
			)
			(layer "F.SilkS")
		)
		(fp_line
			(start -1.27 -1.7018)
			(end 1.27 -1.7018)
			(stroke
				(width 0.1524)
				(type default)
			)
			(layer "F.SilkS")
		)
		(fp_line
			(start 1.27 -1.7018)
			(end 1.27 1.7018)
			(stroke
				(width 0.1524)
				(type default)
			)
			(layer "F.SilkS")
		)
		(fp_line
			(start 0.6604 -1.8034)
			(end 1.3843 -1.8034)
			(stroke
				(width 0.3302)
				(type default)
			)
			(layer "F.SilkS")
		)
		(fp_line
			(start 1.3843 -1.8034)
			(end 1.3843 -1.1176)
			(stroke
				(width 0.3302)
				(type default)
			)
			(layer "F.SilkS")
		)
		(fp_rect
			(start -1.524 1.9558)
			(end 1.524 -1.9558)
			(stroke
				(width 0)
				(type default)
			)
			(fill no)
			(layer "F.CrtYd")
		)
		(fp_poly
			(pts
				(xy -1.524 -1.9558) (xy 1.524 -1.9558) (xy 1.524 1.9558) (xy -1.524 1.9558)
			)
			(stroke
				(width 0)
				(type default)
			)
			(fill no)
			(layer "F.Fab")
		)
		(pad "1" smd rect
			(at 0.65024 -0.8255 270)
			(size 0.4064 1.2192)
			(layers "F.Cu" "F.Mask" "F.Paste")
			(net "SSD11_CLK0_OE_MOS_N")
		)
		(pad "2" smd rect
			(at 0 -0.8255 270)
			(size 0.4064 1.2192)
			(layers "F.Cu" "F.Mask" "F.Paste")
			(net "ATTN_LED_DR11_N")
		)
		(pad "3" smd rect
			(at -0.65024 -0.8255 270)
			(size 0.4064 1.2192)
			(layers "F.Cu" "F.Mask" "F.Paste")
			(net "GND")
		)
		(pad "4" smd rect
			(at -0.65024 0.8255 270)
			(size 0.4064 1.2192)
			(layers "F.Cu" "F.Mask" "F.Paste")
			(net "ATTN_LED_DR11_AND")
		)
		(pad "5" smd rect
			(at 0.65024 0.8255 270)
			(size 0.4064 1.2192)
			(layers "F.Cu" "F.Mask" "F.Paste")
			(net "P3V3")
		)
	)
	(footprint ""
		(layer "F.Cu")
		(at 222.123 -142.10411)
		(property "Reference" "Q45"
			(at 0 0 0)
			(layer "F.SilkS")
			(hide yes)
			(effects
				(font
					(size 1.27 1.27)
				)
			)
		)
		(property "Value" "2N7002A-7-GP"
			(at 0.127 -8.9662 0)
			(unlocked yes)
			(layer "F.Fab")
			(hide yes)
			(effects
				(font
					(size 1.016 1.016)
					(thickness 0.1524)
				)
			)
		)
		(property "Device Type" "SOT23DGS2D4H48"
			(at 0.127 -10.4902 0)
			(unlocked yes)
			(layer "F.Fab")
			(hide yes)
			(effects
				(font
					(size 1.016 1.016)
					(thickness 0.1524)
				)
			)
		)
		(duplicate_pad_numbers_are_jumpers no)
		(fp_line
			(start -1.651 -1.778)
			(end -1.651 1.778)
			(stroke
				(width 0.1524)
				(type default)
			)
			(layer "F.SilkS")
		)
		(fp_line
			(start -1.651 1.778)
			(end 1.651 1.778)
			(stroke
				(width 0.1524)
				(type default)
			)
			(layer "F.SilkS")
		)
		(fp_line
			(start 1.651 -1.778)
			(end -1.651 -1.778)
			(stroke
				(width 0.1524)
				(type default)
			)
			(layer "F.SilkS")
		)
		(fp_line
			(start 1.651 1.778)
			(end 1.651 -1.778)
			(stroke
				(width 0.1524)
				(type default)
			)
			(layer "F.SilkS")
		)
		(fp_poly
			(pts
				(xy -1.778 1.8796) (xy -1.778 -1.8796) (xy 1.778 -1.8796) (xy 1.778 1.8796)
			)
			(stroke
				(width 0)
				(type default)
			)
			(fill no)
			(layer "F.CrtYd")
		)
		(fp_poly
			(pts
				(xy -1.778 1.8796) (xy -1.778 -1.8796) (xy 1.778 -1.8796) (xy 1.778 1.8796)
			)
			(stroke
				(width 0)
				(type default)
			)
			(fill no)
			(layer "F.Fab")
		)
		(pad "D" smd custom
			(at 0 -0.9525)
			(size 0.1905 0.1905)
			(layers "F.Cu" "F.Mask" "F.Paste")
			(net "ATTN_LED_DR3_MOS_N")
			(options
				(clearance outline)
				(anchor circle)
			)
			(primitives
				(gr_poly
					(pts
						(arc
							(start -0.1778 0.5715)
							(mid -0.321484 0.511984)
							(end -0.381 0.3683)
						)
						(arc
							(start -0.381 -0.3683)
							(mid -0.321484 -0.511984)
							(end -0.1778 -0.5715)
						)
						(arc
							(start 0.1778 -0.5715)
							(mid 0.321484 -0.511984)
							(end 0.381 -0.3683)
						)
						(arc
							(start 0.381 0.3683)
							(mid 0.321484 0.511984)
							(end 0.1778 0.5715)
						)
					)
					(width 0)
					(fill yes)
				)
			)
		)
		(pad "G" smd custom
			(at -0.98425 0.9525)
			(size 0.1905 0.1905)
			(layers "F.Cu" "F.Mask" "F.Paste")
			(net "SSD3_CLK0_OE_MOS_N")
			(options
				(clearance outline)
				(anchor circle)
			)
			(primitives
				(gr_poly
					(pts
						(arc
							(start -0.1778 0.5715)
							(mid -0.321484 0.511984)
							(end -0.381 0.3683)
						)
						(arc
							(start -0.381 -0.3683)
							(mid -0.321484 -0.511984)
							(end -0.1778 -0.5715)
						)
						(arc
							(start 0.1778 -0.5715)
							(mid 0.321484 -0.511984)
							(end 0.381 -0.3683)
						)
						(arc
							(start 0.381 0.3683)
							(mid 0.321484 0.511984)
							(end 0.1778 0.5715)
						)
					)
					(width 0)
					(fill yes)
				)
			)
		)
		(pad "S" smd custom
			(at 0.98425 0.9525)
			(size 0.1905 0.1905)
			(layers "F.Cu" "F.Mask" "F.Paste")
			(net "ATTN_LED_DR3_R")
			(options
				(clearance outline)
				(anchor circle)
			)
			(primitives
				(gr_poly
					(pts
						(arc
							(start -0.1778 0.5715)
							(mid -0.321484 0.511984)
							(end -0.381 0.3683)
						)
						(arc
							(start -0.381 -0.3683)
							(mid -0.321484 -0.511984)
							(end -0.1778 -0.5715)
						)
						(arc
							(start 0.1778 -0.5715)
							(mid 0.321484 -0.511984)
							(end 0.381 -0.3683)
						)
						(arc
							(start 0.381 0.3683)
							(mid 0.321484 0.511984)
							(end 0.1778 0.5715)
						)
					)
					(width 0)
					(fill yes)
				)
			)
		)
	)
	(footprint ""
		(layer "F.Cu")
		(at 90.297 -110.236 180)
		(property "Reference" "R9062"
			(at 0 0 180)
			(layer "F.SilkS")
			(hide yes)
			(effects
				(font
					(size 1.27 1.27)
				)
			)
		)
		(property "Value" "27R2F-GP"
			(at 0.064008 -3.993896 180)
			(unlocked yes)
			(layer "F.Fab")
			(hide yes)
			(effects
				(font
					(size 1.016 1.016)
					(thickness 0.1524)
				)
			)
		)
		(property "Device Type" "R402H16"
			(at 0.064008 -5.517896 180)
			(unlocked yes)
			(layer "F.Fab")
			(hide yes)
			(effects
				(font
					(size 1.016 1.016)
					(thickness 0.1524)
				)
			)
		)
		(duplicate_pad_numbers_are_jumpers no)
		(fp_line
			(start 0.508 -0.9398)
			(end -0.508 -0.9398)
			(stroke
				(width 0.1524)
				(type default)
			)
			(layer "F.SilkS")
		)
		(fp_line
			(start -0.508 -0.9398)
			(end -0.508 0.9398)
			(stroke
				(width 0.1524)
				(type default)
			)
			(layer "F.SilkS")
		)
		(fp_rect
			(start -0.508 0.9398)
			(end 0.508 -0.9398)
			(stroke
				(width 0)
				(type default)
			)
			(fill no)
			(layer "F.CrtYd")
		)
		(fp_rect
			(start -0.508 0.9398)
			(end 0.508 -0.9398)
			(stroke
				(width 0)
				(type default)
			)
			(fill no)
			(layer "F.Fab")
		)
		(pad "1" smd custom
			(at 0 -0.4445 180)
			(size 0.1397 0.1397)
			(layers "F.Cu" "F.Mask" "F.Paste")
			(net "PE_CLK_100M_DR13_2_R_N")
			(options
				(clearance outline)
				(anchor circle)
			)
			(primitives
				(gr_poly
					(pts
						(arc
							(start -0.1778 -0.2794)
							(mid -0.249642 -0.249642)
							(end -0.2794 -0.1778)
						)
						(arc
							(start -0.2794 0.1778)
							(mid -0.249642 0.249642)
							(end -0.1778 0.2794)
						)
						(arc
							(start 0.1778 0.2794)
							(mid 0.249642 0.249642)
							(end 0.2794 0.1778)
						)
						(arc
							(start 0.2794 -0.1778)
							(mid 0.249642 -0.249642)
							(end 0.1778 -0.2794)
						)
					)
					(width 0)
					(fill yes)
				)
			)
		)
		(pad "2" smd custom
			(at 0 0.4445 180)
			(size 0.1397 0.1397)
			(layers "F.Cu" "F.Mask" "F.Paste")
			(net "PE_CLK100M_DR13_2_N")
			(options
				(clearance outline)
				(anchor circle)
			)
			(primitives
				(gr_poly
					(pts
						(arc
							(start -0.1778 -0.2794)
							(mid -0.249642 -0.249642)
							(end -0.2794 -0.1778)
						)
						(arc
							(start -0.2794 0.1778)
							(mid -0.249642 0.249642)
							(end -0.1778 0.2794)
						)
						(arc
							(start 0.1778 0.2794)
							(mid 0.249642 0.249642)
							(end 0.2794 0.1778)
						)
						(arc
							(start 0.2794 -0.1778)
							(mid 0.249642 -0.249642)
							(end 0.1778 -0.2794)
						)
					)
					(width 0)
					(fill yes)
				)
			)
		)
	)
	(footprint ""
		(layer "F.Cu")
		(at 203.454 -460.248 90)
		(property "Reference" "R314"
			(at 0 0 90)
			(layer "F.SilkS")
			(hide yes)
			(effects
				(font
					(size 1.27 1.27)
				)
			)
		)
		(property "Value" "0R2J-2-GP"
			(at 0.064008 -3.993896 90)
			(unlocked yes)
			(layer "F.Fab")
			(hide yes)
			(effects
				(font
					(size 1.016 1.016)
					(thickness 0.1524)
				)
			)
		)
		(property "Device Type" "R402H16"
			(at 0.064008 -5.517896 90)
			(unlocked yes)
			(layer "F.Fab")
			(hide yes)
			(effects
				(font
					(size 1.016 1.016)
					(thickness 0.1524)
				)
			)
		)
		(duplicate_pad_numbers_are_jumpers no)
		(fp_line
			(start 0.508 -0.9398)
			(end -0.508 -0.9398)
			(stroke
				(width 0.1524)
				(type default)
			)
			(layer "F.SilkS")
		)
		(fp_line
			(start -0.508 -0.9398)
			(end -0.508 0.9398)
			(stroke
				(width 0.1524)
				(type default)
			)
			(layer "F.SilkS")
		)
		(fp_rect
			(start -0.508 0.9398)
			(end 0.508 -0.9398)
			(stroke
				(width 0)
				(type default)
			)
			(fill no)
			(layer "F.CrtYd")
		)
		(fp_rect
			(start -0.508 0.9398)
			(end 0.508 -0.9398)
			(stroke
				(width 0)
				(type default)
			)
			(fill no)
			(layer "F.Fab")
		)
		(pad "1" smd custom
			(at 0 -0.4445 90)
			(size 0.1397 0.1397)
			(layers "F.Cu" "F.Mask" "F.Paste")
			(net "I2C_B_SDA")
			(options
				(clearance outline)
				(anchor circle)
			)
			(primitives
				(gr_poly
					(pts
						(arc
							(start -0.1778 -0.2794)
							(mid -0.249642 -0.249642)
							(end -0.2794 -0.1778)
						)
						(arc
							(start -0.2794 0.1778)
							(mid -0.249642 0.249642)
							(end -0.1778 0.2794)
						)
						(arc
							(start 0.1778 0.2794)
							(mid 0.249642 0.249642)
							(end 0.2794 0.1778)
						)
						(arc
							(start 0.2794 -0.1778)
							(mid 0.249642 -0.249642)
							(end 0.1778 -0.2794)
						)
					)
					(width 0)
					(fill yes)
				)
			)
		)
		(pad "2" smd custom
			(at 0 0.4445 90)
			(size 0.1397 0.1397)
			(layers "F.Cu" "F.Mask" "F.Paste")
			(net "TMP2_SDA")
			(options
				(clearance outline)
				(anchor circle)
			)
			(primitives
				(gr_poly
					(pts
						(arc
							(start -0.1778 -0.2794)
							(mid -0.249642 -0.249642)
							(end -0.2794 -0.1778)
						)
						(arc
							(start -0.2794 0.1778)
							(mid -0.249642 0.249642)
							(end -0.1778 0.2794)
						)
						(arc
							(start 0.1778 0.2794)
							(mid 0.249642 0.249642)
							(end 0.2794 0.1778)
						)
						(arc
							(start 0.2794 -0.1778)
							(mid 0.249642 -0.249642)
							(end 0.1778 -0.2794)
						)
					)
					(width 0)
					(fill yes)
				)
			)
		)
	)
	(footprint ""
		(layer "F.Cu")
		(at 95.504 -219.456 180)
		(property "Reference" "R9096"
			(at 0 0 180)
			(layer "F.SilkS")
			(hide yes)
			(effects
				(font
					(size 1.27 1.27)
				)
			)
		)
		(property "Value" "27R2F-GP"
			(at 0.064008 -3.993896 180)
			(unlocked yes)
			(layer "F.Fab")
			(hide yes)
			(effects
				(font
					(size 1.016 1.016)
					(thickness 0.1524)
				)
			)
		)
		(property "Device Type" "R402H16"
			(at 0.064008 -5.517896 180)
			(unlocked yes)
			(layer "F.Fab")
			(hide yes)
			(effects
				(font
					(size 1.016 1.016)
					(thickness 0.1524)
				)
			)
		)
		(duplicate_pad_numbers_are_jumpers no)
		(fp_line
			(start 0.508 -0.9398)
			(end -0.508 -0.9398)
			(stroke
				(width 0.1524)
				(type default)
			)
			(layer "F.SilkS")
		)
		(fp_line
			(start -0.508 -0.9398)
			(end -0.508 0.9398)
			(stroke
				(width 0.1524)
				(type default)
			)
			(layer "F.SilkS")
		)
		(fp_rect
			(start -0.508 0.9398)
			(end 0.508 -0.9398)
			(stroke
				(width 0)
				(type default)
			)
			(fill no)
			(layer "F.CrtYd")
		)
		(fp_rect
			(start -0.508 0.9398)
			(end 0.508 -0.9398)
			(stroke
				(width 0)
				(type default)
			)
			(fill no)
			(layer "F.Fab")
		)
		(pad "1" smd custom
			(at 0 -0.4445 180)
			(size 0.1397 0.1397)
			(layers "F.Cu" "F.Mask" "F.Paste")
			(net "PE_CLK_100M_DR7_1_R_N")
			(options
				(clearance outline)
				(anchor circle)
			)
			(primitives
				(gr_poly
					(pts
						(arc
							(start -0.1778 -0.2794)
							(mid -0.249642 -0.249642)
							(end -0.2794 -0.1778)
						)
						(arc
							(start -0.2794 0.1778)
							(mid -0.249642 0.249642)
							(end -0.1778 0.2794)
						)
						(arc
							(start 0.1778 0.2794)
							(mid 0.249642 0.249642)
							(end 0.2794 0.1778)
						)
						(arc
							(start 0.2794 -0.1778)
							(mid 0.249642 -0.249642)
							(end 0.1778 -0.2794)
						)
					)
					(width 0)
					(fill yes)
				)
			)
		)
		(pad "2" smd custom
			(at 0 0.4445 180)
			(size 0.1397 0.1397)
			(layers "F.Cu" "F.Mask" "F.Paste")
			(net "PE_CLK100M_DR7_1_N")
			(options
				(clearance outline)
				(anchor circle)
			)
			(primitives
				(gr_poly
					(pts
						(arc
							(start -0.1778 -0.2794)
							(mid -0.249642 -0.249642)
							(end -0.2794 -0.1778)
						)
						(arc
							(start -0.2794 0.1778)
							(mid -0.249642 0.249642)
							(end -0.1778 0.2794)
						)
						(arc
							(start 0.1778 0.2794)
							(mid 0.249642 0.249642)
							(end 0.2794 0.1778)
						)
						(arc
							(start 0.2794 -0.1778)
							(mid 0.249642 -0.249642)
							(end 0.1778 -0.2794)
						)
					)
					(width 0)
					(fill yes)
				)
			)
		)
	)
	(footprint ""
		(layer "F.Cu")
		(at 214.757 -191.897 -90)
		(property "Reference" "U12"
			(at 0 0 270)
			(layer "F.SilkS")
			(hide yes)
			(effects
				(font
					(size 1.27 1.27)
				)
			)
		)
		(property "Value" "P2003EVG-GP"
			(at 0 -11.1252 270)
			(unlocked yes)
			(layer "F.Fab")
			(hide yes)
			(effects
				(font
					(size 1.016 1.016)
					(thickness 0.1524)
				)
			)
		)
		(property "Device Type" "SOIC8H79"
			(at 0 -12.6492 270)
			(unlocked yes)
			(layer "F.Fab")
			(hide yes)
			(effects
				(font
					(size 1.016 1.016)
					(thickness 0.1524)
				)
			)
		)
		(duplicate_pad_numbers_are_jumpers no)
		(fp_line
			(start -2.6162 3.429)
			(end -2.6162 1.4732)
			(stroke
				(width 0.4064)
				(type default)
			)
			(layer "F.SilkS")
		)
		(fp_line
			(start -2.7432 1.4224)
			(end 2.1336 1.4224)
			(stroke
				(width 0.1524)
				(type default)
			)
			(layer "F.SilkS")
		)
		(fp_line
			(start 2.1336 1.4224)
			(end 2.1336 -1.4224)
			(stroke
				(width 0.1524)
				(type default)
			)
			(layer "F.SilkS")
		)
		(fp_line
			(start -2.2352 0)
			(end -2.7432 0.508)
			(stroke
				(width 0.1524)
				(type default)
			)
			(layer "F.SilkS")
		)
		(fp_line
			(start -2.7432 -0.508)
			(end -2.2352 0)
			(stroke
				(width 0.1524)
				(type default)
			)
			(layer "F.SilkS")
		)
		(fp_line
			(start -2.7432 -1.4224)
			(end -2.7432 1.4224)
			(stroke
				(width 0.1524)
				(type default)
			)
			(layer "F.SilkS")
		)
		(fp_line
			(start 2.1336 -1.4224)
			(end -2.7432 -1.4224)
			(stroke
				(width 0.1524)
				(type default)
			)
			(layer "F.SilkS")
		)
		(fp_poly
			(pts
				(xy 2.2098 -1.4224) (xy 2.2098 1.4224) (xy -2.2225 1.4224) (xy -2.2225 -1.4224)
			)
			(stroke
				(width 0)
				(type default)
			)
			(fill yes)
			(layer "F.SilkS")
		)
		(fp_rect
			(start -2.4511 2.9972)
			(end 2.4511 -2.9972)
			(stroke
				(width 0)
				(type default)
			)
			(fill no)
			(layer "F.CrtYd")
		)
		(fp_poly
			(pts
				(xy -2.8194 3.6322) (xy -2.8194 -3.6322) (xy 2.8194 -3.6322) (xy 2.8194 -2.2987) (xy 2.4511 -2.2987)
				(xy 2.4511 -2.9972) (xy -2.4511 -2.9972) (xy -2.4511 2.9972) (xy 2.4511 2.9972) (xy 2.4511 -2.286)
				(xy 2.8194 -2.286) (xy 2.8194 3.6322)
			)
			(stroke
				(width 0)
				(type default)
			)
			(fill no)
			(layer "F.CrtYd")
		)
		(fp_rect
			(start -2.8194 3.6322)
			(end 2.8194 -3.6322)
			(stroke
				(width 0)
				(type default)
			)
			(fill no)
			(layer "F.Fab")
		)
		(pad "1" smd rect
			(at -1.905 2.54 270)
			(size 0.635 1.651)
			(layers "F.Cu" "F.Mask" "F.Paste")
			(net "P12V")
		)
		(pad "2" smd rect
			(at -0.635 2.54 270)
			(size 0.635 1.651)
			(layers "F.Cu" "F.Mask" "F.Paste")
			(net "P12V")
		)
		(pad "3" smd rect
			(at 0.635 2.54 270)
			(size 0.635 1.651)
			(layers "F.Cu" "F.Mask" "F.Paste")
			(net "P12V")
		)
		(pad "4" smd rect
			(at 1.905 2.54 270)
			(size 0.635 1.651)
			(layers "F.Cu" "F.Mask" "F.Paste")
			(net "SW_SSD3_N")
		)
		(pad "5" smd rect
			(at 1.905 -2.54 270)
			(size 0.635 1.651)
			(layers "F.Cu" "F.Mask" "F.Paste")
			(net "P12V_SSD3")
		)
		(pad "6" smd rect
			(at 0.635 -2.54 270)
			(size 0.635 1.651)
			(layers "F.Cu" "F.Mask" "F.Paste")
			(net "P12V_SSD3")
		)
		(pad "7" smd rect
			(at -0.635 -2.54 270)
			(size 0.635 1.651)
			(layers "F.Cu" "F.Mask" "F.Paste")
			(net "P12V_SSD3")
		)
		(pad "8" smd rect
			(at -1.905 -2.54 270)
			(size 0.635 1.651)
			(layers "F.Cu" "F.Mask" "F.Paste")
			(net "P12V_SSD3")
		)
	)
	(footprint ""
		(layer "F.Cu")
		(at 92.837 -14.732 90)
		(property "Reference" "R387"
			(at 0 0 90)
			(layer "F.SilkS")
			(hide yes)
			(effects
				(font
					(size 1.27 1.27)
				)
			)
		)
		(property "Value" "10KR2F-2-GP"
			(at 0.064008 -3.993896 90)
			(unlocked yes)
			(layer "F.Fab")
			(hide yes)
			(effects
				(font
					(size 1.016 1.016)
					(thickness 0.1524)
				)
			)
		)
		(property "Device Type" "R402H16"
			(at 0.064008 -5.517896 90)
			(unlocked yes)
			(layer "F.Fab")
			(hide yes)
			(effects
				(font
					(size 1.016 1.016)
					(thickness 0.1524)
				)
			)
		)
		(duplicate_pad_numbers_are_jumpers no)
		(fp_line
			(start 0.508 -0.9398)
			(end -0.508 -0.9398)
			(stroke
				(width 0.1524)
				(type default)
			)
			(layer "F.SilkS")
		)
		(fp_line
			(start -0.508 -0.9398)
			(end -0.508 0.9398)
			(stroke
				(width 0.1524)
				(type default)
			)
			(layer "F.SilkS")
		)
		(fp_rect
			(start -0.508 0.9398)
			(end 0.508 -0.9398)
			(stroke
				(width 0)
				(type default)
			)
			(fill no)
			(layer "F.CrtYd")
		)
		(fp_rect
			(start -0.508 0.9398)
			(end 0.508 -0.9398)
			(stroke
				(width 0)
				(type default)
			)
			(fill no)
			(layer "F.Fab")
		)
		(pad "1" smd custom
			(at 0 -0.4445 90)
			(size 0.1397 0.1397)
			(layers "F.Cu" "F.Mask" "F.Paste")
			(net "P12V")
			(options
				(clearance outline)
				(anchor circle)
			)
			(primitives
				(gr_poly
					(pts
						(arc
							(start -0.1778 -0.2794)
							(mid -0.249642 -0.249642)
							(end -0.2794 -0.1778)
						)
						(arc
							(start -0.2794 0.1778)
							(mid -0.249642 0.249642)
							(end -0.1778 0.2794)
						)
						(arc
							(start 0.1778 0.2794)
							(mid 0.249642 0.249642)
							(end 0.2794 0.1778)
						)
						(arc
							(start 0.2794 -0.1778)
							(mid 0.249642 -0.249642)
							(end 0.1778 -0.2794)
						)
					)
					(width 0)
					(fill yes)
				)
			)
		)
		(pad "2" smd custom
			(at 0 0.4445 90)
			(size 0.1397 0.1397)
			(layers "F.Cu" "F.Mask" "F.Paste")
			(net "P12V_SENSE")
			(options
				(clearance outline)
				(anchor circle)
			)
			(primitives
				(gr_poly
					(pts
						(arc
							(start -0.1778 -0.2794)
							(mid -0.249642 -0.249642)
							(end -0.2794 -0.1778)
						)
						(arc
							(start -0.2794 0.1778)
							(mid -0.249642 0.249642)
							(end -0.1778 0.2794)
						)
						(arc
							(start 0.1778 0.2794)
							(mid 0.249642 0.249642)
							(end 0.2794 0.1778)
						)
						(arc
							(start 0.2794 -0.1778)
							(mid 0.249642 -0.249642)
							(end 0.1778 -0.2794)
						)
					)
					(width 0)
					(fill yes)
				)
			)
		)
	)
	(footprint ""
		(layer "F.Cu")
		(at 78.5622 -102.1842)
		(property "Reference" "R9973"
			(at 0 0 0)
			(layer "F.SilkS")
			(hide yes)
			(effects
				(font
					(size 1.27 1.27)
				)
			)
		)
		(property "Value" "470R2F-GP"
			(at 0.064008 -3.993896 0)
			(unlocked yes)
			(layer "F.Fab")
			(hide yes)
			(effects
				(font
					(size 1.016 1.016)
					(thickness 0.1524)
				)
			)
		)
		(property "Device Type" "R402H16"
			(at 0.064008 -5.517896 0)
			(unlocked yes)
			(layer "F.Fab")
			(hide yes)
			(effects
				(font
					(size 1.016 1.016)
					(thickness 0.1524)
				)
			)
		)
		(duplicate_pad_numbers_are_jumpers no)
		(fp_line
			(start -0.508 -0.9398)
			(end -0.508 0.9398)
			(stroke
				(width 0.1524)
				(type default)
			)
			(layer "F.SilkS")
		)
		(fp_line
			(start 0.508 -0.9398)
			(end -0.508 -0.9398)
			(stroke
				(width 0.1524)
				(type default)
			)
			(layer "F.SilkS")
		)
		(fp_rect
			(start -0.508 0.9398)
			(end 0.508 -0.9398)
			(stroke
				(width 0)
				(type default)
			)
			(fill no)
			(layer "F.CrtYd")
		)
		(fp_rect
			(start -0.508 0.9398)
			(end 0.508 -0.9398)
			(stroke
				(width 0)
				(type default)
			)
			(fill no)
			(layer "F.Fab")
		)
		(pad "1" smd custom
			(at 0 -0.4445)
			(size 0.1397 0.1397)
			(layers "F.Cu" "F.Mask" "F.Paste")
			(net "VDD_DIFF_4")
			(options
				(clearance outline)
				(anchor circle)
			)
			(primitives
				(gr_poly
					(pts
						(arc
							(start -0.1778 -0.2794)
							(mid -0.249642 -0.249642)
							(end -0.2794 -0.1778)
						)
						(arc
							(start -0.2794 0.1778)
							(mid -0.249642 0.249642)
							(end -0.1778 0.2794)
						)
						(arc
							(start 0.1778 0.2794)
							(mid 0.249642 0.249642)
							(end 0.2794 0.1778)
						)
						(arc
							(start 0.2794 -0.1778)
							(mid 0.249642 -0.249642)
							(end 0.1778 -0.2794)
						)
					)
					(width 0)
					(fill yes)
				)
			)
		)
		(pad "2" smd custom
			(at 0 0.4445)
			(size 0.1397 0.1397)
			(layers "F.Cu" "F.Mask" "F.Paste")
			(net "PE_100M_CLK1_P")
			(options
				(clearance outline)
				(anchor circle)
			)
			(primitives
				(gr_poly
					(pts
						(arc
							(start -0.1778 -0.2794)
							(mid -0.249642 -0.249642)
							(end -0.2794 -0.1778)
						)
						(arc
							(start -0.2794 0.1778)
							(mid -0.249642 0.249642)
							(end -0.1778 0.2794)
						)
						(arc
							(start 0.1778 0.2794)
							(mid 0.249642 0.249642)
							(end 0.2794 0.1778)
						)
						(arc
							(start 0.2794 -0.1778)
							(mid 0.249642 -0.249642)
							(end 0.1778 -0.2794)
						)
					)
					(width 0)
					(fill yes)
				)
			)
		)
	)
	(footprint ""
		(layer "F.Cu")
		(at 97.155 -318.643)
		(property "Reference" "R9601"
			(at 0 0 0)
			(layer "F.SilkS")
			(hide yes)
			(effects
				(font
					(size 1.27 1.27)
				)
			)
		)
		(property "Value" "10R2F-L-GP"
			(at 0.064008 -3.993896 0)
			(unlocked yes)
			(layer "F.Fab")
			(hide yes)
			(effects
				(font
					(size 1.016 1.016)
					(thickness 0.1524)
				)
			)
		)
		(property "Device Type" "R402H14"
			(at 0.064008 -5.517896 0)
			(unlocked yes)
			(layer "F.Fab")
			(hide yes)
			(effects
				(font
					(size 1.016 1.016)
					(thickness 0.1524)
				)
			)
		)
		(duplicate_pad_numbers_are_jumpers no)
		(fp_line
			(start -0.508 -0.9398)
			(end -0.508 0.9398)
			(stroke
				(width 0.1524)
				(type default)
			)
			(layer "F.SilkS")
		)
		(fp_line
			(start 0.508 -0.9398)
			(end -0.508 -0.9398)
			(stroke
				(width 0.1524)
				(type default)
			)
			(layer "F.SilkS")
		)
		(fp_rect
			(start -0.508 0.9398)
			(end 0.508 -0.9398)
			(stroke
				(width 0)
				(type default)
			)
			(fill no)
			(layer "F.CrtYd")
		)
		(fp_rect
			(start -0.508 0.9398)
			(end 0.508 -0.9398)
			(stroke
				(width 0)
				(type default)
			)
			(fill no)
			(layer "F.Fab")
		)
		(pad "1" smd custom
			(at 0 -0.4445)
			(size 0.1397 0.1397)
			(layers "F.Cu" "F.Mask" "F.Paste")
			(net "SSD6_CLK0_OE_N")
			(options
				(clearance outline)
				(anchor circle)
			)
			(primitives
				(gr_poly
					(pts
						(arc
							(start -0.1778 -0.2794)
							(mid -0.249642 -0.249642)
							(end -0.2794 -0.1778)
						)
						(arc
							(start -0.2794 0.1778)
							(mid -0.249642 0.249642)
							(end -0.1778 0.2794)
						)
						(arc
							(start 0.1778 0.2794)
							(mid 0.249642 0.249642)
							(end 0.2794 0.1778)
						)
						(arc
							(start 0.2794 -0.1778)
							(mid 0.249642 -0.249642)
							(end 0.1778 -0.2794)
						)
					)
					(width 0)
					(fill yes)
				)
			)
		)
		(pad "2" smd custom
			(at 0 0.4445)
			(size 0.1397 0.1397)
			(layers "F.Cu" "F.Mask" "F.Paste")
			(net "SSD6_CLK0_OE_R_N")
			(options
				(clearance outline)
				(anchor circle)
			)
			(primitives
				(gr_poly
					(pts
						(arc
							(start -0.1778 -0.2794)
							(mid -0.249642 -0.249642)
							(end -0.2794 -0.1778)
						)
						(arc
							(start -0.2794 0.1778)
							(mid -0.249642 0.249642)
							(end -0.1778 0.2794)
						)
						(arc
							(start 0.1778 0.2794)
							(mid 0.249642 0.249642)
							(end 0.2794 0.1778)
						)
						(arc
							(start 0.2794 -0.1778)
							(mid 0.249642 -0.249642)
							(end 0.1778 -0.2794)
						)
					)
					(width 0)
					(fill yes)
				)
			)
		)
	)
	(footprint ""
		(layer "F.Cu")
		(at 89.662 -88.138 180)
		(property "Reference" "R9607"
			(at 0 0 180)
			(layer "F.SilkS")
			(hide yes)
			(effects
				(font
					(size 1.27 1.27)
				)
			)
		)
		(property "Value" "10R2F-L-GP"
			(at 0.064008 -3.993896 180)
			(unlocked yes)
			(layer "F.Fab")
			(hide yes)
			(effects
				(font
					(size 1.016 1.016)
					(thickness 0.1524)
				)
			)
		)
		(property "Device Type" "R402H14"
			(at 0.064008 -5.517896 180)
			(unlocked yes)
			(layer "F.Fab")
			(hide yes)
			(effects
				(font
					(size 1.016 1.016)
					(thickness 0.1524)
				)
			)
		)
		(duplicate_pad_numbers_are_jumpers no)
		(fp_line
			(start 0.508 -0.9398)
			(end -0.508 -0.9398)
			(stroke
				(width 0.1524)
				(type default)
			)
			(layer "F.SilkS")
		)
		(fp_line
			(start -0.508 -0.9398)
			(end -0.508 0.9398)
			(stroke
				(width 0.1524)
				(type default)
			)
			(layer "F.SilkS")
		)
		(fp_rect
			(start -0.508 0.9398)
			(end 0.508 -0.9398)
			(stroke
				(width 0)
				(type default)
			)
			(fill no)
			(layer "F.CrtYd")
		)
		(fp_rect
			(start -0.508 0.9398)
			(end 0.508 -0.9398)
			(stroke
				(width 0)
				(type default)
			)
			(fill no)
			(layer "F.Fab")
		)
		(pad "1" smd custom
			(at 0 -0.4445 180)
			(size 0.1397 0.1397)
			(layers "F.Cu" "F.Mask" "F.Paste")
			(net "SSD9_CLK0_OE_N")
			(options
				(clearance outline)
				(anchor circle)
			)
			(primitives
				(gr_poly
					(pts
						(arc
							(start -0.1778 -0.2794)
							(mid -0.249642 -0.249642)
							(end -0.2794 -0.1778)
						)
						(arc
							(start -0.2794 0.1778)
							(mid -0.249642 0.249642)
							(end -0.1778 0.2794)
						)
						(arc
							(start 0.1778 0.2794)
							(mid 0.249642 0.249642)
							(end 0.2794 0.1778)
						)
						(arc
							(start 0.2794 -0.1778)
							(mid 0.249642 -0.249642)
							(end 0.1778 -0.2794)
						)
					)
					(width 0)
					(fill yes)
				)
			)
		)
		(pad "2" smd custom
			(at 0 0.4445 180)
			(size 0.1397 0.1397)
			(layers "F.Cu" "F.Mask" "F.Paste")
			(net "SSD9_CLK0_OE_R_N")
			(options
				(clearance outline)
				(anchor circle)
			)
			(primitives
				(gr_poly
					(pts
						(arc
							(start -0.1778 -0.2794)
							(mid -0.249642 -0.249642)
							(end -0.2794 -0.1778)
						)
						(arc
							(start -0.2794 0.1778)
							(mid -0.249642 0.249642)
							(end -0.1778 0.2794)
						)
						(arc
							(start 0.1778 0.2794)
							(mid 0.249642 0.249642)
							(end 0.2794 0.1778)
						)
						(arc
							(start 0.2794 -0.1778)
							(mid 0.249642 -0.249642)
							(end 0.1778 -0.2794)
						)
					)
					(width 0)
					(fill yes)
				)
			)
		)
	)
	(footprint ""
		(layer "F.Cu")
		(at 226.149916 -479.67011 90)
		(property "Reference" "J100"
			(at 0 0 90)
			(layer "F.SilkS")
			(hide yes)
			(effects
				(font
					(size 1.27 1.27)
				)
			)
		)
		(property "Value" "PCISLT68-14-GP-U1"
			(at -22.225 12.7508 90)
			(unlocked yes)
			(layer "F.Fab")
			(hide yes)
			(effects
				(font
					(size 1.016 1.016)
					(thickness 0.1524)
				)
			)
		)
		(property "Device Type" "SD-78827-0001"
			(at -22.225 11.2268 90)
			(unlocked yes)
			(layer "F.Fab")
			(hide yes)
			(effects
				(font
					(size 1.016 1.016)
					(thickness 0.1524)
				)
			)
		)
		(duplicate_pad_numbers_are_jumpers no)
		(fp_line
			(start 20.4724 -3.4036)
			(end 20.4724 0.0254)
			(stroke
				(width 0.1524)
				(type default)
			)
			(layer "F.SilkS")
		)
		(fp_line
			(start -20.4724 -3.4036)
			(end 20.4724 -3.4036)
			(stroke
				(width 0.1524)
				(type default)
			)
			(layer "F.SilkS")
		)
		(fp_line
			(start 23.749 0.0254)
			(end 23.749 4.6736)
			(stroke
				(width 0.1524)
				(type default)
			)
			(layer "F.SilkS")
		)
		(fp_line
			(start 20.4724 0.0254)
			(end 23.749 0.0254)
			(stroke
				(width 0.1524)
				(type default)
			)
			(layer "F.SilkS")
		)
		(fp_line
			(start -20.4724 0.0254)
			(end -20.4724 -3.4036)
			(stroke
				(width 0.1524)
				(type default)
			)
			(layer "F.SilkS")
		)
		(fp_line
			(start -23.749 0.0254)
			(end -20.4724 0.0254)
			(stroke
				(width 0.1524)
				(type default)
			)
			(layer "F.SilkS")
		)
		(fp_line
			(start 23.117556 1.803908)
			(end 23.117556 2.896108)
			(stroke
				(width 0.3048)
				(type default)
			)
			(layer "F.SilkS")
		)
		(fp_line
			(start -20.882356 1.803908)
			(end -20.882356 2.896108)
			(stroke
				(width 0.3048)
				(type default)
			)
			(layer "F.SilkS")
		)
		(fp_line
			(start 20.882356 2.896108)
			(end 20.882356 1.803908)
			(stroke
				(width 0.3048)
				(type default)
			)
			(layer "F.SilkS")
		)
		(fp_line
			(start -23.117556 2.896108)
			(end -23.117556 1.803908)
			(stroke
				(width 0.3048)
				(type default)
			)
			(layer "F.SilkS")
		)
		(fp_line
			(start 23.749 4.6736)
			(end 20.4724 4.6736)
			(stroke
				(width 0.1524)
				(type default)
			)
			(layer "F.SilkS")
		)
		(fp_line
			(start 20.4724 4.6736)
			(end 20.4724 12.0142)
			(stroke
				(width 0.1524)
				(type default)
			)
			(layer "F.SilkS")
		)
		(fp_line
			(start -20.4724 4.6736)
			(end -23.749 4.6736)
			(stroke
				(width 0.1524)
				(type default)
			)
			(layer "F.SilkS")
		)
		(fp_line
			(start -23.749 4.6736)
			(end -23.749 0.0254)
			(stroke
				(width 0.1524)
				(type default)
			)
			(layer "F.SilkS")
		)
		(fp_line
			(start 17.8435 10.3124)
			(end -17.8435 10.3124)
			(stroke
				(width 0.1524)
				(type default)
			)
			(layer "F.SilkS")
		)
		(fp_line
			(start -17.8435 10.3124)
			(end -17.8435 12.0142)
			(stroke
				(width 0.1524)
				(type default)
			)
			(layer "F.SilkS")
		)
		(fp_line
			(start 20.4724 12.0142)
			(end 17.8435 12.0142)
			(stroke
				(width 0.1524)
				(type default)
			)
			(layer "F.SilkS")
		)
		(fp_line
			(start 17.8435 12.0142)
			(end 17.8435 10.3124)
			(stroke
				(width 0.1524)
				(type default)
			)
			(layer "F.SilkS")
		)
		(fp_line
			(start -17.8435 12.0142)
			(end -20.4724 12.0142)
			(stroke
				(width 0.1524)
				(type default)
			)
			(layer "F.SilkS")
		)
		(fp_line
			(start -20.4724 12.0142)
			(end -20.4724 4.6736)
			(stroke
				(width 0.1524)
				(type default)
			)
			(layer "F.SilkS")
		)
		(fp_arc
			(start 20.882356 1.803908)
			(mid 21.999956 0.686308)
			(end 23.117556 1.803908)
			(stroke
				(width 0.3048)
				(type default)
			)
			(layer "F.SilkS")
		)
		(fp_arc
			(start -23.117556 1.803908)
			(mid -21.999956 0.686308)
			(end -20.882356 1.803908)
			(stroke
				(width 0.3048)
				(type default)
			)
			(layer "F.SilkS")
		)
		(fp_arc
			(start 23.117556 2.896108)
			(mid 21.999956 4.013708)
			(end 20.882356 2.896108)
			(stroke
				(width 0.3048)
				(type default)
			)
			(layer "F.SilkS")
		)
		(fp_arc
			(start -20.882356 2.896108)
			(mid -21.999956 4.013708)
			(end -23.117556 2.896108)
			(stroke
				(width 0.3048)
				(type default)
			)
			(layer "F.SilkS")
		)
		(fp_poly
			(pts
				(xy -20.2184 11.7602) (xy -20.2184 4.4196) (xy -23.495 4.4196) (xy -23.495 0.2794) (xy -20.2184 0.2794)
				(xy -20.2184 -3.1496) (xy 20.2184 -3.1496) (xy 20.2184 0.2794) (xy 23.495 0.2794) (xy 23.495 4.4196)
				(xy 20.2184 4.4196) (xy 20.2184 11.7602) (xy 18.0975 11.7602) (xy 18.0975 10.0584) (xy -18.0975 10.0584)
				(xy -18.0975 11.7602)
			)
			(stroke
				(width 0)
				(type default)
			)
			(fill no)
			(layer "F.CrtYd")
		)
		(fp_poly
			(pts
				(xy -21.2471 16.256) (xy -21.2471 4.9276) (xy -24.003 4.9276) (xy -24.003 -0.2286) (xy -20.7264 -0.2286)
				(xy -20.7264 -3.6576) (xy 20.7264 -3.6576) (xy 20.7264 -0.2286) (xy 24.003 -0.2286) (xy 24.003 -0.00635)
				(xy 20.2184 -0.00635) (xy 20.2184 -3.1496) (xy -20.2184 -3.1496) (xy -20.2184 0.2794) (xy -23.495 0.2794)
				(xy -23.495 4.4196) (xy -20.2184 4.4196) (xy -20.2184 11.7602) (xy -18.0975 11.7602) (xy -18.0975 10.0584)
				(xy 18.0975 10.0584) (xy 18.0975 11.7602) (xy 20.2184 11.7602) (xy 20.2184 4.4196) (xy 23.495 4.4196)
				(xy 23.495 0.2794) (xy 20.2184 0.2794) (xy 20.2184 0.00635) (xy 24.003 0.00635) (xy 24.003 4.9276)
				(xy 21.2471 4.9276) (xy 21.2471 16.256)
			)
			(stroke
				(width 0)
				(type default)
			)
			(fill no)
			(layer "F.CrtYd")
		)
		(fp_poly
			(pts
				(xy -21.2471 16.256) (xy -21.2471 4.9276) (xy -24.003 4.9276) (xy -24.003 -0.2286) (xy -20.7264 -0.2286)
				(xy -20.7264 -3.6576) (xy 20.7264 -3.6576) (xy 20.7264 -0.2286) (xy 24.003 -0.2286) (xy 24.003 4.9276)
				(xy 21.2471 4.9276) (xy 21.2471 16.256)
			)
			(stroke
				(width 0)
				(type default)
			)
			(fill no)
			(layer "F.Fab")
		)
		(pad "" np_thru_hole circle
			(at -18.999962 0 90)
			(size 0.254 0.254)
			(drill 1.8542)
			(layers "*.Cu" "*.Mask")
			(clearance 1.1557)
			(thermal_gap 1.1557)
		)
		(pad "" np_thru_hole circle
			(at 18.999962 0 90)
			(size 0.254 0.254)
			(drill 1.8542)
			(layers "*.Cu" "*.Mask")
			(clearance 1.1557)
			(thermal_gap 1.1557)
		)
		(pad "E1" smd rect
			(at -7.079996 1.240028 90)
			(size 0.508 2.0066)
			(layers "F.Cu" "F.Mask" "F.Paste")
			(net "PE_CLK100M_DR0_2_P")
		)
		(pad "E2" smd rect
			(at -6.279896 1.240028 90)
			(size 0.508 2.0066)
			(layers "F.Cu" "F.Mask" "F.Paste")
			(net "PE_CLK100M_DR0_2_N")
		)
		(pad "E3" smd rect
			(at -5.48005 1.240028 90)
			(size 0.508 2.0066)
			(layers "F.Cu" "F.Mask" "F.Paste")
			(net "P3V3")
		)
		(pad "E4" smd rect
			(at -4.67995 1.240028 90)
			(size 0.508 2.0066)
			(layers "F.Cu" "F.Mask" "F.Paste")
			(net "SSD0_PERST_N")
		)
		(pad "E5" smd rect
			(at -3.880104 1.240028 90)
			(size 0.508 2.0066)
			(layers "F.Cu" "F.Mask" "F.Paste")
			(net "SSD0_PERST_N")
		)
		(pad "E6" smd rect
			(at -3.080004 1.240028 90)
			(size 0.508 2.0066)
			(layers "F.Cu" "F.Mask" "F.Paste")
			(net "Net_17")
		)
		(pad "E7" smd rect
			(at -15.48003 -1.949958 90)
			(size 0.508 2.0066)
			(layers "F.Cu" "F.Mask" "F.Paste")
			(net "PE_CLK100M_DR0_1_P")
		)
		(pad "E8" smd rect
			(at -14.67993 -1.949958 90)
			(size 0.508 2.0066)
			(layers "F.Cu" "F.Mask" "F.Paste")
			(net "PE_CLK100M_DR0_1_N")
		)
		(pad "E9" smd rect
			(at -13.880084 -1.949958 90)
			(size 0.508 2.0066)
			(layers "F.Cu" "F.Mask" "F.Paste")
			(net "GND")
		)
		(pad "E10" smd rect
			(at -13.079984 -1.949958 90)
			(size 0.508 2.0066)
			(layers "F.Cu" "F.Mask" "F.Paste")
			(net "PE_TX1_DR0_N")
		)
		(pad "E11" smd rect
			(at -12.279884 -1.949958 90)
			(size 0.508 2.0066)
			(layers "F.Cu" "F.Mask" "F.Paste")
			(net "PE_TX1_DR0_P")
		)
		(pad "E12" smd rect
			(at -11.480038 -1.949958 90)
			(size 0.508 2.0066)
			(layers "F.Cu" "F.Mask" "F.Paste")
			(net "GND")
		)
		(pad "E13" smd rect
			(at -10.679938 -1.949958 90)
			(size 0.508 2.0066)
			(layers "F.Cu" "F.Mask" "F.Paste")
			(net "PE_RX1_DR0_N")
		)
		(pad "E14" smd rect
			(at -9.880092 -1.949958 90)
			(size 0.508 2.0066)
			(layers "F.Cu" "F.Mask" "F.Paste")
			(net "PE_RX1_DR0_P")
		)
		(pad "E15" smd rect
			(at -9.079992 -1.949958 90)
			(size 0.508 2.0066)
			(layers "F.Cu" "F.Mask" "F.Paste")
			(net "GND")
		)
		(pad "E16" smd rect
			(at -8.279892 -1.949958 90)
			(size 0.508 2.0066)
			(layers "F.Cu" "F.Mask" "F.Paste")
			(net "Net_24")
		)
		(pad "E17" smd rect
			(at 9.320022 -1.949958 90)
			(size 0.508 2.0066)
			(layers "F.Cu" "F.Mask" "F.Paste")
			(net "PE_TX4_DR0_N")
		)
		(pad "E18" smd rect
			(at 10.120122 -1.949958 90)
			(size 0.508 2.0066)
			(layers "F.Cu" "F.Mask" "F.Paste")
			(net "PE_TX4_DR0_P")
		)
		(pad "E19" smd rect
			(at 10.919968 -1.949958 90)
			(size 0.508 2.0066)
			(layers "F.Cu" "F.Mask" "F.Paste")
			(net "GND")
		)
		(pad "E20" smd rect
			(at 11.720068 -1.949958 90)
			(size 0.508 2.0066)
			(layers "F.Cu" "F.Mask" "F.Paste")
			(net "PE_RX4_DR0_N")
		)
		(pad "E21" smd rect
			(at 12.519914 -1.949958 90)
			(size 0.508 2.0066)
			(layers "F.Cu" "F.Mask" "F.Paste")
			(net "PE_RX4_DR0_P")
		)
		(pad "E22" smd rect
			(at 13.320014 -1.949958 90)
			(size 0.508 2.0066)
			(layers "F.Cu" "F.Mask" "F.Paste")
			(net "GND")
		)
		(pad "E23" smd rect
			(at 14.120114 -1.949958 90)
			(size 0.508 2.0066)
			(layers "F.Cu" "F.Mask" "F.Paste")
			(net "SCL_DR0_R")
		)
		(pad "E24" smd rect
			(at 14.91996 -1.949958 90)
			(size 0.508 2.0066)
			(layers "F.Cu" "F.Mask" "F.Paste")
			(net "SDA_DR0_R")
		)
		(pad "E25" smd rect
			(at 15.72006 -1.949958 90)
			(size 0.508 2.0066)
			(layers "F.Cu" "F.Mask" "F.Paste")
			(net "DUALPORTEN#0")
		)
		(pad "P1" smd rect
			(at -1.905 0.824992 90)
			(size 0.6604 2.0574)
			(layers "F.Cu" "F.Mask" "F.Paste")
			(net "Net_20")
		)
		(pad "P2" smd rect
			(at -0.635 0.824992 90)
			(size 0.6604 2.0574)
			(layers "F.Cu" "F.Mask" "F.Paste")
			(net "Net_19")
		)
		(pad "P3" smd rect
			(at 0.635 0.824992 90)
			(size 0.6604 2.0574)
			(layers "F.Cu" "F.Mask" "F.Paste")
			(net "Net_18")
		)
		(pad "P4" smd rect
			(at 1.905 0.824992 90)
			(size 0.6604 2.0574)
			(layers "F.Cu" "F.Mask" "F.Paste")
			(net "SSD0_CLK0_OE_N")
		)
		(pad "P5" smd rect
			(at 3.175 0.824992 90)
			(size 0.6604 2.0574)
			(layers "F.Cu" "F.Mask" "F.Paste")
			(net "GND")
		)
		(pad "P6" smd rect
			(at 4.445 0.824992 90)
			(size 0.6604 2.0574)
			(layers "F.Cu" "F.Mask" "F.Paste")
			(net "GND")
		)
		(pad "P7" smd rect
			(at 5.715 0.824992 90)
			(size 0.6604 2.0574)
			(layers "F.Cu" "F.Mask" "F.Paste")
			(net "Net_14")
		)
		(pad "P8" smd rect
			(at 6.985 0.824992 90)
			(size 0.6604 2.0574)
			(layers "F.Cu" "F.Mask" "F.Paste")
			(net "Net_13")
		)
		(pad "P9" smd rect
			(at 8.255 0.824992 90)
			(size 0.6604 2.0574)
			(layers "F.Cu" "F.Mask" "F.Paste")
			(net "Net_12")
		)
		(pad "P10" smd rect
			(at 9.525 0.824992 90)
			(size 0.6604 2.0574)
			(layers "F.Cu" "F.Mask" "F.Paste")
			(net "SSD_PRSNT_NET0")
		)
		(pad "P11" smd rect
			(at 10.795 0.824992 90)
			(size 0.6604 2.0574)
			(layers "F.Cu" "F.Mask" "F.Paste")
			(net "SSD_ACT_DR0")
		)
		(pad "P12" smd rect
			(at 12.065 0.824992 90)
			(size 0.6604 2.0574)
			(layers "F.Cu" "F.Mask" "F.Paste")
			(net "GND")
		)
		(pad "P13" smd rect
			(at 13.335 0.824992 90)
			(size 0.6604 2.0574)
			(layers "F.Cu" "F.Mask" "F.Paste")
			(net "12V_PRECH_SSD0")
		)
		(pad "P14" smd rect
			(at 14.605 0.824992 90)
			(size 0.6604 2.0574)
			(layers "F.Cu" "F.Mask" "F.Paste")
			(net "P12V_SSD0")
		)
		(pad "P15" smd rect
			(at 15.875 0.824992 90)
			(size 0.6604 2.0574)
			(layers "F.Cu" "F.Mask" "F.Paste")
			(net "P12V_SSD0")
		)
		(pad "PTH1" thru_hole oval
			(at -21.999956 2.350008 90)
			(size 1.524 2.6162)
			(drill oval 0.8128 1.905)
			(layers "*.Cu" "*.Mask")
			(remove_unused_layers no)
			(net "Net_29")
			(clearance 0.1524)
			(thermal_gap 0.1524)
		)
		(pad "PTH2" thru_hole oval
			(at 21.999956 2.350008 90)
			(size 1.524 2.6162)
			(drill oval 0.8128 1.905)
			(layers "*.Cu" "*.Mask")
			(remove_unused_layers no)
			(net "Net_10")
			(clearance 0.1524)
			(thermal_gap 0.1524)
		)
		(pad "S1" smd rect
			(at -15.875 0.824992 90)
			(size 0.6604 2.0574)
			(layers "F.Cu" "F.Mask" "F.Paste")
			(net "GND")
		)
		(pad "S2" smd rect
			(at -14.605 0.824992 90)
			(size 0.6604 2.0574)
			(layers "F.Cu" "F.Mask" "F.Paste")
			(net "Net_28")
		)
		(pad "S3" smd rect
			(at -13.335 0.824992 90)
			(size 0.6604 2.0574)
			(layers "F.Cu" "F.Mask" "F.Paste")
			(net "Net_27")
		)
		(pad "S4" smd rect
			(at -12.065 0.824992 90)
			(size 0.6604 2.0574)
			(layers "F.Cu" "F.Mask" "F.Paste")
			(net "GND")
		)
		(pad "S5" smd rect
			(at -10.795 0.824992 90)
			(size 0.6604 2.0574)
			(layers "F.Cu" "F.Mask" "F.Paste")
			(net "Net_26")
		)
		(pad "S6" smd rect
			(at -9.525 0.824992 90)
			(size 0.6604 2.0574)
			(layers "F.Cu" "F.Mask" "F.Paste")
			(net "Net_25")
		)
		(pad "S7" smd rect
			(at -8.255 0.824992 90)
			(size 0.6604 2.0574)
			(layers "F.Cu" "F.Mask" "F.Paste")
			(net "GND")
		)
		(pad "S8" smd rect
			(at -7.480046 -1.949958 90)
			(size 0.508 2.0066)
			(layers "F.Cu" "F.Mask" "F.Paste")
			(net "GND")
		)
		(pad "S9" smd rect
			(at -6.679946 -1.949958 90)
			(size 0.508 2.0066)
			(layers "F.Cu" "F.Mask" "F.Paste")
			(net "Net_23")
		)
		(pad "S10" smd rect
			(at -5.8801 -1.949958 90)
			(size 0.508 2.0066)
			(layers "F.Cu" "F.Mask" "F.Paste")
			(net "Net_22")
		)
		(pad "S11" smd rect
			(at -5.08 -1.949958 90)
			(size 0.508 2.0066)
			(layers "F.Cu" "F.Mask" "F.Paste")
			(net "GND")
		)
		(pad "S12" smd rect
			(at -4.2799 -1.949958 90)
			(size 0.508 2.0066)
			(layers "F.Cu" "F.Mask" "F.Paste")
			(net "Net_21")
		)
		(pad "S13" smd rect
			(at -3.480054 -1.949958 90)
			(size 0.508 2.0066)
			(layers "F.Cu" "F.Mask" "F.Paste")
			(net "Net_16")
		)
		(pad "S14" smd rect
			(at -2.679954 -1.949958 90)
			(size 0.508 2.0066)
			(layers "F.Cu" "F.Mask" "F.Paste")
			(net "GND")
		)
		(pad "S15" smd rect
			(at -1.880108 -1.949958 90)
			(size 0.508 2.0066)
			(layers "F.Cu" "F.Mask" "F.Paste")
			(net "Net_15")
		)
		(pad "S16" smd rect
			(at -1.080008 -1.949958 90)
			(size 0.508 2.0066)
			(layers "F.Cu" "F.Mask" "F.Paste")
			(net "GND")
		)
		(pad "S17" smd rect
			(at -0.279908 -1.949958 90)
			(size 0.508 2.0066)
			(layers "F.Cu" "F.Mask" "F.Paste")
			(net "PE_TX2_DR0_N")
		)
		(pad "S18" smd rect
			(at 0.519938 -1.949958 90)
			(size 0.508 2.0066)
			(layers "F.Cu" "F.Mask" "F.Paste")
			(net "PE_TX2_DR0_P")
		)
		(pad "S19" smd rect
			(at 1.320038 -1.949958 90)
			(size 0.508 2.0066)
			(layers "F.Cu" "F.Mask" "F.Paste")
			(net "GND")
		)
		(pad "S20" smd rect
			(at 2.119884 -1.949958 90)
			(size 0.508 2.0066)
			(layers "F.Cu" "F.Mask" "F.Paste")
			(net "PE_RX2_DR0_N")
		)
		(pad "S21" smd rect
			(at 2.919984 -1.949958 90)
			(size 0.508 2.0066)
			(layers "F.Cu" "F.Mask" "F.Paste")
			(net "PE_RX2_DR0_P")
		)
		(pad "S22" smd rect
			(at 3.720084 -1.949958 90)
			(size 0.508 2.0066)
			(layers "F.Cu" "F.Mask" "F.Paste")
			(net "GND")
		)
		(pad "S23" smd rect
			(at 4.51993 -1.949958 90)
			(size 0.508 2.0066)
			(layers "F.Cu" "F.Mask" "F.Paste")
			(net "PE_TX3_DR0_N")
		)
		(pad "S24" smd rect
			(at 5.32003 -1.949958 90)
			(size 0.508 2.0066)
			(layers "F.Cu" "F.Mask" "F.Paste")
			(net "PE_TX3_DR0_P")
		)
		(pad "S25" smd rect
			(at 6.119876 -1.949958 90)
			(size 0.508 2.0066)
			(layers "F.Cu" "F.Mask" "F.Paste")
			(net "GND")
		)
		(pad "S26" smd rect
			(at 6.919976 -1.949958 90)
			(size 0.508 2.0066)
			(layers "F.Cu" "F.Mask" "F.Paste")
			(net "PE_RX3_DR0_N")
		)
		(pad "S27" smd rect
			(at 7.720076 -1.949958 90)
			(size 0.508 2.0066)
			(layers "F.Cu" "F.Mask" "F.Paste")
			(net "PE_RX3_DR0_P")
		)
		(pad "S28" smd rect
			(at 8.519922 -1.949958 90)
			(size 0.508 2.0066)
			(layers "F.Cu" "F.Mask" "F.Paste")
			(net "GND")
		)
		(zone
			(layers "F.Cu" "B.Cu" "In1.Cu" "In2.Cu" "In3.Cu" "In4.Cu" "In5.Cu" "In6.Cu")
			(hatch none 0.5)
			(connect_pads
				(clearance 0)
			)
			(min_thickness 0.25)
			(keepout
				(tracks not_allowed)
				(vias allowed)
				(pads allowed)
				(copperpour not_allowed)
				(footprints allowed)
			)
			(placement
				(enabled no)
				(sheetname "")
			)
			(fill
				(thermal_gap 0.5)
				(thermal_bridge_width 0.5)
				(island_removal_mode 0)
			)
			(polygon
				(pts
					(arc
						(start 227.381816 -498.670072)
						(mid 224.918016 -498.670072)
						(end 227.381816 -498.670072)
					)
				)
			)
		)
		(zone
			(layers "F.Cu" "B.Cu" "In1.Cu" "In2.Cu" "In3.Cu" "In4.Cu" "In5.Cu" "In6.Cu")
			(hatch none 0.5)
			(connect_pads
				(clearance 0)
			)
			(min_thickness 0.25)
			(keepout
				(tracks not_allowed)
				(vias allowed)
				(pads allowed)
				(copperpour not_allowed)
				(footprints allowed)
			)
			(placement
				(enabled no)
				(sheetname "")
			)
			(fill
				(thermal_gap 0.5)
				(thermal_bridge_width 0.5)
				(island_removal_mode 0)
			)
			(polygon
				(pts
					(arc
						(start 227.381816 -460.670148)
						(mid 224.918016 -460.670148)
						(end 227.381816 -460.670148)
					)
				)
			)
		)
	)
	(footprint ""
		(layer "F.Cu")
		(at 203.454 -50.292 90)
		(property "Reference" "R326"
			(at 0 0 90)
			(layer "F.SilkS")
			(hide yes)
			(effects
				(font
					(size 1.27 1.27)
				)
			)
		)
		(property "Value" "0R2J-2-GP"
			(at 0.064008 -3.993896 90)
			(unlocked yes)
			(layer "F.Fab")
			(hide yes)
			(effects
				(font
					(size 1.016 1.016)
					(thickness 0.1524)
				)
			)
		)
		(property "Device Type" "R402H16"
			(at 0.064008 -5.517896 90)
			(unlocked yes)
			(layer "F.Fab")
			(hide yes)
			(effects
				(font
					(size 1.016 1.016)
					(thickness 0.1524)
				)
			)
		)
		(duplicate_pad_numbers_are_jumpers no)
		(fp_line
			(start 0.508 -0.9398)
			(end -0.508 -0.9398)
			(stroke
				(width 0.1524)
				(type default)
			)
			(layer "F.SilkS")
		)
		(fp_line
			(start -0.508 -0.9398)
			(end -0.508 0.9398)
			(stroke
				(width 0.1524)
				(type default)
			)
			(layer "F.SilkS")
		)
		(fp_rect
			(start -0.508 0.9398)
			(end 0.508 -0.9398)
			(stroke
				(width 0)
				(type default)
			)
			(fill no)
			(layer "F.CrtYd")
		)
		(fp_rect
			(start -0.508 0.9398)
			(end 0.508 -0.9398)
			(stroke
				(width 0)
				(type default)
			)
			(fill no)
			(layer "F.Fab")
		)
		(pad "1" smd custom
			(at 0 -0.4445 90)
			(size 0.1397 0.1397)
			(layers "F.Cu" "F.Mask" "F.Paste")
			(net "I2C_B_SDA")
			(options
				(clearance outline)
				(anchor circle)
			)
			(primitives
				(gr_poly
					(pts
						(arc
							(start -0.1778 -0.2794)
							(mid -0.249642 -0.249642)
							(end -0.2794 -0.1778)
						)
						(arc
							(start -0.2794 0.1778)
							(mid -0.249642 0.249642)
							(end -0.1778 0.2794)
						)
						(arc
							(start 0.1778 0.2794)
							(mid 0.249642 0.249642)
							(end 0.2794 0.1778)
						)
						(arc
							(start 0.2794 -0.1778)
							(mid 0.249642 -0.249642)
							(end 0.1778 -0.2794)
						)
					)
					(width 0)
					(fill yes)
				)
			)
		)
		(pad "2" smd custom
			(at 0 0.4445 90)
			(size 0.1397 0.1397)
			(layers "F.Cu" "F.Mask" "F.Paste")
			(net "TMP3_SDA")
			(options
				(clearance outline)
				(anchor circle)
			)
			(primitives
				(gr_poly
					(pts
						(arc
							(start -0.1778 -0.2794)
							(mid -0.249642 -0.249642)
							(end -0.2794 -0.1778)
						)
						(arc
							(start -0.2794 0.1778)
							(mid -0.249642 0.249642)
							(end -0.1778 0.2794)
						)
						(arc
							(start 0.1778 0.2794)
							(mid 0.249642 0.249642)
							(end 0.2794 0.1778)
						)
						(arc
							(start 0.2794 -0.1778)
							(mid 0.249642 -0.249642)
							(end 0.1778 -0.2794)
						)
					)
					(width 0)
					(fill yes)
				)
			)
		)
	)
	(footprint ""
		(layer "F.Cu")
		(at 24.003 -157.474158 -90)
		(property "Reference" "SR1147"
			(at 0 0 270)
			(layer "F.SilkS")
			(hide yes)
			(effects
				(font
					(size 1.27 1.27)
				)
			)
		)
		(property "Value" "4K7R2F-GP"
			(at 0.064008 -3.993896 270)
			(unlocked yes)
			(layer "F.Fab")
			(hide yes)
			(effects
				(font
					(size 1.016 1.016)
					(thickness 0.1524)
				)
			)
		)
		(property "Device Type" "R402H16"
			(at 0.064008 -5.517896 270)
			(unlocked yes)
			(layer "F.Fab")
			(hide yes)
			(effects
				(font
					(size 1.016 1.016)
					(thickness 0.1524)
				)
			)
		)
		(duplicate_pad_numbers_are_jumpers no)
		(fp_line
			(start -0.508 -0.9398)
			(end -0.508 0.9398)
			(stroke
				(width 0.1524)
				(type default)
			)
			(layer "F.SilkS")
		)
		(fp_line
			(start 0.508 -0.9398)
			(end -0.508 -0.9398)
			(stroke
				(width 0.1524)
				(type default)
			)
			(layer "F.SilkS")
		)
		(fp_rect
			(start -0.508 0.9398)
			(end 0.508 -0.9398)
			(stroke
				(width 0)
				(type default)
			)
			(fill no)
			(layer "F.CrtYd")
		)
		(fp_rect
			(start -0.508 0.9398)
			(end 0.508 -0.9398)
			(stroke
				(width 0)
				(type default)
			)
			(fill no)
			(layer "F.Fab")
		)
		(pad "1" smd custom
			(at 0 -0.4445 270)
			(size 0.1397 0.1397)
			(layers "F.Cu" "F.Mask" "F.Paste")
			(net "P3V3")
			(options
				(clearance outline)
				(anchor circle)
			)
			(primitives
				(gr_poly
					(pts
						(arc
							(start -0.1778 -0.2794)
							(mid -0.249642 -0.249642)
							(end -0.2794 -0.1778)
						)
						(arc
							(start -0.2794 0.1778)
							(mid -0.249642 0.249642)
							(end -0.1778 0.2794)
						)
						(arc
							(start 0.1778 0.2794)
							(mid 0.249642 0.249642)
							(end 0.2794 0.1778)
						)
						(arc
							(start 0.2794 -0.1778)
							(mid 0.249642 -0.249642)
							(end 0.1778 -0.2794)
						)
					)
					(width 0)
					(fill yes)
				)
			)
		)
		(pad "2" smd custom
			(at 0 0.4445 270)
			(size 0.1397 0.1397)
			(layers "F.Cu" "F.Mask" "F.Paste")
			(net "SSD13_CLK0_OE_MOS_N")
			(options
				(clearance outline)
				(anchor circle)
			)
			(primitives
				(gr_poly
					(pts
						(arc
							(start -0.1778 -0.2794)
							(mid -0.249642 -0.249642)
							(end -0.2794 -0.1778)
						)
						(arc
							(start -0.2794 0.1778)
							(mid -0.249642 0.249642)
							(end -0.1778 0.2794)
						)
						(arc
							(start 0.1778 0.2794)
							(mid 0.249642 0.249642)
							(end 0.2794 0.1778)
						)
						(arc
							(start 0.2794 -0.1778)
							(mid 0.249642 -0.249642)
							(end 0.1778 -0.2794)
						)
					)
					(width 0)
					(fill yes)
				)
			)
		)
	)
	(footprint ""
		(layer "F.Cu")
		(at 94.615 -439.293 180)
		(property "Reference" "C8839"
			(at 0 0 180)
			(layer "F.SilkS")
			(hide yes)
			(effects
				(font
					(size 1.27 1.27)
				)
			)
		)
		(property "Value" "SCD1U16V2KX-3GP"
			(at 1.1811 -2.7051 180)
			(unlocked yes)
			(layer "F.Fab")
			(hide yes)
			(effects
				(font
					(size 1.016 1.016)
					(thickness 0.1524)
				)
			)
		)
		(property "Device Type" "C402H22"
			(at 1.1811 -4.2291 180)
			(unlocked yes)
			(layer "F.Fab")
			(hide yes)
			(effects
				(font
					(size 1.016 1.016)
					(thickness 0.1524)
				)
			)
		)
		(duplicate_pad_numbers_are_jumpers no)
		(fp_rect
			(start -0.4318 0.9525)
			(end 0.4318 -0.9525)
			(stroke
				(width 0)
				(type default)
			)
			(fill no)
			(layer "F.CrtYd")
		)
		(fp_rect
			(start -0.4318 0.9525)
			(end 0.4318 -0.9525)
			(stroke
				(width 0)
				(type default)
			)
			(fill no)
			(layer "F.Fab")
		)
		(pad "1" smd custom
			(at 0 -0.4445 180)
			(size 0.1524 0.1524)
			(layers "F.Cu" "F.Mask" "F.Paste")
			(net "VDD_IO_1")
			(options
				(clearance outline)
				(anchor circle)
			)
			(primitives
				(gr_poly
					(pts
						(arc
							(start 0.3048 -0.2032)
							(mid 0.275042 -0.275042)
							(end 0.2032 -0.3048)
						)
						(arc
							(start -0.2032 -0.3048)
							(mid -0.275042 -0.275042)
							(end -0.3048 -0.2032)
						)
						(arc
							(start -0.3048 0.2032)
							(mid -0.275042 0.275042)
							(end -0.2032 0.3048)
						)
						(arc
							(start 0.2032 0.3048)
							(mid 0.275042 0.275042)
							(end 0.3048 0.2032)
						)
					)
					(width 0)
					(fill yes)
				)
			)
		)
		(pad "2" smd custom
			(at 0 0.4445 180)
			(size 0.1524 0.1524)
			(layers "F.Cu" "F.Mask" "F.Paste")
			(net "GND")
			(options
				(clearance outline)
				(anchor circle)
			)
			(primitives
				(gr_poly
					(pts
						(arc
							(start 0.3048 -0.2032)
							(mid 0.275042 -0.275042)
							(end 0.2032 -0.3048)
						)
						(arc
							(start -0.2032 -0.3048)
							(mid -0.275042 -0.275042)
							(end -0.3048 -0.2032)
						)
						(arc
							(start -0.3048 0.2032)
							(mid -0.275042 0.275042)
							(end -0.2032 0.3048)
						)
						(arc
							(start 0.2032 0.3048)
							(mid 0.275042 0.275042)
							(end 0.3048 0.2032)
						)
					)
					(width 0)
					(fill yes)
				)
			)
		)
	)
	(footprint ""
		(layer "F.Cu")
		(at 8.8138 -473.7608 90)
		(property "Reference" "PC1096"
			(at 0 0 90)
			(layer "F.SilkS")
			(hide yes)
			(effects
				(font
					(size 1.27 1.27)
				)
			)
		)
		(property "Value" "SC22U25V6KX-GP-U"
			(at -2.860802 -5.279644 90)
			(unlocked yes)
			(layer "F.Fab")
			(hide yes)
			(effects
				(font
					(size 1.016 1.016)
					(thickness 0.1524)
				)
			)
		)
		(property "Device Type" "C1206-TO0D3H75"
			(at -2.860802 -6.803644 90)
			(unlocked yes)
			(layer "F.Fab")
			(hide yes)
			(effects
				(font
					(size 1.016 1.016)
					(thickness 0.1524)
				)
			)
		)
		(duplicate_pad_numbers_are_jumpers no)
		(fp_line
			(start 1.3081 -2.3749)
			(end 1.3081 2.3749)
			(stroke
				(width 0.1524)
				(type default)
			)
			(layer "F.SilkS")
		)
		(fp_line
			(start -1.3081 -2.3749)
			(end 1.3081 -2.3749)
			(stroke
				(width 0.1524)
				(type default)
			)
			(layer "F.SilkS")
		)
		(fp_line
			(start 1.3081 2.3749)
			(end -1.3081 2.3749)
			(stroke
				(width 0.1524)
				(type default)
			)
			(layer "F.SilkS")
		)
		(fp_line
			(start -1.3081 2.3749)
			(end -1.3081 -2.3749)
			(stroke
				(width 0.1524)
				(type default)
			)
			(layer "F.SilkS")
		)
		(fp_rect
			(start -0.8001 1.6002)
			(end 0.8001 -1.6002)
			(stroke
				(width 0)
				(type default)
			)
			(fill no)
			(layer "F.CrtYd")
		)
		(fp_poly
			(pts
				(xy -1.5621 2.4511) (xy -1.5621 1.6002) (xy 0.8001 1.6002) (xy 0.8001 -1.6002) (xy -0.8001 -1.6002)
				(xy -0.8001 1.5875) (xy -1.5621 1.5875) (xy -1.5621 -2.4511) (xy 1.5621 -2.4511) (xy 1.5621 2.4511)
			)
			(stroke
				(width 0)
				(type default)
			)
			(fill no)
			(layer "F.CrtYd")
		)
		(fp_rect
			(start -1.5621 2.4511)
			(end 1.5621 -2.4511)
			(stroke
				(width 0)
				(type default)
			)
			(fill no)
			(layer "F.Fab")
		)
		(pad "1" smd rect
			(at 0 -1.392936 90)
			(size 2.1082 1.4478)
			(layers "F.Cu" "F.Mask" "F.Paste")
			(net "P12V")
		)
		(pad "2" smd rect
			(at 0 1.392936 90)
			(size 2.1082 1.4478)
			(layers "F.Cu" "F.Mask" "F.Paste")
			(net "GND")
		)
	)
	(footprint ""
		(layer "F.Cu")
		(at 81.661 -360.045 -90)
		(property "Reference" "SR990"
			(at 0 0 270)
			(layer "F.SilkS")
			(hide yes)
			(effects
				(font
					(size 1.27 1.27)
				)
			)
		)
		(property "Value" "2KR2F-3-GP"
			(at 0.064008 -3.993896 270)
			(unlocked yes)
			(layer "F.Fab")
			(hide yes)
			(effects
				(font
					(size 1.016 1.016)
					(thickness 0.1524)
				)
			)
		)
		(property "Device Type" "R402H16"
			(at 0.064008 -5.517896 270)
			(unlocked yes)
			(layer "F.Fab")
			(hide yes)
			(effects
				(font
					(size 1.016 1.016)
					(thickness 0.1524)
				)
			)
		)
		(duplicate_pad_numbers_are_jumpers no)
		(fp_line
			(start -0.508 -0.9398)
			(end -0.508 0.9398)
			(stroke
				(width 0.1524)
				(type default)
			)
			(layer "F.SilkS")
		)
		(fp_line
			(start 0.508 -0.9398)
			(end -0.508 -0.9398)
			(stroke
				(width 0.1524)
				(type default)
			)
			(layer "F.SilkS")
		)
		(fp_rect
			(start -0.508 0.9398)
			(end 0.508 -0.9398)
			(stroke
				(width 0)
				(type default)
			)
			(fill no)
			(layer "F.CrtYd")
		)
		(fp_rect
			(start -0.508 0.9398)
			(end 0.508 -0.9398)
			(stroke
				(width 0)
				(type default)
			)
			(fill no)
			(layer "F.Fab")
		)
		(pad "1" smd custom
			(at 0 -0.4445 270)
			(size 0.1397 0.1397)
			(layers "F.Cu" "F.Mask" "F.Paste")
			(net "P3V3")
			(options
				(clearance outline)
				(anchor circle)
			)
			(primitives
				(gr_poly
					(pts
						(arc
							(start -0.1778 -0.2794)
							(mid -0.249642 -0.249642)
							(end -0.2794 -0.1778)
						)
						(arc
							(start -0.2794 0.1778)
							(mid -0.249642 0.249642)
							(end -0.1778 0.2794)
						)
						(arc
							(start 0.1778 0.2794)
							(mid 0.249642 0.249642)
							(end 0.2794 0.1778)
						)
						(arc
							(start 0.2794 -0.1778)
							(mid 0.249642 -0.249642)
							(end 0.1778 -0.2794)
						)
					)
					(width 0)
					(fill yes)
				)
			)
		)
		(pad "2" smd custom
			(at 0 0.4445 270)
			(size 0.1397 0.1397)
			(layers "F.Cu" "F.Mask" "F.Paste")
			(net "SDA_DR1")
			(options
				(clearance outline)
				(anchor circle)
			)
			(primitives
				(gr_poly
					(pts
						(arc
							(start -0.1778 -0.2794)
							(mid -0.249642 -0.249642)
							(end -0.2794 -0.1778)
						)
						(arc
							(start -0.2794 0.1778)
							(mid -0.249642 0.249642)
							(end -0.1778 0.2794)
						)
						(arc
							(start 0.1778 0.2794)
							(mid 0.249642 0.249642)
							(end 0.2794 0.1778)
						)
						(arc
							(start 0.2794 -0.1778)
							(mid 0.249642 -0.249642)
							(end 0.1778 -0.2794)
						)
					)
					(width 0)
					(fill yes)
				)
			)
		)
	)
	(footprint ""
		(layer "F.Cu")
		(at 210.312 -190.119)
		(property "Reference" "C385"
			(at 0 0 0)
			(layer "F.SilkS")
			(hide yes)
			(effects
				(font
					(size 1.27 1.27)
				)
			)
		)
		(property "Value" "SCD1U25V2KX-2-GP"
			(at 1.1811 -2.7051 0)
			(unlocked yes)
			(layer "F.Fab")
			(hide yes)
			(effects
				(font
					(size 1.016 1.016)
					(thickness 0.1524)
				)
			)
		)
		(property "Device Type" "C402H22"
			(at 1.1811 -4.2291 0)
			(unlocked yes)
			(layer "F.Fab")
			(hide yes)
			(effects
				(font
					(size 1.016 1.016)
					(thickness 0.1524)
				)
			)
		)
		(duplicate_pad_numbers_are_jumpers no)
		(fp_rect
			(start -0.4318 0.9525)
			(end 0.4318 -0.9525)
			(stroke
				(width 0)
				(type default)
			)
			(fill no)
			(layer "F.CrtYd")
		)
		(fp_rect
			(start -0.4318 0.9525)
			(end 0.4318 -0.9525)
			(stroke
				(width 0)
				(type default)
			)
			(fill no)
			(layer "F.Fab")
		)
		(pad "1" smd custom
			(at 0 -0.4445)
			(size 0.1524 0.1524)
			(layers "F.Cu" "F.Mask" "F.Paste")
			(net "P12V")
			(options
				(clearance outline)
				(anchor circle)
			)
			(primitives
				(gr_poly
					(pts
						(arc
							(start 0.3048 -0.2032)
							(mid 0.275042 -0.275042)
							(end 0.2032 -0.3048)
						)
						(arc
							(start -0.2032 -0.3048)
							(mid -0.275042 -0.275042)
							(end -0.3048 -0.2032)
						)
						(arc
							(start -0.3048 0.2032)
							(mid -0.275042 0.275042)
							(end -0.2032 0.3048)
						)
						(arc
							(start 0.2032 0.3048)
							(mid 0.275042 0.275042)
							(end 0.3048 0.2032)
						)
					)
					(width 0)
					(fill yes)
				)
			)
		)
		(pad "2" smd custom
			(at 0 0.4445)
			(size 0.1524 0.1524)
			(layers "F.Cu" "F.Mask" "F.Paste")
			(net "SW_SSD3_N")
			(options
				(clearance outline)
				(anchor circle)
			)
			(primitives
				(gr_poly
					(pts
						(arc
							(start 0.3048 -0.2032)
							(mid 0.275042 -0.275042)
							(end 0.2032 -0.3048)
						)
						(arc
							(start -0.2032 -0.3048)
							(mid -0.275042 -0.275042)
							(end -0.3048 -0.2032)
						)
						(arc
							(start -0.3048 0.2032)
							(mid -0.275042 0.275042)
							(end -0.2032 0.3048)
						)
						(arc
							(start 0.2032 0.3048)
							(mid 0.275042 0.275042)
							(end 0.3048 0.2032)
						)
					)
					(width 0)
					(fill yes)
				)
			)
		)
	)
	(footprint ""
		(layer "F.Cu")
		(at 20.066 -373.38 -90)
		(property "Reference" "R9853"
			(at 0 0 270)
			(layer "F.SilkS")
			(hide yes)
			(effects
				(font
					(size 1.27 1.27)
				)
			)
		)
		(property "Value" "0R2J-2-GP"
			(at 0.064008 -3.993896 270)
			(unlocked yes)
			(layer "F.Fab")
			(hide yes)
			(effects
				(font
					(size 1.016 1.016)
					(thickness 0.1524)
				)
			)
		)
		(property "Device Type" "R402H16"
			(at 0.064008 -5.517896 270)
			(unlocked yes)
			(layer "F.Fab")
			(hide yes)
			(effects
				(font
					(size 1.016 1.016)
					(thickness 0.1524)
				)
			)
		)
		(duplicate_pad_numbers_are_jumpers no)
		(fp_line
			(start -0.508 -0.9398)
			(end -0.508 0.9398)
			(stroke
				(width 0.1524)
				(type default)
			)
			(layer "F.SilkS")
		)
		(fp_line
			(start 0.508 -0.9398)
			(end -0.508 -0.9398)
			(stroke
				(width 0.1524)
				(type default)
			)
			(layer "F.SilkS")
		)
		(fp_rect
			(start -0.508 0.9398)
			(end 0.508 -0.9398)
			(stroke
				(width 0)
				(type default)
			)
			(fill no)
			(layer "F.CrtYd")
		)
		(fp_rect
			(start -0.508 0.9398)
			(end 0.508 -0.9398)
			(stroke
				(width 0)
				(type default)
			)
			(fill no)
			(layer "F.Fab")
		)
		(pad "1" smd custom
			(at 0 -0.4445 270)
			(size 0.1397 0.1397)
			(layers "F.Cu" "F.Mask" "F.Paste")
			(net "ATTN_LED_DR11_AND")
			(options
				(clearance outline)
				(anchor circle)
			)
			(primitives
				(gr_poly
					(pts
						(arc
							(start -0.1778 -0.2794)
							(mid -0.249642 -0.249642)
							(end -0.2794 -0.1778)
						)
						(arc
							(start -0.2794 0.1778)
							(mid -0.249642 0.249642)
							(end -0.1778 0.2794)
						)
						(arc
							(start 0.1778 0.2794)
							(mid 0.249642 0.249642)
							(end 0.2794 0.1778)
						)
						(arc
							(start 0.2794 -0.1778)
							(mid 0.249642 -0.249642)
							(end 0.1778 -0.2794)
						)
					)
					(width 0)
					(fill yes)
				)
			)
		)
		(pad "2" smd custom
			(at 0 0.4445 270)
			(size 0.1397 0.1397)
			(layers "F.Cu" "F.Mask" "F.Paste")
			(net "ATTN_LED_DR11_AND_R")
			(options
				(clearance outline)
				(anchor circle)
			)
			(primitives
				(gr_poly
					(pts
						(arc
							(start -0.1778 -0.2794)
							(mid -0.249642 -0.249642)
							(end -0.2794 -0.1778)
						)
						(arc
							(start -0.2794 0.1778)
							(mid -0.249642 0.249642)
							(end -0.1778 0.2794)
						)
						(arc
							(start 0.1778 0.2794)
							(mid 0.249642 0.249642)
							(end 0.2794 0.1778)
						)
						(arc
							(start 0.2794 -0.1778)
							(mid 0.249642 -0.249642)
							(end 0.1778 -0.2794)
						)
					)
					(width 0)
					(fill yes)
				)
			)
		)
	)
	(footprint ""
		(layer "F.Cu")
		(at 31.0896 -290.6522 180)
		(property "Reference" "SR1106"
			(at 0 0 180)
			(layer "F.SilkS")
			(hide yes)
			(effects
				(font
					(size 1.27 1.27)
				)
			)
		)
		(property "Value" "4K7R2F-GP"
			(at 0.064008 -3.993896 180)
			(unlocked yes)
			(layer "F.Fab")
			(hide yes)
			(effects
				(font
					(size 1.016 1.016)
					(thickness 0.1524)
				)
			)
		)
		(property "Device Type" "R402H16"
			(at 0.064008 -5.517896 180)
			(unlocked yes)
			(layer "F.Fab")
			(hide yes)
			(effects
				(font
					(size 1.016 1.016)
					(thickness 0.1524)
				)
			)
		)
		(duplicate_pad_numbers_are_jumpers no)
		(fp_line
			(start 0.508 -0.9398)
			(end -0.508 -0.9398)
			(stroke
				(width 0.1524)
				(type default)
			)
			(layer "F.SilkS")
		)
		(fp_line
			(start -0.508 -0.9398)
			(end -0.508 0.9398)
			(stroke
				(width 0.1524)
				(type default)
			)
			(layer "F.SilkS")
		)
		(fp_rect
			(start -0.508 0.9398)
			(end 0.508 -0.9398)
			(stroke
				(width 0)
				(type default)
			)
			(fill no)
			(layer "F.CrtYd")
		)
		(fp_rect
			(start -0.508 0.9398)
			(end 0.508 -0.9398)
			(stroke
				(width 0)
				(type default)
			)
			(fill no)
			(layer "F.Fab")
		)
		(pad "1" smd custom
			(at 0 -0.4445 180)
			(size 0.1397 0.1397)
			(layers "F.Cu" "F.Mask" "F.Paste")
			(net "DUALPORTEN#7")
			(options
				(clearance outline)
				(anchor circle)
			)
			(primitives
				(gr_poly
					(pts
						(arc
							(start -0.1778 -0.2794)
							(mid -0.249642 -0.249642)
							(end -0.2794 -0.1778)
						)
						(arc
							(start -0.2794 0.1778)
							(mid -0.249642 0.249642)
							(end -0.1778 0.2794)
						)
						(arc
							(start 0.1778 0.2794)
							(mid 0.249642 0.249642)
							(end 0.2794 0.1778)
						)
						(arc
							(start 0.2794 -0.1778)
							(mid 0.249642 -0.249642)
							(end 0.1778 -0.2794)
						)
					)
					(width 0)
					(fill yes)
				)
			)
		)
		(pad "2" smd custom
			(at 0 0.4445 180)
			(size 0.1397 0.1397)
			(layers "F.Cu" "F.Mask" "F.Paste")
			(net "GND")
			(options
				(clearance outline)
				(anchor circle)
			)
			(primitives
				(gr_poly
					(pts
						(arc
							(start -0.1778 -0.2794)
							(mid -0.249642 -0.249642)
							(end -0.2794 -0.1778)
						)
						(arc
							(start -0.2794 0.1778)
							(mid -0.249642 0.249642)
							(end -0.1778 0.2794)
						)
						(arc
							(start 0.1778 0.2794)
							(mid 0.249642 0.249642)
							(end 0.2794 0.1778)
						)
						(arc
							(start 0.2794 -0.1778)
							(mid 0.249642 -0.249642)
							(end 0.1778 -0.2794)
						)
					)
					(width 0)
					(fill yes)
				)
			)
		)
	)
	(footprint ""
		(layer "F.Cu")
		(at 31.6992 -492.5314 -90)
		(property "Reference" "R398"
			(at 0 0 270)
			(layer "F.SilkS")
			(hide yes)
			(effects
				(font
					(size 1.27 1.27)
				)
			)
		)
		(property "Value" "0R2J-2-GP"
			(at 0.064008 -3.993896 270)
			(unlocked yes)
			(layer "F.Fab")
			(hide yes)
			(effects
				(font
					(size 1.016 1.016)
					(thickness 0.1524)
				)
			)
		)
		(property "Device Type" "R402H16"
			(at 0.064008 -5.517896 270)
			(unlocked yes)
			(layer "F.Fab")
			(hide yes)
			(effects
				(font
					(size 1.016 1.016)
					(thickness 0.1524)
				)
			)
		)
		(duplicate_pad_numbers_are_jumpers no)
		(fp_line
			(start -0.508 -0.9398)
			(end -0.508 0.9398)
			(stroke
				(width 0.1524)
				(type default)
			)
			(layer "F.SilkS")
		)
		(fp_line
			(start 0.508 -0.9398)
			(end -0.508 -0.9398)
			(stroke
				(width 0.1524)
				(type default)
			)
			(layer "F.SilkS")
		)
		(fp_rect
			(start -0.508 0.9398)
			(end 0.508 -0.9398)
			(stroke
				(width 0)
				(type default)
			)
			(fill no)
			(layer "F.CrtYd")
		)
		(fp_rect
			(start -0.508 0.9398)
			(end 0.508 -0.9398)
			(stroke
				(width 0)
				(type default)
			)
			(fill no)
			(layer "F.Fab")
		)
		(pad "1" smd custom
			(at 0 -0.4445 270)
			(size 0.1397 0.1397)
			(layers "F.Cu" "F.Mask" "F.Paste")
			(net "SDA_DR5_R")
			(options
				(clearance outline)
				(anchor circle)
			)
			(primitives
				(gr_poly
					(pts
						(arc
							(start -0.1778 -0.2794)
							(mid -0.249642 -0.249642)
							(end -0.2794 -0.1778)
						)
						(arc
							(start -0.2794 0.1778)
							(mid -0.249642 0.249642)
							(end -0.1778 0.2794)
						)
						(arc
							(start 0.1778 0.2794)
							(mid 0.249642 0.249642)
							(end 0.2794 0.1778)
						)
						(arc
							(start 0.2794 -0.1778)
							(mid 0.249642 -0.249642)
							(end 0.1778 -0.2794)
						)
					)
					(width 0)
					(fill yes)
				)
			)
		)
		(pad "2" smd custom
			(at 0 0.4445 270)
			(size 0.1397 0.1397)
			(layers "F.Cu" "F.Mask" "F.Paste")
			(net "SDA_DR5")
			(options
				(clearance outline)
				(anchor circle)
			)
			(primitives
				(gr_poly
					(pts
						(arc
							(start -0.1778 -0.2794)
							(mid -0.249642 -0.249642)
							(end -0.2794 -0.1778)
						)
						(arc
							(start -0.2794 0.1778)
							(mid -0.249642 0.249642)
							(end -0.1778 0.2794)
						)
						(arc
							(start 0.1778 0.2794)
							(mid 0.249642 0.249642)
							(end 0.2794 0.1778)
						)
						(arc
							(start 0.2794 -0.1778)
							(mid 0.249642 -0.249642)
							(end 0.1778 -0.2794)
						)
					)
					(width 0)
					(fill yes)
				)
			)
		)
	)
	(footprint ""
		(layer "F.Cu")
		(at 70.739 -357.505 -90)
		(property "Reference" "SR1051"
			(at 0 0 270)
			(layer "F.SilkS")
			(hide yes)
			(effects
				(font
					(size 1.27 1.27)
				)
			)
		)
		(property "Value" "4K7R2F-GP"
			(at 0.064008 -3.993896 270)
			(unlocked yes)
			(layer "F.Fab")
			(hide yes)
			(effects
				(font
					(size 1.016 1.016)
					(thickness 0.1524)
				)
			)
		)
		(property "Device Type" "R402H16"
			(at 0.064008 -5.517896 270)
			(unlocked yes)
			(layer "F.Fab")
			(hide yes)
			(effects
				(font
					(size 1.016 1.016)
					(thickness 0.1524)
				)
			)
		)
		(duplicate_pad_numbers_are_jumpers no)
		(fp_line
			(start -0.508 -0.9398)
			(end -0.508 0.9398)
			(stroke
				(width 0.1524)
				(type default)
			)
			(layer "F.SilkS")
		)
		(fp_line
			(start 0.508 -0.9398)
			(end -0.508 -0.9398)
			(stroke
				(width 0.1524)
				(type default)
			)
			(layer "F.SilkS")
		)
		(fp_rect
			(start -0.508 0.9398)
			(end 0.508 -0.9398)
			(stroke
				(width 0)
				(type default)
			)
			(fill no)
			(layer "F.CrtYd")
		)
		(fp_rect
			(start -0.508 0.9398)
			(end 0.508 -0.9398)
			(stroke
				(width 0)
				(type default)
			)
			(fill no)
			(layer "F.Fab")
		)
		(pad "1" smd custom
			(at 0 -0.4445 270)
			(size 0.1397 0.1397)
			(layers "F.Cu" "F.Mask" "F.Paste")
			(net "I2C_SW_EU17_ADDRESS_A2")
			(options
				(clearance outline)
				(anchor circle)
			)
			(primitives
				(gr_poly
					(pts
						(arc
							(start -0.1778 -0.2794)
							(mid -0.249642 -0.249642)
							(end -0.2794 -0.1778)
						)
						(arc
							(start -0.2794 0.1778)
							(mid -0.249642 0.249642)
							(end -0.1778 0.2794)
						)
						(arc
							(start 0.1778 0.2794)
							(mid 0.249642 0.249642)
							(end 0.2794 0.1778)
						)
						(arc
							(start 0.2794 -0.1778)
							(mid 0.249642 -0.249642)
							(end 0.1778 -0.2794)
						)
					)
					(width 0)
					(fill yes)
				)
			)
		)
		(pad "2" smd custom
			(at 0 0.4445 270)
			(size 0.1397 0.1397)
			(layers "F.Cu" "F.Mask" "F.Paste")
			(net "GND")
			(options
				(clearance outline)
				(anchor circle)
			)
			(primitives
				(gr_poly
					(pts
						(arc
							(start -0.1778 -0.2794)
							(mid -0.249642 -0.249642)
							(end -0.2794 -0.1778)
						)
						(arc
							(start -0.2794 0.1778)
							(mid -0.249642 0.249642)
							(end -0.1778 0.2794)
						)
						(arc
							(start 0.1778 0.2794)
							(mid 0.249642 0.249642)
							(end 0.2794 0.1778)
						)
						(arc
							(start 0.2794 -0.1778)
							(mid 0.249642 -0.249642)
							(end 0.1778 -0.2794)
						)
					)
					(width 0)
					(fill yes)
				)
			)
		)
	)
	(footprint ""
		(layer "F.Cu")
		(at 37.6936 -208.8134)
		(property "Reference" "Q20"
			(at 0 0 0)
			(layer "F.SilkS")
			(hide yes)
			(effects
				(font
					(size 1.27 1.27)
				)
			)
		)
		(property "Value" "2N7002A-7-GP"
			(at 0.127 -8.9662 0)
			(unlocked yes)
			(layer "F.Fab")
			(hide yes)
			(effects
				(font
					(size 1.016 1.016)
					(thickness 0.1524)
				)
			)
		)
		(property "Device Type" "SOT23DGS2D4H48"
			(at 0.127 -10.4902 0)
			(unlocked yes)
			(layer "F.Fab")
			(hide yes)
			(effects
				(font
					(size 1.016 1.016)
					(thickness 0.1524)
				)
			)
		)
		(duplicate_pad_numbers_are_jumpers no)
		(fp_line
			(start -1.651 -1.778)
			(end -1.651 1.778)
			(stroke
				(width 0.1524)
				(type default)
			)
			(layer "F.SilkS")
		)
		(fp_line
			(start -1.651 1.778)
			(end 1.651 1.778)
			(stroke
				(width 0.1524)
				(type default)
			)
			(layer "F.SilkS")
		)
		(fp_line
			(start 1.651 -1.778)
			(end -1.651 -1.778)
			(stroke
				(width 0.1524)
				(type default)
			)
			(layer "F.SilkS")
		)
		(fp_line
			(start 1.651 1.778)
			(end 1.651 -1.778)
			(stroke
				(width 0.1524)
				(type default)
			)
			(layer "F.SilkS")
		)
		(fp_poly
			(pts
				(xy -1.778 1.8796) (xy -1.778 -1.8796) (xy 1.778 -1.8796) (xy 1.778 1.8796)
			)
			(stroke
				(width 0)
				(type default)
			)
			(fill no)
			(layer "F.CrtYd")
		)
		(fp_poly
			(pts
				(xy -1.778 1.8796) (xy -1.778 -1.8796) (xy 1.778 -1.8796) (xy 1.778 1.8796)
			)
			(stroke
				(width 0)
				(type default)
			)
			(fill no)
			(layer "F.Fab")
		)
		(pad "D" smd custom
			(at 0 -0.9525)
			(size 0.1905 0.1905)
			(layers "F.Cu" "F.Mask" "F.Paste")
			(net "SW_SSD12_R")
			(options
				(clearance outline)
				(anchor circle)
			)
			(primitives
				(gr_poly
					(pts
						(arc
							(start -0.1778 0.5715)
							(mid -0.321484 0.511984)
							(end -0.381 0.3683)
						)
						(arc
							(start -0.381 -0.3683)
							(mid -0.321484 -0.511984)
							(end -0.1778 -0.5715)
						)
						(arc
							(start 0.1778 -0.5715)
							(mid 0.321484 -0.511984)
							(end 0.381 -0.3683)
						)
						(arc
							(start 0.381 0.3683)
							(mid 0.321484 0.511984)
							(end 0.1778 0.5715)
						)
					)
					(width 0)
					(fill yes)
				)
			)
		)
		(pad "G" smd custom
			(at -0.98425 0.9525)
			(size 0.1905 0.1905)
			(layers "F.Cu" "F.Mask" "F.Paste")
			(net "SSD12_PWREN")
			(options
				(clearance outline)
				(anchor circle)
			)
			(primitives
				(gr_poly
					(pts
						(arc
							(start -0.1778 0.5715)
							(mid -0.321484 0.511984)
							(end -0.381 0.3683)
						)
						(arc
							(start -0.381 -0.3683)
							(mid -0.321484 -0.511984)
							(end -0.1778 -0.5715)
						)
						(arc
							(start 0.1778 -0.5715)
							(mid 0.321484 -0.511984)
							(end 0.381 -0.3683)
						)
						(arc
							(start 0.381 0.3683)
							(mid 0.321484 0.511984)
							(end 0.1778 0.5715)
						)
					)
					(width 0)
					(fill yes)
				)
			)
		)
		(pad "S" smd custom
			(at 0.98425 0.9525)
			(size 0.1905 0.1905)
			(layers "F.Cu" "F.Mask" "F.Paste")
			(net "GND")
			(options
				(clearance outline)
				(anchor circle)
			)
			(primitives
				(gr_poly
					(pts
						(arc
							(start -0.1778 0.5715)
							(mid -0.321484 0.511984)
							(end -0.381 0.3683)
						)
						(arc
							(start -0.381 -0.3683)
							(mid -0.321484 -0.511984)
							(end -0.1778 -0.5715)
						)
						(arc
							(start 0.1778 -0.5715)
							(mid 0.321484 -0.511984)
							(end 0.381 -0.3683)
						)
						(arc
							(start 0.381 0.3683)
							(mid 0.321484 0.511984)
							(end 0.1778 0.5715)
						)
					)
					(width 0)
					(fill yes)
				)
			)
		)
	)
	(footprint ""
		(layer "F.Cu")
		(at 39.83355 -410.01315 -90)
		(property "Reference" "R9845"
			(at 0 0 270)
			(layer "F.SilkS")
			(hide yes)
			(effects
				(font
					(size 1.27 1.27)
				)
			)
		)
		(property "Value" "1KR2J-1-GP"
			(at 0.064008 -3.993896 270)
			(unlocked yes)
			(layer "F.Fab")
			(hide yes)
			(effects
				(font
					(size 1.016 1.016)
					(thickness 0.1524)
				)
			)
		)
		(property "Device Type" "R402H16"
			(at 0.064008 -5.517896 270)
			(unlocked yes)
			(layer "F.Fab")
			(hide yes)
			(effects
				(font
					(size 1.016 1.016)
					(thickness 0.1524)
				)
			)
		)
		(duplicate_pad_numbers_are_jumpers no)
		(fp_line
			(start -0.508 -0.9398)
			(end -0.508 0.9398)
			(stroke
				(width 0.1524)
				(type default)
			)
			(layer "F.SilkS")
		)
		(fp_line
			(start 0.508 -0.9398)
			(end -0.508 -0.9398)
			(stroke
				(width 0.1524)
				(type default)
			)
			(layer "F.SilkS")
		)
		(fp_rect
			(start -0.508 0.9398)
			(end 0.508 -0.9398)
			(stroke
				(width 0)
				(type default)
			)
			(fill no)
			(layer "F.CrtYd")
		)
		(fp_rect
			(start -0.508 0.9398)
			(end 0.508 -0.9398)
			(stroke
				(width 0)
				(type default)
			)
			(fill no)
			(layer "F.Fab")
		)
		(pad "1" smd custom
			(at 0 -0.4445 270)
			(size 0.1397 0.1397)
			(layers "F.Cu" "F.Mask" "F.Paste")
			(net "SSD10_PWREN")
			(options
				(clearance outline)
				(anchor circle)
			)
			(primitives
				(gr_poly
					(pts
						(arc
							(start -0.1778 -0.2794)
							(mid -0.249642 -0.249642)
							(end -0.2794 -0.1778)
						)
						(arc
							(start -0.2794 0.1778)
							(mid -0.249642 0.249642)
							(end -0.1778 0.2794)
						)
						(arc
							(start 0.1778 0.2794)
							(mid 0.249642 0.249642)
							(end 0.2794 0.1778)
						)
						(arc
							(start 0.2794 -0.1778)
							(mid 0.249642 -0.249642)
							(end 0.1778 -0.2794)
						)
					)
					(width 0)
					(fill yes)
				)
			)
		)
		(pad "2" smd custom
			(at 0 0.4445 270)
			(size 0.1397 0.1397)
			(layers "F.Cu" "F.Mask" "F.Paste")
			(net "SSD10_PWREN_R")
			(options
				(clearance outline)
				(anchor circle)
			)
			(primitives
				(gr_poly
					(pts
						(arc
							(start -0.1778 -0.2794)
							(mid -0.249642 -0.249642)
							(end -0.2794 -0.1778)
						)
						(arc
							(start -0.2794 0.1778)
							(mid -0.249642 0.249642)
							(end -0.1778 0.2794)
						)
						(arc
							(start 0.1778 0.2794)
							(mid 0.249642 0.249642)
							(end 0.2794 0.1778)
						)
						(arc
							(start 0.2794 -0.1778)
							(mid 0.249642 -0.249642)
							(end 0.1778 -0.2794)
						)
					)
					(width 0)
					(fill yes)
				)
			)
		)
	)
	(footprint ""
		(layer "F.Cu")
		(at 35.56 -297.18 180)
		(property "Reference" "PC1245"
			(at 0 0 180)
			(layer "F.SilkS")
			(hide yes)
			(effects
				(font
					(size 1.27 1.27)
				)
			)
		)
		(property "Value" "SC22U25V6KX-GP-U"
			(at -2.860802 -5.279644 180)
			(unlocked yes)
			(layer "F.Fab")
			(hide yes)
			(effects
				(font
					(size 1.016 1.016)
					(thickness 0.1524)
				)
			)
		)
		(property "Device Type" "C1206-TO0D3H75"
			(at -2.860802 -6.803644 180)
			(unlocked yes)
			(layer "F.Fab")
			(hide yes)
			(effects
				(font
					(size 1.016 1.016)
					(thickness 0.1524)
				)
			)
		)
		(duplicate_pad_numbers_are_jumpers no)
		(fp_line
			(start 1.3081 2.3749)
			(end -1.3081 2.3749)
			(stroke
				(width 0.1524)
				(type default)
			)
			(layer "F.SilkS")
		)
		(fp_line
			(start 1.3081 -2.3749)
			(end 1.3081 2.3749)
			(stroke
				(width 0.1524)
				(type default)
			)
			(layer "F.SilkS")
		)
		(fp_line
			(start -1.3081 2.3749)
			(end -1.3081 -2.3749)
			(stroke
				(width 0.1524)
				(type default)
			)
			(layer "F.SilkS")
		)
		(fp_line
			(start -1.3081 -2.3749)
			(end 1.3081 -2.3749)
			(stroke
				(width 0.1524)
				(type default)
			)
			(layer "F.SilkS")
		)
		(fp_rect
			(start -0.8001 1.6002)
			(end 0.8001 -1.6002)
			(stroke
				(width 0)
				(type default)
			)
			(fill no)
			(layer "F.CrtYd")
		)
		(fp_poly
			(pts
				(xy -1.5621 2.4511) (xy -1.5621 1.6002) (xy 0.8001 1.6002) (xy 0.8001 -1.6002) (xy -0.8001 -1.6002)
				(xy -0.8001 1.5875) (xy -1.5621 1.5875) (xy -1.5621 -2.4511) (xy 1.5621 -2.4511) (xy 1.5621 2.4511)
			)
			(stroke
				(width 0)
				(type default)
			)
			(fill no)
			(layer "F.CrtYd")
		)
		(fp_rect
			(start -1.5621 2.4511)
			(end 1.5621 -2.4511)
			(stroke
				(width 0)
				(type default)
			)
			(fill no)
			(layer "F.Fab")
		)
		(pad "1" smd rect
			(at 0 -1.392936 180)
			(size 2.1082 1.4478)
			(layers "F.Cu" "F.Mask" "F.Paste")
			(net "P12V_SSD7")
		)
		(pad "2" smd rect
			(at 0 1.392936 180)
			(size 2.1082 1.4478)
			(layers "F.Cu" "F.Mask" "F.Paste")
			(net "GND")
		)
	)
	(footprint ""
		(layer "F.Cu")
		(at 219.329 -243.580158 90)
		(property "Reference" "SR1125"
			(at 0 0 90)
			(layer "F.SilkS")
			(hide yes)
			(effects
				(font
					(size 1.27 1.27)
				)
			)
		)
		(property "Value" "4K7R2F-GP"
			(at 0.064008 -3.993896 90)
			(unlocked yes)
			(layer "F.Fab")
			(hide yes)
			(effects
				(font
					(size 1.016 1.016)
					(thickness 0.1524)
				)
			)
		)
		(property "Device Type" "R402H16"
			(at 0.064008 -5.517896 90)
			(unlocked yes)
			(layer "F.Fab")
			(hide yes)
			(effects
				(font
					(size 1.016 1.016)
					(thickness 0.1524)
				)
			)
		)
		(duplicate_pad_numbers_are_jumpers no)
		(fp_line
			(start 0.508 -0.9398)
			(end -0.508 -0.9398)
			(stroke
				(width 0.1524)
				(type default)
			)
			(layer "F.SilkS")
		)
		(fp_line
			(start -0.508 -0.9398)
			(end -0.508 0.9398)
			(stroke
				(width 0.1524)
				(type default)
			)
			(layer "F.SilkS")
		)
		(fp_rect
			(start -0.508 0.9398)
			(end 0.508 -0.9398)
			(stroke
				(width 0)
				(type default)
			)
			(fill no)
			(layer "F.CrtYd")
		)
		(fp_rect
			(start -0.508 0.9398)
			(end 0.508 -0.9398)
			(stroke
				(width 0)
				(type default)
			)
			(fill no)
			(layer "F.Fab")
		)
		(pad "1" smd custom
			(at 0 -0.4445 90)
			(size 0.1397 0.1397)
			(layers "F.Cu" "F.Mask" "F.Paste")
			(net "P3V3")
			(options
				(clearance outline)
				(anchor circle)
			)
			(primitives
				(gr_poly
					(pts
						(arc
							(start -0.1778 -0.2794)
							(mid -0.249642 -0.249642)
							(end -0.2794 -0.1778)
						)
						(arc
							(start -0.2794 0.1778)
							(mid -0.249642 0.249642)
							(end -0.1778 0.2794)
						)
						(arc
							(start 0.1778 0.2794)
							(mid 0.249642 0.249642)
							(end 0.2794 0.1778)
						)
						(arc
							(start 0.2794 -0.1778)
							(mid 0.249642 -0.249642)
							(end 0.1778 -0.2794)
						)
					)
					(width 0)
					(fill yes)
				)
			)
		)
		(pad "2" smd custom
			(at 0 0.4445 90)
			(size 0.1397 0.1397)
			(layers "F.Cu" "F.Mask" "F.Paste")
			(net "SSD2_CLK0_OE_MOS_N")
			(options
				(clearance outline)
				(anchor circle)
			)
			(primitives
				(gr_poly
					(pts
						(arc
							(start -0.1778 -0.2794)
							(mid -0.249642 -0.249642)
							(end -0.2794 -0.1778)
						)
						(arc
							(start -0.2794 0.1778)
							(mid -0.249642 0.249642)
							(end -0.1778 0.2794)
						)
						(arc
							(start 0.1778 0.2794)
							(mid 0.249642 0.249642)
							(end 0.2794 0.1778)
						)
						(arc
							(start 0.2794 -0.1778)
							(mid 0.249642 -0.249642)
							(end 0.1778 -0.2794)
						)
					)
					(width 0)
					(fill yes)
				)
			)
		)
	)
	(footprint ""
		(layer "F.Cu")
		(at 221.996 -194.437 180)
		(property "Reference" "PC1225"
			(at 0 0 180)
			(layer "F.SilkS")
			(hide yes)
			(effects
				(font
					(size 1.27 1.27)
				)
			)
		)
		(property "Value" "SC22U25V6KX-GP-U"
			(at -2.860802 -5.279644 180)
			(unlocked yes)
			(layer "F.Fab")
			(hide yes)
			(effects
				(font
					(size 1.016 1.016)
					(thickness 0.1524)
				)
			)
		)
		(property "Device Type" "C1206-TO0D3H75"
			(at -2.860802 -6.803644 180)
			(unlocked yes)
			(layer "F.Fab")
			(hide yes)
			(effects
				(font
					(size 1.016 1.016)
					(thickness 0.1524)
				)
			)
		)
		(duplicate_pad_numbers_are_jumpers no)
		(fp_line
			(start 1.3081 2.3749)
			(end -1.3081 2.3749)
			(stroke
				(width 0.1524)
				(type default)
			)
			(layer "F.SilkS")
		)
		(fp_line
			(start 1.3081 -2.3749)
			(end 1.3081 2.3749)
			(stroke
				(width 0.1524)
				(type default)
			)
			(layer "F.SilkS")
		)
		(fp_line
			(start -1.3081 2.3749)
			(end -1.3081 -2.3749)
			(stroke
				(width 0.1524)
				(type default)
			)
			(layer "F.SilkS")
		)
		(fp_line
			(start -1.3081 -2.3749)
			(end 1.3081 -2.3749)
			(stroke
				(width 0.1524)
				(type default)
			)
			(layer "F.SilkS")
		)
		(fp_rect
			(start -0.8001 1.6002)
			(end 0.8001 -1.6002)
			(stroke
				(width 0)
				(type default)
			)
			(fill no)
			(layer "F.CrtYd")
		)
		(fp_poly
			(pts
				(xy -1.5621 2.4511) (xy -1.5621 1.6002) (xy 0.8001 1.6002) (xy 0.8001 -1.6002) (xy -0.8001 -1.6002)
				(xy -0.8001 1.5875) (xy -1.5621 1.5875) (xy -1.5621 -2.4511) (xy 1.5621 -2.4511) (xy 1.5621 2.4511)
			)
			(stroke
				(width 0)
				(type default)
			)
			(fill no)
			(layer "F.CrtYd")
		)
		(fp_rect
			(start -1.5621 2.4511)
			(end 1.5621 -2.4511)
			(stroke
				(width 0)
				(type default)
			)
			(fill no)
			(layer "F.Fab")
		)
		(pad "1" smd rect
			(at 0 -1.392936 180)
			(size 2.1082 1.4478)
			(layers "F.Cu" "F.Mask" "F.Paste")
			(net "P12V_SSD3")
		)
		(pad "2" smd rect
			(at 0 1.392936 180)
			(size 2.1082 1.4478)
			(layers "F.Cu" "F.Mask" "F.Paste")
			(net "GND")
		)
	)
	(footprint ""
		(layer "F.Cu")
		(at 38.851586 -342.341708 90)
		(property "Reference" "R9918"
			(at 0 0 90)
			(layer "F.SilkS")
			(hide yes)
			(effects
				(font
					(size 1.27 1.27)
				)
			)
		)
		(property "Value" "47KR2J-2-GP"
			(at 0.064008 -3.993896 90)
			(unlocked yes)
			(layer "F.Fab")
			(hide yes)
			(effects
				(font
					(size 1.016 1.016)
					(thickness 0.1524)
				)
			)
		)
		(property "Device Type" "R402H16"
			(at 0.064008 -5.517896 90)
			(unlocked yes)
			(layer "F.Fab")
			(hide yes)
			(effects
				(font
					(size 1.016 1.016)
					(thickness 0.1524)
				)
			)
		)
		(duplicate_pad_numbers_are_jumpers no)
		(fp_line
			(start 0.508 -0.9398)
			(end -0.508 -0.9398)
			(stroke
				(width 0.1524)
				(type default)
			)
			(layer "F.SilkS")
		)
		(fp_line
			(start -0.508 -0.9398)
			(end -0.508 0.9398)
			(stroke
				(width 0.1524)
				(type default)
			)
			(layer "F.SilkS")
		)
		(fp_rect
			(start -0.508 0.9398)
			(end 0.508 -0.9398)
			(stroke
				(width 0)
				(type default)
			)
			(fill no)
			(layer "F.CrtYd")
		)
		(fp_rect
			(start -0.508 0.9398)
			(end 0.508 -0.9398)
			(stroke
				(width 0)
				(type default)
			)
			(fill no)
			(layer "F.Fab")
		)
		(pad "1" smd custom
			(at 0 -0.4445 90)
			(size 0.1397 0.1397)
			(layers "F.Cu" "F.Mask" "F.Paste")
			(net "P3V3")
			(options
				(clearance outline)
				(anchor circle)
			)
			(primitives
				(gr_poly
					(pts
						(arc
							(start -0.1778 -0.2794)
							(mid -0.249642 -0.249642)
							(end -0.2794 -0.1778)
						)
						(arc
							(start -0.2794 0.1778)
							(mid -0.249642 0.249642)
							(end -0.1778 0.2794)
						)
						(arc
							(start 0.1778 0.2794)
							(mid 0.249642 0.249642)
							(end 0.2794 0.1778)
						)
						(arc
							(start 0.2794 -0.1778)
							(mid 0.249642 -0.249642)
							(end 0.1778 -0.2794)
						)
					)
					(width 0)
					(fill yes)
				)
			)
		)
		(pad "2" smd custom
			(at 0 0.4445 90)
			(size 0.1397 0.1397)
			(layers "F.Cu" "F.Mask" "F.Paste")
			(net "ATTN_LED_DR6_N")
			(options
				(clearance outline)
				(anchor circle)
			)
			(primitives
				(gr_poly
					(pts
						(arc
							(start -0.1778 -0.2794)
							(mid -0.249642 -0.249642)
							(end -0.2794 -0.1778)
						)
						(arc
							(start -0.2794 0.1778)
							(mid -0.249642 0.249642)
							(end -0.1778 0.2794)
						)
						(arc
							(start 0.1778 0.2794)
							(mid 0.249642 0.249642)
							(end 0.2794 0.1778)
						)
						(arc
							(start 0.2794 -0.1778)
							(mid 0.249642 -0.249642)
							(end 0.1778 -0.2794)
						)
					)
					(width 0)
					(fill yes)
				)
			)
		)
	)
	(footprint ""
		(layer "F.Cu")
		(at 219.329 -346.579952 90)
		(property "Reference" "SR1123"
			(at 0 0 90)
			(layer "F.SilkS")
			(hide yes)
			(effects
				(font
					(size 1.27 1.27)
				)
			)
		)
		(property "Value" "4K7R2F-GP"
			(at 0.064008 -3.993896 90)
			(unlocked yes)
			(layer "F.Fab")
			(hide yes)
			(effects
				(font
					(size 1.016 1.016)
					(thickness 0.1524)
				)
			)
		)
		(property "Device Type" "R402H16"
			(at 0.064008 -5.517896 90)
			(unlocked yes)
			(layer "F.Fab")
			(hide yes)
			(effects
				(font
					(size 1.016 1.016)
					(thickness 0.1524)
				)
			)
		)
		(duplicate_pad_numbers_are_jumpers no)
		(fp_line
			(start 0.508 -0.9398)
			(end -0.508 -0.9398)
			(stroke
				(width 0.1524)
				(type default)
			)
			(layer "F.SilkS")
		)
		(fp_line
			(start -0.508 -0.9398)
			(end -0.508 0.9398)
			(stroke
				(width 0.1524)
				(type default)
			)
			(layer "F.SilkS")
		)
		(fp_rect
			(start -0.508 0.9398)
			(end 0.508 -0.9398)
			(stroke
				(width 0)
				(type default)
			)
			(fill no)
			(layer "F.CrtYd")
		)
		(fp_rect
			(start -0.508 0.9398)
			(end 0.508 -0.9398)
			(stroke
				(width 0)
				(type default)
			)
			(fill no)
			(layer "F.Fab")
		)
		(pad "1" smd custom
			(at 0 -0.4445 90)
			(size 0.1397 0.1397)
			(layers "F.Cu" "F.Mask" "F.Paste")
			(net "P3V3")
			(options
				(clearance outline)
				(anchor circle)
			)
			(primitives
				(gr_poly
					(pts
						(arc
							(start -0.1778 -0.2794)
							(mid -0.249642 -0.249642)
							(end -0.2794 -0.1778)
						)
						(arc
							(start -0.2794 0.1778)
							(mid -0.249642 0.249642)
							(end -0.1778 0.2794)
						)
						(arc
							(start 0.1778 0.2794)
							(mid 0.249642 0.249642)
							(end 0.2794 0.1778)
						)
						(arc
							(start 0.2794 -0.1778)
							(mid 0.249642 -0.249642)
							(end 0.1778 -0.2794)
						)
					)
					(width 0)
					(fill yes)
				)
			)
		)
		(pad "2" smd custom
			(at 0 0.4445 90)
			(size 0.1397 0.1397)
			(layers "F.Cu" "F.Mask" "F.Paste")
			(net "SSD1_CLK0_OE_MOS_N")
			(options
				(clearance outline)
				(anchor circle)
			)
			(primitives
				(gr_poly
					(pts
						(arc
							(start -0.1778 -0.2794)
							(mid -0.249642 -0.249642)
							(end -0.2794 -0.1778)
						)
						(arc
							(start -0.2794 0.1778)
							(mid -0.249642 0.249642)
							(end -0.1778 0.2794)
						)
						(arc
							(start 0.1778 0.2794)
							(mid 0.249642 0.249642)
							(end 0.2794 0.1778)
						)
						(arc
							(start 0.2794 -0.1778)
							(mid 0.249642 -0.249642)
							(end 0.1778 -0.2794)
						)
					)
					(width 0)
					(fill yes)
				)
			)
		)
	)
	(footprint ""
		(layer "F.Cu")
		(at 31.051754 -215.200484)
		(property "Reference" "SR1116"
			(at 0 0 0)
			(layer "F.SilkS")
			(hide yes)
			(effects
				(font
					(size 1.27 1.27)
				)
			)
		)
		(property "Value" "4K7R2F-GP"
			(at 0.064008 -3.993896 0)
			(unlocked yes)
			(layer "F.Fab")
			(hide yes)
			(effects
				(font
					(size 1.016 1.016)
					(thickness 0.1524)
				)
			)
		)
		(property "Device Type" "R402H16"
			(at 0.064008 -5.517896 0)
			(unlocked yes)
			(layer "F.Fab")
			(hide yes)
			(effects
				(font
					(size 1.016 1.016)
					(thickness 0.1524)
				)
			)
		)
		(duplicate_pad_numbers_are_jumpers no)
		(fp_line
			(start -0.508 -0.9398)
			(end -0.508 0.9398)
			(stroke
				(width 0.1524)
				(type default)
			)
			(layer "F.SilkS")
		)
		(fp_line
			(start 0.508 -0.9398)
			(end -0.508 -0.9398)
			(stroke
				(width 0.1524)
				(type default)
			)
			(layer "F.SilkS")
		)
		(fp_rect
			(start -0.508 0.9398)
			(end 0.508 -0.9398)
			(stroke
				(width 0)
				(type default)
			)
			(fill no)
			(layer "F.CrtYd")
		)
		(fp_rect
			(start -0.508 0.9398)
			(end 0.508 -0.9398)
			(stroke
				(width 0)
				(type default)
			)
			(fill no)
			(layer "F.Fab")
		)
		(pad "1" smd custom
			(at 0 -0.4445)
			(size 0.1397 0.1397)
			(layers "F.Cu" "F.Mask" "F.Paste")
			(net "DUALPORTEN#12")
			(options
				(clearance outline)
				(anchor circle)
			)
			(primitives
				(gr_poly
					(pts
						(arc
							(start -0.1778 -0.2794)
							(mid -0.249642 -0.249642)
							(end -0.2794 -0.1778)
						)
						(arc
							(start -0.2794 0.1778)
							(mid -0.249642 0.249642)
							(end -0.1778 0.2794)
						)
						(arc
							(start 0.1778 0.2794)
							(mid 0.249642 0.249642)
							(end 0.2794 0.1778)
						)
						(arc
							(start 0.2794 -0.1778)
							(mid 0.249642 -0.249642)
							(end 0.1778 -0.2794)
						)
					)
					(width 0)
					(fill yes)
				)
			)
		)
		(pad "2" smd custom
			(at 0 0.4445)
			(size 0.1397 0.1397)
			(layers "F.Cu" "F.Mask" "F.Paste")
			(net "GND")
			(options
				(clearance outline)
				(anchor circle)
			)
			(primitives
				(gr_poly
					(pts
						(arc
							(start -0.1778 -0.2794)
							(mid -0.249642 -0.249642)
							(end -0.2794 -0.1778)
						)
						(arc
							(start -0.2794 0.1778)
							(mid -0.249642 0.249642)
							(end -0.1778 0.2794)
						)
						(arc
							(start 0.1778 0.2794)
							(mid 0.249642 0.249642)
							(end 0.2794 0.1778)
						)
						(arc
							(start 0.2794 -0.1778)
							(mid 0.249642 -0.249642)
							(end 0.1778 -0.2794)
						)
					)
					(width 0)
					(fill yes)
				)
			)
		)
	)
	(footprint ""
		(layer "F.Cu")
		(at 102.616 -208.28 90)
		(property "Reference" "R9081"
			(at 0 0 90)
			(layer "F.SilkS")
			(hide yes)
			(effects
				(font
					(size 1.27 1.27)
				)
			)
		)
		(property "Value" "27R2F-GP"
			(at 0.064008 -3.993896 90)
			(unlocked yes)
			(layer "F.Fab")
			(hide yes)
			(effects
				(font
					(size 1.016 1.016)
					(thickness 0.1524)
				)
			)
		)
		(property "Device Type" "R402H16"
			(at 0.064008 -5.517896 90)
			(unlocked yes)
			(layer "F.Fab")
			(hide yes)
			(effects
				(font
					(size 1.016 1.016)
					(thickness 0.1524)
				)
			)
		)
		(duplicate_pad_numbers_are_jumpers no)
		(fp_line
			(start 0.508 -0.9398)
			(end -0.508 -0.9398)
			(stroke
				(width 0.1524)
				(type default)
			)
			(layer "F.SilkS")
		)
		(fp_line
			(start -0.508 -0.9398)
			(end -0.508 0.9398)
			(stroke
				(width 0.1524)
				(type default)
			)
			(layer "F.SilkS")
		)
		(fp_rect
			(start -0.508 0.9398)
			(end 0.508 -0.9398)
			(stroke
				(width 0)
				(type default)
			)
			(fill no)
			(layer "F.CrtYd")
		)
		(fp_rect
			(start -0.508 0.9398)
			(end 0.508 -0.9398)
			(stroke
				(width 0)
				(type default)
			)
			(fill no)
			(layer "F.Fab")
		)
		(pad "1" smd custom
			(at 0 -0.4445 90)
			(size 0.1397 0.1397)
			(layers "F.Cu" "F.Mask" "F.Paste")
			(net "PE_CLK_100M_DR3_1_R_P")
			(options
				(clearance outline)
				(anchor circle)
			)
			(primitives
				(gr_poly
					(pts
						(arc
							(start -0.1778 -0.2794)
							(mid -0.249642 -0.249642)
							(end -0.2794 -0.1778)
						)
						(arc
							(start -0.2794 0.1778)
							(mid -0.249642 0.249642)
							(end -0.1778 0.2794)
						)
						(arc
							(start 0.1778 0.2794)
							(mid 0.249642 0.249642)
							(end 0.2794 0.1778)
						)
						(arc
							(start 0.2794 -0.1778)
							(mid 0.249642 -0.249642)
							(end 0.1778 -0.2794)
						)
					)
					(width 0)
					(fill yes)
				)
			)
		)
		(pad "2" smd custom
			(at 0 0.4445 90)
			(size 0.1397 0.1397)
			(layers "F.Cu" "F.Mask" "F.Paste")
			(net "PE_CLK100M_DR3_1_P")
			(options
				(clearance outline)
				(anchor circle)
			)
			(primitives
				(gr_poly
					(pts
						(arc
							(start -0.1778 -0.2794)
							(mid -0.249642 -0.249642)
							(end -0.2794 -0.1778)
						)
						(arc
							(start -0.2794 0.1778)
							(mid -0.249642 0.249642)
							(end -0.1778 0.2794)
						)
						(arc
							(start 0.1778 0.2794)
							(mid 0.249642 0.249642)
							(end 0.2794 0.1778)
						)
						(arc
							(start 0.2794 -0.1778)
							(mid 0.249642 -0.249642)
							(end 0.1778 -0.2794)
						)
					)
					(width 0)
					(fill yes)
				)
			)
		)
	)
	(footprint ""
		(layer "F.Cu")
		(at 20.850098 -232.32999 -90)
		(property "Reference" "J12"
			(at 0 0 270)
			(layer "F.SilkS")
			(hide yes)
			(effects
				(font
					(size 1.27 1.27)
				)
			)
		)
		(property "Value" "PCISLT68-14-GP-U1"
			(at -22.225 12.7508 270)
			(unlocked yes)
			(layer "F.Fab")
			(hide yes)
			(effects
				(font
					(size 1.016 1.016)
					(thickness 0.1524)
				)
			)
		)
		(property "Device Type" "SD-78827-0001"
			(at -22.225 11.2268 270)
			(unlocked yes)
			(layer "F.Fab")
			(hide yes)
			(effects
				(font
					(size 1.016 1.016)
					(thickness 0.1524)
				)
			)
		)
		(duplicate_pad_numbers_are_jumpers no)
		(fp_line
			(start -20.4724 12.0142)
			(end -20.4724 4.6736)
			(stroke
				(width 0.1524)
				(type default)
			)
			(layer "F.SilkS")
		)
		(fp_line
			(start -17.8435 12.0142)
			(end -20.4724 12.0142)
			(stroke
				(width 0.1524)
				(type default)
			)
			(layer "F.SilkS")
		)
		(fp_line
			(start 17.8435 12.0142)
			(end 17.8435 10.3124)
			(stroke
				(width 0.1524)
				(type default)
			)
			(layer "F.SilkS")
		)
		(fp_line
			(start 20.4724 12.0142)
			(end 17.8435 12.0142)
			(stroke
				(width 0.1524)
				(type default)
			)
			(layer "F.SilkS")
		)
		(fp_line
			(start -17.8435 10.3124)
			(end -17.8435 12.0142)
			(stroke
				(width 0.1524)
				(type default)
			)
			(layer "F.SilkS")
		)
		(fp_line
			(start 17.8435 10.3124)
			(end -17.8435 10.3124)
			(stroke
				(width 0.1524)
				(type default)
			)
			(layer "F.SilkS")
		)
		(fp_line
			(start -23.749 4.6736)
			(end -23.749 0.0254)
			(stroke
				(width 0.1524)
				(type default)
			)
			(layer "F.SilkS")
		)
		(fp_line
			(start -20.4724 4.6736)
			(end -23.749 4.6736)
			(stroke
				(width 0.1524)
				(type default)
			)
			(layer "F.SilkS")
		)
		(fp_line
			(start 20.4724 4.6736)
			(end 20.4724 12.0142)
			(stroke
				(width 0.1524)
				(type default)
			)
			(layer "F.SilkS")
		)
		(fp_line
			(start 23.749 4.6736)
			(end 20.4724 4.6736)
			(stroke
				(width 0.1524)
				(type default)
			)
			(layer "F.SilkS")
		)
		(fp_line
			(start -23.117556 2.896108)
			(end -23.117556 1.803908)
			(stroke
				(width 0.3048)
				(type default)
			)
			(layer "F.SilkS")
		)
		(fp_line
			(start 20.882356 2.896108)
			(end 20.882356 1.803908)
			(stroke
				(width 0.3048)
				(type default)
			)
			(layer "F.SilkS")
		)
		(fp_line
			(start -20.882356 1.803908)
			(end -20.882356 2.896108)
			(stroke
				(width 0.3048)
				(type default)
			)
			(layer "F.SilkS")
		)
		(fp_line
			(start 23.117556 1.803908)
			(end 23.117556 2.896108)
			(stroke
				(width 0.3048)
				(type default)
			)
			(layer "F.SilkS")
		)
		(fp_line
			(start -23.749 0.0254)
			(end -20.4724 0.0254)
			(stroke
				(width 0.1524)
				(type default)
			)
			(layer "F.SilkS")
		)
		(fp_line
			(start -20.4724 0.0254)
			(end -20.4724 -3.4036)
			(stroke
				(width 0.1524)
				(type default)
			)
			(layer "F.SilkS")
		)
		(fp_line
			(start 20.4724 0.0254)
			(end 23.749 0.0254)
			(stroke
				(width 0.1524)
				(type default)
			)
			(layer "F.SilkS")
		)
		(fp_line
			(start 23.749 0.0254)
			(end 23.749 4.6736)
			(stroke
				(width 0.1524)
				(type default)
			)
			(layer "F.SilkS")
		)
		(fp_line
			(start -20.4724 -3.4036)
			(end 20.4724 -3.4036)
			(stroke
				(width 0.1524)
				(type default)
			)
			(layer "F.SilkS")
		)
		(fp_line
			(start 20.4724 -3.4036)
			(end 20.4724 0.0254)
			(stroke
				(width 0.1524)
				(type default)
			)
			(layer "F.SilkS")
		)
		(fp_arc
			(start -20.882356 2.896108)
			(mid -21.999956 4.013708)
			(end -23.117556 2.896108)
			(stroke
				(width 0.3048)
				(type default)
			)
			(layer "F.SilkS")
		)
		(fp_arc
			(start 23.117556 2.896108)
			(mid 21.999956 4.013708)
			(end 20.882356 2.896108)
			(stroke
				(width 0.3048)
				(type default)
			)
			(layer "F.SilkS")
		)
		(fp_arc
			(start -23.117556 1.803908)
			(mid -21.999956 0.686308)
			(end -20.882356 1.803908)
			(stroke
				(width 0.3048)
				(type default)
			)
			(layer "F.SilkS")
		)
		(fp_arc
			(start 20.882356 1.803908)
			(mid 21.999956 0.686308)
			(end 23.117556 1.803908)
			(stroke
				(width 0.3048)
				(type default)
			)
			(layer "F.SilkS")
		)
		(fp_poly
			(pts
				(xy -20.2184 11.7602) (xy -20.2184 4.4196) (xy -23.495 4.4196) (xy -23.495 0.2794) (xy -20.2184 0.2794)
				(xy -20.2184 -3.1496) (xy 20.2184 -3.1496) (xy 20.2184 0.2794) (xy 23.495 0.2794) (xy 23.495 4.4196)
				(xy 20.2184 4.4196) (xy 20.2184 11.7602) (xy 18.0975 11.7602) (xy 18.0975 10.0584) (xy -18.0975 10.0584)
				(xy -18.0975 11.7602)
			)
			(stroke
				(width 0)
				(type default)
			)
			(fill no)
			(layer "F.CrtYd")
		)
		(fp_poly
			(pts
				(xy -21.2471 16.256) (xy -21.2471 4.9276) (xy -24.003 4.9276) (xy -24.003 -0.2286) (xy -20.7264 -0.2286)
				(xy -20.7264 -3.6576) (xy 20.7264 -3.6576) (xy 20.7264 -0.2286) (xy 24.003 -0.2286) (xy 24.003 -0.00635)
				(xy 20.2184 -0.00635) (xy 20.2184 -3.1496) (xy -20.2184 -3.1496) (xy -20.2184 0.2794) (xy -23.495 0.2794)
				(xy -23.495 4.4196) (xy -20.2184 4.4196) (xy -20.2184 11.7602) (xy -18.0975 11.7602) (xy -18.0975 10.0584)
				(xy 18.0975 10.0584) (xy 18.0975 11.7602) (xy 20.2184 11.7602) (xy 20.2184 4.4196) (xy 23.495 4.4196)
				(xy 23.495 0.2794) (xy 20.2184 0.2794) (xy 20.2184 0.00635) (xy 24.003 0.00635) (xy 24.003 4.9276)
				(xy 21.2471 4.9276) (xy 21.2471 16.256)
			)
			(stroke
				(width 0)
				(type default)
			)
			(fill no)
			(layer "F.CrtYd")
		)
		(fp_poly
			(pts
				(xy -21.2471 16.256) (xy -21.2471 4.9276) (xy -24.003 4.9276) (xy -24.003 -0.2286) (xy -20.7264 -0.2286)
				(xy -20.7264 -3.6576) (xy 20.7264 -3.6576) (xy 20.7264 -0.2286) (xy 24.003 -0.2286) (xy 24.003 4.9276)
				(xy 21.2471 4.9276) (xy 21.2471 16.256)
			)
			(stroke
				(width 0)
				(type default)
			)
			(fill no)
			(layer "F.Fab")
		)
		(pad "" np_thru_hole circle
			(at -18.999962 0 270)
			(size 0.254 0.254)
			(drill 1.8542)
			(layers "*.Cu" "*.Mask")
			(clearance 1.1557)
			(thermal_gap 1.1557)
		)
		(pad "" np_thru_hole circle
			(at 18.999962 0 270)
			(size 0.254 0.254)
			(drill 1.8542)
			(layers "*.Cu" "*.Mask")
			(clearance 1.1557)
			(thermal_gap 1.1557)
		)
		(pad "E1" smd rect
			(at -7.079996 1.240028 270)
			(size 0.508 2.0066)
			(layers "F.Cu" "F.Mask" "F.Paste")
			(net "PE_CLK100M_DR12_2_P")
		)
		(pad "E2" smd rect
			(at -6.279896 1.240028 270)
			(size 0.508 2.0066)
			(layers "F.Cu" "F.Mask" "F.Paste")
			(net "PE_CLK100M_DR12_2_N")
		)
		(pad "E3" smd rect
			(at -5.48005 1.240028 270)
			(size 0.508 2.0066)
			(layers "F.Cu" "F.Mask" "F.Paste")
			(net "P3V3")
		)
		(pad "E4" smd rect
			(at -4.67995 1.240028 270)
			(size 0.508 2.0066)
			(layers "F.Cu" "F.Mask" "F.Paste")
			(net "SSD12_PERST_N")
		)
		(pad "E5" smd rect
			(at -3.880104 1.240028 270)
			(size 0.508 2.0066)
			(layers "F.Cu" "F.Mask" "F.Paste")
			(net "SSD12_PERST_N")
		)
		(pad "E6" smd rect
			(at -3.080004 1.240028 270)
			(size 0.508 2.0066)
			(layers "F.Cu" "F.Mask" "F.Paste")
			(net "Net_1251")
		)
		(pad "E7" smd rect
			(at -15.48003 -1.949958 270)
			(size 0.508 2.0066)
			(layers "F.Cu" "F.Mask" "F.Paste")
			(net "PE_CLK100M_DR12_1_P")
		)
		(pad "E8" smd rect
			(at -14.67993 -1.949958 270)
			(size 0.508 2.0066)
			(layers "F.Cu" "F.Mask" "F.Paste")
			(net "PE_CLK100M_DR12_1_N")
		)
		(pad "E9" smd rect
			(at -13.880084 -1.949958 270)
			(size 0.508 2.0066)
			(layers "F.Cu" "F.Mask" "F.Paste")
			(net "GND")
		)
		(pad "E10" smd rect
			(at -13.079984 -1.949958 270)
			(size 0.508 2.0066)
			(layers "F.Cu" "F.Mask" "F.Paste")
			(net "PE_TX1_DR12_N")
		)
		(pad "E11" smd rect
			(at -12.279884 -1.949958 270)
			(size 0.508 2.0066)
			(layers "F.Cu" "F.Mask" "F.Paste")
			(net "PE_TX1_DR12_P")
		)
		(pad "E12" smd rect
			(at -11.480038 -1.949958 270)
			(size 0.508 2.0066)
			(layers "F.Cu" "F.Mask" "F.Paste")
			(net "GND")
		)
		(pad "E13" smd rect
			(at -10.679938 -1.949958 270)
			(size 0.508 2.0066)
			(layers "F.Cu" "F.Mask" "F.Paste")
			(net "PE_RX1_DR12_N")
		)
		(pad "E14" smd rect
			(at -9.880092 -1.949958 270)
			(size 0.508 2.0066)
			(layers "F.Cu" "F.Mask" "F.Paste")
			(net "PE_RX1_DR12_P")
		)
		(pad "E15" smd rect
			(at -9.079992 -1.949958 270)
			(size 0.508 2.0066)
			(layers "F.Cu" "F.Mask" "F.Paste")
			(net "GND")
		)
		(pad "E16" smd rect
			(at -8.279892 -1.949958 270)
			(size 0.508 2.0066)
			(layers "F.Cu" "F.Mask" "F.Paste")
			(net "Net_1258")
		)
		(pad "E17" smd rect
			(at 9.320022 -1.949958 270)
			(size 0.508 2.0066)
			(layers "F.Cu" "F.Mask" "F.Paste")
			(net "PE_TX4_DR12_N")
		)
		(pad "E18" smd rect
			(at 10.120122 -1.949958 270)
			(size 0.508 2.0066)
			(layers "F.Cu" "F.Mask" "F.Paste")
			(net "PE_TX4_DR12_P")
		)
		(pad "E19" smd rect
			(at 10.919968 -1.949958 270)
			(size 0.508 2.0066)
			(layers "F.Cu" "F.Mask" "F.Paste")
			(net "GND")
		)
		(pad "E20" smd rect
			(at 11.720068 -1.949958 270)
			(size 0.508 2.0066)
			(layers "F.Cu" "F.Mask" "F.Paste")
			(net "PE_RX4_DR12_N")
		)
		(pad "E21" smd rect
			(at 12.519914 -1.949958 270)
			(size 0.508 2.0066)
			(layers "F.Cu" "F.Mask" "F.Paste")
			(net "PE_RX4_DR12_P")
		)
		(pad "E22" smd rect
			(at 13.320014 -1.949958 270)
			(size 0.508 2.0066)
			(layers "F.Cu" "F.Mask" "F.Paste")
			(net "GND")
		)
		(pad "E23" smd rect
			(at 14.120114 -1.949958 270)
			(size 0.508 2.0066)
			(layers "F.Cu" "F.Mask" "F.Paste")
			(net "SCL_DR12_R")
		)
		(pad "E24" smd rect
			(at 14.91996 -1.949958 270)
			(size 0.508 2.0066)
			(layers "F.Cu" "F.Mask" "F.Paste")
			(net "SDA_DR12_R")
		)
		(pad "E25" smd rect
			(at 15.72006 -1.949958 270)
			(size 0.508 2.0066)
			(layers "F.Cu" "F.Mask" "F.Paste")
			(net "DUALPORTEN#12")
		)
		(pad "P1" smd rect
			(at -1.905 0.824992 270)
			(size 0.6604 2.0574)
			(layers "F.Cu" "F.Mask" "F.Paste")
			(net "Net_1254")
		)
		(pad "P2" smd rect
			(at -0.635 0.824992 270)
			(size 0.6604 2.0574)
			(layers "F.Cu" "F.Mask" "F.Paste")
			(net "Net_1253")
		)
		(pad "P3" smd rect
			(at 0.635 0.824992 270)
			(size 0.6604 2.0574)
			(layers "F.Cu" "F.Mask" "F.Paste")
			(net "Net_1252")
		)
		(pad "P4" smd rect
			(at 1.905 0.824992 270)
			(size 0.6604 2.0574)
			(layers "F.Cu" "F.Mask" "F.Paste")
			(net "SSD12_CLK0_OE_N")
		)
		(pad "P5" smd rect
			(at 3.175 0.824992 270)
			(size 0.6604 2.0574)
			(layers "F.Cu" "F.Mask" "F.Paste")
			(net "GND")
		)
		(pad "P6" smd rect
			(at 4.445 0.824992 270)
			(size 0.6604 2.0574)
			(layers "F.Cu" "F.Mask" "F.Paste")
			(net "GND")
		)
		(pad "P7" smd rect
			(at 5.715 0.824992 270)
			(size 0.6604 2.0574)
			(layers "F.Cu" "F.Mask" "F.Paste")
			(net "Net_98")
		)
		(pad "P8" smd rect
			(at 6.985 0.824992 270)
			(size 0.6604 2.0574)
			(layers "F.Cu" "F.Mask" "F.Paste")
			(net "Net_70")
		)
		(pad "P9" smd rect
			(at 8.255 0.824992 270)
			(size 0.6604 2.0574)
			(layers "F.Cu" "F.Mask" "F.Paste")
			(net "Net_84")
		)
		(pad "P10" smd rect
			(at 9.525 0.824992 270)
			(size 0.6604 2.0574)
			(layers "F.Cu" "F.Mask" "F.Paste")
			(net "SSD_PRSNT_NET12")
		)
		(pad "P11" smd rect
			(at 10.795 0.824992 270)
			(size 0.6604 2.0574)
			(layers "F.Cu" "F.Mask" "F.Paste")
			(net "SSD_ACT_DR12")
		)
		(pad "P12" smd rect
			(at 12.065 0.824992 270)
			(size 0.6604 2.0574)
			(layers "F.Cu" "F.Mask" "F.Paste")
			(net "GND")
		)
		(pad "P13" smd rect
			(at 13.335 0.824992 270)
			(size 0.6604 2.0574)
			(layers "F.Cu" "F.Mask" "F.Paste")
			(net "12V_PRECH_SSD12")
		)
		(pad "P14" smd rect
			(at 14.605 0.824992 270)
			(size 0.6604 2.0574)
			(layers "F.Cu" "F.Mask" "F.Paste")
			(net "P12V_SSD12")
		)
		(pad "P15" smd rect
			(at 15.875 0.824992 270)
			(size 0.6604 2.0574)
			(layers "F.Cu" "F.Mask" "F.Paste")
			(net "P12V_SSD12")
		)
		(pad "PTH1" thru_hole oval
			(at -21.999956 2.350008 270)
			(size 1.524 2.6162)
			(drill oval 0.8128 1.905)
			(layers "*.Cu" "*.Mask")
			(remove_unused_layers no)
			(net "Net_1263")
			(clearance 0.1524)
			(thermal_gap 0.1524)
		)
		(pad "PTH2" thru_hole oval
			(at 21.999956 2.350008 270)
			(size 1.524 2.6162)
			(drill oval 0.8128 1.905)
			(layers "*.Cu" "*.Mask")
			(remove_unused_layers no)
			(net "Net_1247")
			(clearance 0.1524)
			(thermal_gap 0.1524)
		)
		(pad "S1" smd rect
			(at -15.875 0.824992 270)
			(size 0.6604 2.0574)
			(layers "F.Cu" "F.Mask" "F.Paste")
			(net "GND")
		)
		(pad "S2" smd rect
			(at -14.605 0.824992 270)
			(size 0.6604 2.0574)
			(layers "F.Cu" "F.Mask" "F.Paste")
			(net "Net_1262")
		)
		(pad "S3" smd rect
			(at -13.335 0.824992 270)
			(size 0.6604 2.0574)
			(layers "F.Cu" "F.Mask" "F.Paste")
			(net "Net_1261")
		)
		(pad "S4" smd rect
			(at -12.065 0.824992 270)
			(size 0.6604 2.0574)
			(layers "F.Cu" "F.Mask" "F.Paste")
			(net "GND")
		)
		(pad "S5" smd rect
			(at -10.795 0.824992 270)
			(size 0.6604 2.0574)
			(layers "F.Cu" "F.Mask" "F.Paste")
			(net "Net_1260")
		)
		(pad "S6" smd rect
			(at -9.525 0.824992 270)
			(size 0.6604 2.0574)
			(layers "F.Cu" "F.Mask" "F.Paste")
			(net "Net_1259")
		)
		(pad "S7" smd rect
			(at -8.255 0.824992 270)
			(size 0.6604 2.0574)
			(layers "F.Cu" "F.Mask" "F.Paste")
			(net "GND")
		)
		(pad "S8" smd rect
			(at -7.480046 -1.949958 270)
			(size 0.508 2.0066)
			(layers "F.Cu" "F.Mask" "F.Paste")
			(net "GND")
		)
		(pad "S9" smd rect
			(at -6.679946 -1.949958 270)
			(size 0.508 2.0066)
			(layers "F.Cu" "F.Mask" "F.Paste")
			(net "Net_1257")
		)
		(pad "S10" smd rect
			(at -5.8801 -1.949958 270)
			(size 0.508 2.0066)
			(layers "F.Cu" "F.Mask" "F.Paste")
			(net "Net_1256")
		)
		(pad "S11" smd rect
			(at -5.08 -1.949958 270)
			(size 0.508 2.0066)
			(layers "F.Cu" "F.Mask" "F.Paste")
			(net "GND")
		)
		(pad "S12" smd rect
			(at -4.2799 -1.949958 270)
			(size 0.508 2.0066)
			(layers "F.Cu" "F.Mask" "F.Paste")
			(net "Net_1255")
		)
		(pad "S13" smd rect
			(at -3.480054 -1.949958 270)
			(size 0.508 2.0066)
			(layers "F.Cu" "F.Mask" "F.Paste")
			(net "Net_1250")
		)
		(pad "S14" smd rect
			(at -2.679954 -1.949958 270)
			(size 0.508 2.0066)
			(layers "F.Cu" "F.Mask" "F.Paste")
			(net "GND")
		)
		(pad "S15" smd rect
			(at -1.880108 -1.949958 270)
			(size 0.508 2.0066)
			(layers "F.Cu" "F.Mask" "F.Paste")
			(net "Net_1249")
		)
		(pad "S16" smd rect
			(at -1.080008 -1.949958 270)
			(size 0.508 2.0066)
			(layers "F.Cu" "F.Mask" "F.Paste")
			(net "GND")
		)
		(pad "S17" smd rect
			(at -0.279908 -1.949958 270)
			(size 0.508 2.0066)
			(layers "F.Cu" "F.Mask" "F.Paste")
			(net "PE_TX2_DR12_N")
		)
		(pad "S18" smd rect
			(at 0.519938 -1.949958 270)
			(size 0.508 2.0066)
			(layers "F.Cu" "F.Mask" "F.Paste")
			(net "PE_TX2_DR12_P")
		)
		(pad "S19" smd rect
			(at 1.320038 -1.949958 270)
			(size 0.508 2.0066)
			(layers "F.Cu" "F.Mask" "F.Paste")
			(net "GND")
		)
		(pad "S20" smd rect
			(at 2.119884 -1.949958 270)
			(size 0.508 2.0066)
			(layers "F.Cu" "F.Mask" "F.Paste")
			(net "PE_RX2_DR12_N")
		)
		(pad "S21" smd rect
			(at 2.919984 -1.949958 270)
			(size 0.508 2.0066)
			(layers "F.Cu" "F.Mask" "F.Paste")
			(net "PE_RX2_DR12_P")
		)
		(pad "S22" smd rect
			(at 3.720084 -1.949958 270)
			(size 0.508 2.0066)
			(layers "F.Cu" "F.Mask" "F.Paste")
			(net "GND")
		)
		(pad "S23" smd rect
			(at 4.51993 -1.949958 270)
			(size 0.508 2.0066)
			(layers "F.Cu" "F.Mask" "F.Paste")
			(net "PE_TX3_DR12_N")
		)
		(pad "S24" smd rect
			(at 5.32003 -1.949958 270)
			(size 0.508 2.0066)
			(layers "F.Cu" "F.Mask" "F.Paste")
			(net "PE_TX3_DR12_P")
		)
		(pad "S25" smd rect
			(at 6.119876 -1.949958 270)
			(size 0.508 2.0066)
			(layers "F.Cu" "F.Mask" "F.Paste")
			(net "GND")
		)
		(pad "S26" smd rect
			(at 6.919976 -1.949958 270)
			(size 0.508 2.0066)
			(layers "F.Cu" "F.Mask" "F.Paste")
			(net "PE_RX3_DR12_N")
		)
		(pad "S27" smd rect
			(at 7.720076 -1.949958 270)
			(size 0.508 2.0066)
			(layers "F.Cu" "F.Mask" "F.Paste")
			(net "PE_RX3_DR12_P")
		)
		(pad "S28" smd rect
			(at 8.519922 -1.949958 270)
			(size 0.508 2.0066)
			(layers "F.Cu" "F.Mask" "F.Paste")
			(net "GND")
		)
		(zone
			(layers "F.Cu" "B.Cu" "In1.Cu" "In2.Cu" "In3.Cu" "In4.Cu" "In5.Cu" "In6.Cu")
			(hatch none 0.5)
			(connect_pads
				(clearance 0)
			)
			(min_thickness 0.25)
			(keepout
				(tracks not_allowed)
				(vias allowed)
				(pads allowed)
				(copperpour not_allowed)
				(footprints allowed)
			)
			(placement
				(enabled no)
				(sheetname "")
			)
			(fill
				(thermal_gap 0.5)
				(thermal_bridge_width 0.5)
				(island_removal_mode 0)
			)
			(polygon
				(pts
					(arc
						(start 22.081998 -251.329952)
						(mid 19.618198 -251.329952)
						(end 22.081998 -251.329952)
					)
				)
			)
		)
		(zone
			(layers "F.Cu" "B.Cu" "In1.Cu" "In2.Cu" "In3.Cu" "In4.Cu" "In5.Cu" "In6.Cu")
			(hatch none 0.5)
			(connect_pads
				(clearance 0)
			)
			(min_thickness 0.25)
			(keepout
				(tracks not_allowed)
				(vias allowed)
				(pads allowed)
				(copperpour not_allowed)
				(footprints allowed)
			)
			(placement
				(enabled no)
				(sheetname "")
			)
			(fill
				(thermal_gap 0.5)
				(thermal_bridge_width 0.5)
				(island_removal_mode 0)
			)
			(polygon
				(pts
					(arc
						(start 22.081998 -213.330028)
						(mid 19.618198 -213.330028)
						(end 22.081998 -213.330028)
					)
				)
			)
		)
	)
	(footprint ""
		(layer "F.Cu")
		(at 80.645 -143.256 180)
		(property "Reference" "SR1152"
			(at 0 0 180)
			(layer "F.SilkS")
			(hide yes)
			(effects
				(font
					(size 1.27 1.27)
				)
			)
		)
		(property "Value" "4K7R2F-GP"
			(at 0.064008 -3.993896 180)
			(unlocked yes)
			(layer "F.Fab")
			(hide yes)
			(effects
				(font
					(size 1.016 1.016)
					(thickness 0.1524)
				)
			)
		)
		(property "Device Type" "R402H16"
			(at 0.064008 -5.517896 180)
			(unlocked yes)
			(layer "F.Fab")
			(hide yes)
			(effects
				(font
					(size 1.016 1.016)
					(thickness 0.1524)
				)
			)
		)
		(duplicate_pad_numbers_are_jumpers no)
		(fp_line
			(start 0.508 -0.9398)
			(end -0.508 -0.9398)
			(stroke
				(width 0.1524)
				(type default)
			)
			(layer "F.SilkS")
		)
		(fp_line
			(start -0.508 -0.9398)
			(end -0.508 0.9398)
			(stroke
				(width 0.1524)
				(type default)
			)
			(layer "F.SilkS")
		)
		(fp_rect
			(start -0.508 0.9398)
			(end 0.508 -0.9398)
			(stroke
				(width 0)
				(type default)
			)
			(fill no)
			(layer "F.CrtYd")
		)
		(fp_rect
			(start -0.508 0.9398)
			(end 0.508 -0.9398)
			(stroke
				(width 0)
				(type default)
			)
			(fill no)
			(layer "F.Fab")
		)
		(pad "1" smd custom
			(at 0 -0.4445 180)
			(size 0.1397 0.1397)
			(layers "F.Cu" "F.Mask" "F.Paste")
			(net "P3V3")
			(options
				(clearance outline)
				(anchor circle)
			)
			(primitives
				(gr_poly
					(pts
						(arc
							(start -0.1778 -0.2794)
							(mid -0.249642 -0.249642)
							(end -0.2794 -0.1778)
						)
						(arc
							(start -0.2794 0.1778)
							(mid -0.249642 0.249642)
							(end -0.1778 0.2794)
						)
						(arc
							(start 0.1778 0.2794)
							(mid 0.249642 0.249642)
							(end 0.2794 0.1778)
						)
						(arc
							(start 0.2794 -0.1778)
							(mid 0.249642 -0.249642)
							(end 0.1778 -0.2794)
						)
					)
					(width 0)
					(fill yes)
				)
			)
		)
		(pad "2" smd custom
			(at 0 0.4445 180)
			(size 0.1397 0.1397)
			(layers "F.Cu" "F.Mask" "F.Paste")
			(net "I2C_SW_EU16_ADDRESS_A2")
			(options
				(clearance outline)
				(anchor circle)
			)
			(primitives
				(gr_poly
					(pts
						(arc
							(start -0.1778 -0.2794)
							(mid -0.249642 -0.249642)
							(end -0.2794 -0.1778)
						)
						(arc
							(start -0.2794 0.1778)
							(mid -0.249642 0.249642)
							(end -0.1778 0.2794)
						)
						(arc
							(start 0.1778 0.2794)
							(mid 0.249642 0.249642)
							(end 0.2794 0.1778)
						)
						(arc
							(start 0.2794 -0.1778)
							(mid 0.249642 -0.249642)
							(end 0.1778 -0.2794)
						)
					)
					(width 0)
					(fill yes)
				)
			)
		)
	)
	(footprint ""
		(layer "F.Cu")
		(at 81.153 -354.076 180)
		(property "Reference" "PR9047"
			(at 0 0 180)
			(layer "F.SilkS")
			(hide yes)
			(effects
				(font
					(size 1.27 1.27)
				)
			)
		)
		(property "Value" "0R2J-2-GP"
			(at 0.064008 -3.993896 180)
			(unlocked yes)
			(layer "F.Fab")
			(hide yes)
			(effects
				(font
					(size 1.016 1.016)
					(thickness 0.1524)
				)
			)
		)
		(property "Device Type" "R402H16"
			(at 0.064008 -5.517896 180)
			(unlocked yes)
			(layer "F.Fab")
			(hide yes)
			(effects
				(font
					(size 1.016 1.016)
					(thickness 0.1524)
				)
			)
		)
		(duplicate_pad_numbers_are_jumpers no)
		(fp_line
			(start 0.508 -0.9398)
			(end -0.508 -0.9398)
			(stroke
				(width 0.1524)
				(type default)
			)
			(layer "F.SilkS")
		)
		(fp_line
			(start -0.508 -0.9398)
			(end -0.508 0.9398)
			(stroke
				(width 0.1524)
				(type default)
			)
			(layer "F.SilkS")
		)
		(fp_rect
			(start -0.508 0.9398)
			(end 0.508 -0.9398)
			(stroke
				(width 0)
				(type default)
			)
			(fill no)
			(layer "F.CrtYd")
		)
		(fp_rect
			(start -0.508 0.9398)
			(end 0.508 -0.9398)
			(stroke
				(width 0)
				(type default)
			)
			(fill no)
			(layer "F.Fab")
		)
		(pad "1" smd custom
			(at 0 -0.4445 180)
			(size 0.1397 0.1397)
			(layers "F.Cu" "F.Mask" "F.Paste")
			(net "I2C_MUX_RESET")
			(options
				(clearance outline)
				(anchor circle)
			)
			(primitives
				(gr_poly
					(pts
						(arc
							(start -0.1778 -0.2794)
							(mid -0.249642 -0.249642)
							(end -0.2794 -0.1778)
						)
						(arc
							(start -0.2794 0.1778)
							(mid -0.249642 0.249642)
							(end -0.1778 0.2794)
						)
						(arc
							(start 0.1778 0.2794)
							(mid 0.249642 0.249642)
							(end 0.2794 0.1778)
						)
						(arc
							(start 0.2794 -0.1778)
							(mid 0.249642 -0.249642)
							(end 0.1778 -0.2794)
						)
					)
					(width 0)
					(fill yes)
				)
			)
		)
		(pad "2" smd custom
			(at 0 0.4445 180)
			(size 0.1397 0.1397)
			(layers "F.Cu" "F.Mask" "F.Paste")
			(net "I2C_MUX_RESET_R_EU17")
			(options
				(clearance outline)
				(anchor circle)
			)
			(primitives
				(gr_poly
					(pts
						(arc
							(start -0.1778 -0.2794)
							(mid -0.249642 -0.249642)
							(end -0.2794 -0.1778)
						)
						(arc
							(start -0.2794 0.1778)
							(mid -0.249642 0.249642)
							(end -0.1778 0.2794)
						)
						(arc
							(start 0.1778 0.2794)
							(mid 0.249642 0.249642)
							(end 0.2794 0.1778)
						)
						(arc
							(start 0.2794 -0.1778)
							(mid 0.249642 -0.249642)
							(end 0.1778 -0.2794)
						)
					)
					(width 0)
					(fill yes)
				)
			)
		)
	)
	(footprint ""
		(layer "F.Cu")
		(at 84.455 -207.01 90)
		(property "Reference" "R423"
			(at 0 0 90)
			(layer "F.SilkS")
			(hide yes)
			(effects
				(font
					(size 1.27 1.27)
				)
			)
		)
		(property "Value" "0R2J-2-GP"
			(at 0.064008 -3.993896 90)
			(unlocked yes)
			(layer "F.Fab")
			(hide yes)
			(effects
				(font
					(size 1.016 1.016)
					(thickness 0.1524)
				)
			)
		)
		(property "Device Type" "R402H16"
			(at 0.064008 -5.517896 90)
			(unlocked yes)
			(layer "F.Fab")
			(hide yes)
			(effects
				(font
					(size 1.016 1.016)
					(thickness 0.1524)
				)
			)
		)
		(duplicate_pad_numbers_are_jumpers no)
		(fp_line
			(start 0.508 -0.9398)
			(end -0.508 -0.9398)
			(stroke
				(width 0.1524)
				(type default)
			)
			(layer "F.SilkS")
		)
		(fp_line
			(start -0.508 -0.9398)
			(end -0.508 0.9398)
			(stroke
				(width 0.1524)
				(type default)
			)
			(layer "F.SilkS")
		)
		(fp_rect
			(start -0.508 0.9398)
			(end 0.508 -0.9398)
			(stroke
				(width 0)
				(type default)
			)
			(fill no)
			(layer "F.CrtYd")
		)
		(fp_rect
			(start -0.508 0.9398)
			(end 0.508 -0.9398)
			(stroke
				(width 0)
				(type default)
			)
			(fill no)
			(layer "F.Fab")
		)
		(pad "1" smd custom
			(at 0 -0.4445 90)
			(size 0.1397 0.1397)
			(layers "F.Cu" "F.Mask" "F.Paste")
			(net "BMC_I2C_SDA_BUF_8")
			(options
				(clearance outline)
				(anchor circle)
			)
			(primitives
				(gr_poly
					(pts
						(arc
							(start -0.1778 -0.2794)
							(mid -0.249642 -0.249642)
							(end -0.2794 -0.1778)
						)
						(arc
							(start -0.2794 0.1778)
							(mid -0.249642 0.249642)
							(end -0.1778 0.2794)
						)
						(arc
							(start 0.1778 0.2794)
							(mid 0.249642 0.249642)
							(end 0.2794 0.1778)
						)
						(arc
							(start 0.2794 -0.1778)
							(mid 0.249642 -0.249642)
							(end 0.1778 -0.2794)
						)
					)
					(width 0)
					(fill yes)
				)
			)
		)
		(pad "2" smd custom
			(at 0 0.4445 90)
			(size 0.1397 0.1397)
			(layers "F.Cu" "F.Mask" "F.Paste")
			(net "I2C_SDA_BUF_8_EU3_R")
			(options
				(clearance outline)
				(anchor circle)
			)
			(primitives
				(gr_poly
					(pts
						(arc
							(start -0.1778 -0.2794)
							(mid -0.249642 -0.249642)
							(end -0.2794 -0.1778)
						)
						(arc
							(start -0.2794 0.1778)
							(mid -0.249642 0.249642)
							(end -0.1778 0.2794)
						)
						(arc
							(start 0.1778 0.2794)
							(mid 0.249642 0.249642)
							(end 0.2794 0.1778)
						)
						(arc
							(start 0.2794 -0.1778)
							(mid 0.249642 -0.249642)
							(end 0.1778 -0.2794)
						)
					)
					(width 0)
					(fill yes)
				)
			)
		)
	)
	(footprint ""
		(layer "F.Cu")
		(at 243.586 -424.18)
		(property "Reference" "R369"
			(at 0 0 0)
			(layer "F.SilkS")
			(hide yes)
			(effects
				(font
					(size 1.27 1.27)
				)
			)
		)
		(property "Value" "4K7R2J-2-GP"
			(at 0.064008 -3.993896 0)
			(unlocked yes)
			(layer "F.Fab")
			(hide yes)
			(effects
				(font
					(size 1.016 1.016)
					(thickness 0.1524)
				)
			)
		)
		(property "Device Type" "R402H16"
			(at 0.064008 -5.517896 0)
			(unlocked yes)
			(layer "F.Fab")
			(hide yes)
			(effects
				(font
					(size 1.016 1.016)
					(thickness 0.1524)
				)
			)
		)
		(duplicate_pad_numbers_are_jumpers no)
		(fp_line
			(start -0.508 -0.9398)
			(end -0.508 0.9398)
			(stroke
				(width 0.1524)
				(type default)
			)
			(layer "F.SilkS")
		)
		(fp_line
			(start 0.508 -0.9398)
			(end -0.508 -0.9398)
			(stroke
				(width 0.1524)
				(type default)
			)
			(layer "F.SilkS")
		)
		(fp_rect
			(start -0.508 0.9398)
			(end 0.508 -0.9398)
			(stroke
				(width 0)
				(type default)
			)
			(fill no)
			(layer "F.CrtYd")
		)
		(fp_rect
			(start -0.508 0.9398)
			(end 0.508 -0.9398)
			(stroke
				(width 0)
				(type default)
			)
			(fill no)
			(layer "F.Fab")
		)
		(pad "1" smd custom
			(at 0 -0.4445)
			(size 0.1397 0.1397)
			(layers "F.Cu" "F.Mask" "F.Paste")
			(net "P3V3")
			(options
				(clearance outline)
				(anchor circle)
			)
			(primitives
				(gr_poly
					(pts
						(arc
							(start -0.1778 -0.2794)
							(mid -0.249642 -0.249642)
							(end -0.2794 -0.1778)
						)
						(arc
							(start -0.2794 0.1778)
							(mid -0.249642 0.249642)
							(end -0.1778 0.2794)
						)
						(arc
							(start 0.1778 0.2794)
							(mid 0.249642 0.249642)
							(end 0.2794 0.1778)
						)
						(arc
							(start 0.2794 -0.1778)
							(mid 0.249642 -0.249642)
							(end 0.1778 -0.2794)
						)
					)
					(width 0)
					(fill yes)
				)
			)
		)
		(pad "2" smd custom
			(at 0 0.4445)
			(size 0.1397 0.1397)
			(layers "F.Cu" "F.Mask" "F.Paste")
			(net "I2C_C_SCL")
			(options
				(clearance outline)
				(anchor circle)
			)
			(primitives
				(gr_poly
					(pts
						(arc
							(start -0.1778 -0.2794)
							(mid -0.249642 -0.249642)
							(end -0.2794 -0.1778)
						)
						(arc
							(start -0.2794 0.1778)
							(mid -0.249642 0.249642)
							(end -0.1778 0.2794)
						)
						(arc
							(start 0.1778 0.2794)
							(mid 0.249642 0.249642)
							(end 0.2794 0.1778)
						)
						(arc
							(start 0.2794 -0.1778)
							(mid 0.249642 -0.249642)
							(end 0.1778 -0.2794)
						)
					)
					(width 0)
					(fill yes)
				)
			)
		)
	)
	(footprint ""
		(layer "F.Cu")
		(at 84.455 -94.742 -90)
		(property "Reference" "R9122"
			(at 0 0 270)
			(layer "F.SilkS")
			(hide yes)
			(effects
				(font
					(size 1.27 1.27)
				)
			)
		)
		(property "Value" "4K7R2F-GP"
			(at 0.064008 -3.993896 270)
			(unlocked yes)
			(layer "F.Fab")
			(hide yes)
			(effects
				(font
					(size 1.016 1.016)
					(thickness 0.1524)
				)
			)
		)
		(property "Device Type" "R402H16"
			(at 0.064008 -5.517896 270)
			(unlocked yes)
			(layer "F.Fab")
			(hide yes)
			(effects
				(font
					(size 1.016 1.016)
					(thickness 0.1524)
				)
			)
		)
		(duplicate_pad_numbers_are_jumpers no)
		(fp_line
			(start -0.508 -0.9398)
			(end -0.508 0.9398)
			(stroke
				(width 0.1524)
				(type default)
			)
			(layer "F.SilkS")
		)
		(fp_line
			(start 0.508 -0.9398)
			(end -0.508 -0.9398)
			(stroke
				(width 0.1524)
				(type default)
			)
			(layer "F.SilkS")
		)
		(fp_rect
			(start -0.508 0.9398)
			(end 0.508 -0.9398)
			(stroke
				(width 0)
				(type default)
			)
			(fill no)
			(layer "F.CrtYd")
		)
		(fp_rect
			(start -0.508 0.9398)
			(end 0.508 -0.9398)
			(stroke
				(width 0)
				(type default)
			)
			(fill no)
			(layer "F.Fab")
		)
		(pad "1" smd custom
			(at 0 -0.4445 270)
			(size 0.1397 0.1397)
			(layers "F.Cu" "F.Mask" "F.Paste")
			(net "CLK_BUF_EU4_SMB_A1_TRI")
			(options
				(clearance outline)
				(anchor circle)
			)
			(primitives
				(gr_poly
					(pts
						(arc
							(start -0.1778 -0.2794)
							(mid -0.249642 -0.249642)
							(end -0.2794 -0.1778)
						)
						(arc
							(start -0.2794 0.1778)
							(mid -0.249642 0.249642)
							(end -0.1778 0.2794)
						)
						(arc
							(start 0.1778 0.2794)
							(mid 0.249642 0.249642)
							(end 0.2794 0.1778)
						)
						(arc
							(start 0.2794 -0.1778)
							(mid 0.249642 -0.249642)
							(end 0.1778 -0.2794)
						)
					)
					(width 0)
					(fill yes)
				)
			)
		)
		(pad "2" smd custom
			(at 0 0.4445 270)
			(size 0.1397 0.1397)
			(layers "F.Cu" "F.Mask" "F.Paste")
			(net "GND")
			(options
				(clearance outline)
				(anchor circle)
			)
			(primitives
				(gr_poly
					(pts
						(arc
							(start -0.1778 -0.2794)
							(mid -0.249642 -0.249642)
							(end -0.2794 -0.1778)
						)
						(arc
							(start -0.2794 0.1778)
							(mid -0.249642 0.249642)
							(end -0.1778 0.2794)
						)
						(arc
							(start 0.1778 0.2794)
							(mid 0.249642 0.249642)
							(end 0.2794 0.1778)
						)
						(arc
							(start 0.2794 -0.1778)
							(mid 0.249642 -0.249642)
							(end 0.1778 -0.2794)
						)
					)
					(width 0)
					(fill yes)
				)
			)
		)
	)
	(footprint ""
		(layer "F.Cu")
		(at 203.454 -458.978 90)
		(property "Reference" "R319"
			(at 0 0 90)
			(layer "F.SilkS")
			(hide yes)
			(effects
				(font
					(size 1.27 1.27)
				)
			)
		)
		(property "Value" "0R2J-2-GP"
			(at 0.064008 -3.993896 90)
			(unlocked yes)
			(layer "F.Fab")
			(hide yes)
			(effects
				(font
					(size 1.016 1.016)
					(thickness 0.1524)
				)
			)
		)
		(property "Device Type" "R402H16"
			(at 0.064008 -5.517896 90)
			(unlocked yes)
			(layer "F.Fab")
			(hide yes)
			(effects
				(font
					(size 1.016 1.016)
					(thickness 0.1524)
				)
			)
		)
		(duplicate_pad_numbers_are_jumpers no)
		(fp_line
			(start 0.508 -0.9398)
			(end -0.508 -0.9398)
			(stroke
				(width 0.1524)
				(type default)
			)
			(layer "F.SilkS")
		)
		(fp_line
			(start -0.508 -0.9398)
			(end -0.508 0.9398)
			(stroke
				(width 0.1524)
				(type default)
			)
			(layer "F.SilkS")
		)
		(fp_rect
			(start -0.508 0.9398)
			(end 0.508 -0.9398)
			(stroke
				(width 0)
				(type default)
			)
			(fill no)
			(layer "F.CrtYd")
		)
		(fp_rect
			(start -0.508 0.9398)
			(end 0.508 -0.9398)
			(stroke
				(width 0)
				(type default)
			)
			(fill no)
			(layer "F.Fab")
		)
		(pad "1" smd custom
			(at 0 -0.4445 90)
			(size 0.1397 0.1397)
			(layers "F.Cu" "F.Mask" "F.Paste")
			(net "I2C_B_SCL")
			(options
				(clearance outline)
				(anchor circle)
			)
			(primitives
				(gr_poly
					(pts
						(arc
							(start -0.1778 -0.2794)
							(mid -0.249642 -0.249642)
							(end -0.2794 -0.1778)
						)
						(arc
							(start -0.2794 0.1778)
							(mid -0.249642 0.249642)
							(end -0.1778 0.2794)
						)
						(arc
							(start 0.1778 0.2794)
							(mid 0.249642 0.249642)
							(end 0.2794 0.1778)
						)
						(arc
							(start 0.2794 -0.1778)
							(mid 0.249642 -0.249642)
							(end 0.1778 -0.2794)
						)
					)
					(width 0)
					(fill yes)
				)
			)
		)
		(pad "2" smd custom
			(at 0 0.4445 90)
			(size 0.1397 0.1397)
			(layers "F.Cu" "F.Mask" "F.Paste")
			(net "TMP2_SCL")
			(options
				(clearance outline)
				(anchor circle)
			)
			(primitives
				(gr_poly
					(pts
						(arc
							(start -0.1778 -0.2794)
							(mid -0.249642 -0.249642)
							(end -0.2794 -0.1778)
						)
						(arc
							(start -0.2794 0.1778)
							(mid -0.249642 0.249642)
							(end -0.1778 0.2794)
						)
						(arc
							(start 0.1778 0.2794)
							(mid 0.249642 0.249642)
							(end 0.2794 0.1778)
						)
						(arc
							(start 0.2794 -0.1778)
							(mid 0.249642 -0.249642)
							(end 0.1778 -0.2794)
						)
					)
					(width 0)
					(fill yes)
				)
			)
		)
	)
	(footprint ""
		(layer "F.Cu")
		(at 82.931 -433.959 90)
		(property "Reference" "SR946"
			(at 0 0 90)
			(layer "F.SilkS")
			(hide yes)
			(effects
				(font
					(size 1.27 1.27)
				)
			)
		)
		(property "Value" "4K7R2F-GP"
			(at 0.064008 -3.993896 90)
			(unlocked yes)
			(layer "F.Fab")
			(hide yes)
			(effects
				(font
					(size 1.016 1.016)
					(thickness 0.1524)
				)
			)
		)
		(property "Device Type" "R402H16"
			(at 0.064008 -5.517896 90)
			(unlocked yes)
			(layer "F.Fab")
			(hide yes)
			(effects
				(font
					(size 1.016 1.016)
					(thickness 0.1524)
				)
			)
		)
		(duplicate_pad_numbers_are_jumpers no)
		(fp_line
			(start 0.508 -0.9398)
			(end -0.508 -0.9398)
			(stroke
				(width 0.1524)
				(type default)
			)
			(layer "F.SilkS")
		)
		(fp_line
			(start -0.508 -0.9398)
			(end -0.508 0.9398)
			(stroke
				(width 0.1524)
				(type default)
			)
			(layer "F.SilkS")
		)
		(fp_rect
			(start -0.508 0.9398)
			(end 0.508 -0.9398)
			(stroke
				(width 0)
				(type default)
			)
			(fill no)
			(layer "F.CrtYd")
		)
		(fp_rect
			(start -0.508 0.9398)
			(end 0.508 -0.9398)
			(stroke
				(width 0)
				(type default)
			)
			(fill no)
			(layer "F.Fab")
		)
		(pad "1" smd custom
			(at 0 -0.4445 90)
			(size 0.1397 0.1397)
			(layers "F.Cu" "F.Mask" "F.Paste")
			(net "VDD_DIFF_1")
			(options
				(clearance outline)
				(anchor circle)
			)
			(primitives
				(gr_poly
					(pts
						(arc
							(start -0.1778 -0.2794)
							(mid -0.249642 -0.249642)
							(end -0.2794 -0.1778)
						)
						(arc
							(start -0.2794 0.1778)
							(mid -0.249642 0.249642)
							(end -0.1778 0.2794)
						)
						(arc
							(start 0.1778 0.2794)
							(mid 0.249642 0.249642)
							(end 0.2794 0.1778)
						)
						(arc
							(start 0.2794 -0.1778)
							(mid 0.249642 -0.249642)
							(end 0.1778 -0.2794)
						)
					)
					(width 0)
					(fill yes)
				)
			)
		)
		(pad "2" smd custom
			(at 0 0.4445 90)
			(size 0.1397 0.1397)
			(layers "F.Cu" "F.Mask" "F.Paste")
			(net "P3V3_PG")
			(options
				(clearance outline)
				(anchor circle)
			)
			(primitives
				(gr_poly
					(pts
						(arc
							(start -0.1778 -0.2794)
							(mid -0.249642 -0.249642)
							(end -0.2794 -0.1778)
						)
						(arc
							(start -0.2794 0.1778)
							(mid -0.249642 0.249642)
							(end -0.1778 0.2794)
						)
						(arc
							(start 0.1778 0.2794)
							(mid 0.249642 0.249642)
							(end 0.2794 0.1778)
						)
						(arc
							(start 0.2794 -0.1778)
							(mid 0.249642 -0.249642)
							(end 0.1778 -0.2794)
						)
					)
					(width 0)
					(fill yes)
				)
			)
		)
	)
	(footprint ""
		(layer "F.Cu")
		(at 20.3835 -163.887658 -90)
		(property "Reference" "SR1148"
			(at 0 0 270)
			(layer "F.SilkS")
			(hide yes)
			(effects
				(font
					(size 1.27 1.27)
				)
			)
		)
		(property "Value" "4K7R2J-2-GP"
			(at 0.064008 -3.993896 270)
			(unlocked yes)
			(layer "F.Fab")
			(hide yes)
			(effects
				(font
					(size 1.016 1.016)
					(thickness 0.1524)
				)
			)
		)
		(property "Device Type" "R402H16"
			(at 0.064008 -5.517896 270)
			(unlocked yes)
			(layer "F.Fab")
			(hide yes)
			(effects
				(font
					(size 1.016 1.016)
					(thickness 0.1524)
				)
			)
		)
		(duplicate_pad_numbers_are_jumpers no)
		(fp_line
			(start -0.508 -0.9398)
			(end -0.508 0.9398)
			(stroke
				(width 0.1524)
				(type default)
			)
			(layer "F.SilkS")
		)
		(fp_line
			(start 0.508 -0.9398)
			(end -0.508 -0.9398)
			(stroke
				(width 0.1524)
				(type default)
			)
			(layer "F.SilkS")
		)
		(fp_rect
			(start -0.508 0.9398)
			(end 0.508 -0.9398)
			(stroke
				(width 0)
				(type default)
			)
			(fill no)
			(layer "F.CrtYd")
		)
		(fp_rect
			(start -0.508 0.9398)
			(end 0.508 -0.9398)
			(stroke
				(width 0)
				(type default)
			)
			(fill no)
			(layer "F.Fab")
		)
		(pad "1" smd custom
			(at 0 -0.4445 270)
			(size 0.1397 0.1397)
			(layers "F.Cu" "F.Mask" "F.Paste")
			(net "P3V3")
			(options
				(clearance outline)
				(anchor circle)
			)
			(primitives
				(gr_poly
					(pts
						(arc
							(start -0.1778 -0.2794)
							(mid -0.249642 -0.249642)
							(end -0.2794 -0.1778)
						)
						(arc
							(start -0.2794 0.1778)
							(mid -0.249642 0.249642)
							(end -0.1778 0.2794)
						)
						(arc
							(start 0.1778 0.2794)
							(mid 0.249642 0.249642)
							(end 0.2794 0.1778)
						)
						(arc
							(start 0.2794 -0.1778)
							(mid 0.249642 -0.249642)
							(end 0.1778 -0.2794)
						)
					)
					(width 0)
					(fill yes)
				)
			)
		)
		(pad "2" smd custom
			(at 0 0.4445 270)
			(size 0.1397 0.1397)
			(layers "F.Cu" "F.Mask" "F.Paste")
			(net "SSD_ACT_DR13")
			(options
				(clearance outline)
				(anchor circle)
			)
			(primitives
				(gr_poly
					(pts
						(arc
							(start -0.1778 -0.2794)
							(mid -0.249642 -0.249642)
							(end -0.2794 -0.1778)
						)
						(arc
							(start -0.2794 0.1778)
							(mid -0.249642 0.249642)
							(end -0.1778 0.2794)
						)
						(arc
							(start 0.1778 0.2794)
							(mid 0.249642 0.249642)
							(end 0.2794 0.1778)
						)
						(arc
							(start 0.2794 -0.1778)
							(mid 0.249642 -0.249642)
							(end 0.1778 -0.2794)
						)
					)
					(width 0)
					(fill yes)
				)
			)
		)
	)
	(footprint ""
		(layer "F.Cu")
		(at 108.966 -310.261)
		(property "Reference" "R9492"
			(at 0 0 0)
			(layer "F.SilkS")
			(hide yes)
			(effects
				(font
					(size 1.27 1.27)
				)
			)
		)
		(property "Value" "4K7R2J-2-GP"
			(at 0.064008 -3.993896 0)
			(unlocked yes)
			(layer "F.Fab")
			(hide yes)
			(effects
				(font
					(size 1.016 1.016)
					(thickness 0.1524)
				)
			)
		)
		(property "Device Type" "R402H16"
			(at 0.064008 -5.517896 0)
			(unlocked yes)
			(layer "F.Fab")
			(hide yes)
			(effects
				(font
					(size 1.016 1.016)
					(thickness 0.1524)
				)
			)
		)
		(duplicate_pad_numbers_are_jumpers no)
		(fp_line
			(start -0.508 -0.9398)
			(end -0.508 0.9398)
			(stroke
				(width 0.1524)
				(type default)
			)
			(layer "F.SilkS")
		)
		(fp_line
			(start 0.508 -0.9398)
			(end -0.508 -0.9398)
			(stroke
				(width 0.1524)
				(type default)
			)
			(layer "F.SilkS")
		)
		(fp_rect
			(start -0.508 0.9398)
			(end 0.508 -0.9398)
			(stroke
				(width 0)
				(type default)
			)
			(fill no)
			(layer "F.CrtYd")
		)
		(fp_rect
			(start -0.508 0.9398)
			(end 0.508 -0.9398)
			(stroke
				(width 0)
				(type default)
			)
			(fill no)
			(layer "F.Fab")
		)
		(pad "1" smd custom
			(at 0 -0.4445)
			(size 0.1397 0.1397)
			(layers "F.Cu" "F.Mask" "F.Paste")
			(net "P3V3")
			(options
				(clearance outline)
				(anchor circle)
			)
			(primitives
				(gr_poly
					(pts
						(arc
							(start -0.1778 -0.2794)
							(mid -0.249642 -0.249642)
							(end -0.2794 -0.1778)
						)
						(arc
							(start -0.2794 0.1778)
							(mid -0.249642 0.249642)
							(end -0.1778 0.2794)
						)
						(arc
							(start 0.1778 0.2794)
							(mid 0.249642 0.249642)
							(end 0.2794 0.1778)
						)
						(arc
							(start 0.2794 -0.1778)
							(mid 0.249642 -0.249642)
							(end 0.1778 -0.2794)
						)
					)
					(width 0)
					(fill yes)
				)
			)
		)
		(pad "2" smd custom
			(at 0 0.4445)
			(size 0.1397 0.1397)
			(layers "F.Cu" "F.Mask" "F.Paste")
			(net "SSD1_CLK0_OE_N")
			(options
				(clearance outline)
				(anchor circle)
			)
			(primitives
				(gr_poly
					(pts
						(arc
							(start -0.1778 -0.2794)
							(mid -0.249642 -0.249642)
							(end -0.2794 -0.1778)
						)
						(arc
							(start -0.2794 0.1778)
							(mid -0.249642 0.249642)
							(end -0.1778 0.2794)
						)
						(arc
							(start 0.1778 0.2794)
							(mid 0.249642 0.249642)
							(end 0.2794 0.1778)
						)
						(arc
							(start 0.2794 -0.1778)
							(mid 0.249642 -0.249642)
							(end 0.1778 -0.2794)
						)
					)
					(width 0)
					(fill yes)
				)
			)
		)
	)
	(footprint ""
		(layer "F.Cu")
		(at 210.312 -293.116)
		(property "Reference" "C384"
			(at 0 0 0)
			(layer "F.SilkS")
			(hide yes)
			(effects
				(font
					(size 1.27 1.27)
				)
			)
		)
		(property "Value" "SCD1U25V2KX-2-GP"
			(at 1.1811 -2.7051 0)
			(unlocked yes)
			(layer "F.Fab")
			(hide yes)
			(effects
				(font
					(size 1.016 1.016)
					(thickness 0.1524)
				)
			)
		)
		(property "Device Type" "C402H22"
			(at 1.1811 -4.2291 0)
			(unlocked yes)
			(layer "F.Fab")
			(hide yes)
			(effects
				(font
					(size 1.016 1.016)
					(thickness 0.1524)
				)
			)
		)
		(duplicate_pad_numbers_are_jumpers no)
		(fp_rect
			(start -0.4318 0.9525)
			(end 0.4318 -0.9525)
			(stroke
				(width 0)
				(type default)
			)
			(fill no)
			(layer "F.CrtYd")
		)
		(fp_rect
			(start -0.4318 0.9525)
			(end 0.4318 -0.9525)
			(stroke
				(width 0)
				(type default)
			)
			(fill no)
			(layer "F.Fab")
		)
		(pad "1" smd custom
			(at 0 -0.4445)
			(size 0.1524 0.1524)
			(layers "F.Cu" "F.Mask" "F.Paste")
			(net "P12V")
			(options
				(clearance outline)
				(anchor circle)
			)
			(primitives
				(gr_poly
					(pts
						(arc
							(start 0.3048 -0.2032)
							(mid 0.275042 -0.275042)
							(end 0.2032 -0.3048)
						)
						(arc
							(start -0.2032 -0.3048)
							(mid -0.275042 -0.275042)
							(end -0.3048 -0.2032)
						)
						(arc
							(start -0.3048 0.2032)
							(mid -0.275042 0.275042)
							(end -0.2032 0.3048)
						)
						(arc
							(start 0.2032 0.3048)
							(mid 0.275042 0.275042)
							(end 0.3048 0.2032)
						)
					)
					(width 0)
					(fill yes)
				)
			)
		)
		(pad "2" smd custom
			(at 0 0.4445)
			(size 0.1524 0.1524)
			(layers "F.Cu" "F.Mask" "F.Paste")
			(net "SW_SSD2_N")
			(options
				(clearance outline)
				(anchor circle)
			)
			(primitives
				(gr_poly
					(pts
						(arc
							(start 0.3048 -0.2032)
							(mid 0.275042 -0.275042)
							(end 0.2032 -0.3048)
						)
						(arc
							(start -0.2032 -0.3048)
							(mid -0.275042 -0.275042)
							(end -0.3048 -0.2032)
						)
						(arc
							(start -0.3048 0.2032)
							(mid -0.275042 0.275042)
							(end -0.2032 0.3048)
						)
						(arc
							(start 0.2032 0.3048)
							(mid 0.275042 0.275042)
							(end 0.3048 0.2032)
						)
					)
					(width 0)
					(fill yes)
				)
			)
		)
	)
	(footprint ""
		(layer "F.Cu")
		(at 78.5622 -303.7205 180)
		(property "Reference" "R9962"
			(at 0 0 180)
			(layer "F.SilkS")
			(hide yes)
			(effects
				(font
					(size 1.27 1.27)
				)
			)
		)
		(property "Value" "470R2F-GP"
			(at 0.064008 -3.993896 180)
			(unlocked yes)
			(layer "F.Fab")
			(hide yes)
			(effects
				(font
					(size 1.016 1.016)
					(thickness 0.1524)
				)
			)
		)
		(property "Device Type" "R402H16"
			(at 0.064008 -5.517896 180)
			(unlocked yes)
			(layer "F.Fab")
			(hide yes)
			(effects
				(font
					(size 1.016 1.016)
					(thickness 0.1524)
				)
			)
		)
		(duplicate_pad_numbers_are_jumpers no)
		(fp_line
			(start 0.508 -0.9398)
			(end -0.508 -0.9398)
			(stroke
				(width 0.1524)
				(type default)
			)
			(layer "F.SilkS")
		)
		(fp_line
			(start -0.508 -0.9398)
			(end -0.508 0.9398)
			(stroke
				(width 0.1524)
				(type default)
			)
			(layer "F.SilkS")
		)
		(fp_rect
			(start -0.508 0.9398)
			(end 0.508 -0.9398)
			(stroke
				(width 0)
				(type default)
			)
			(fill no)
			(layer "F.CrtYd")
		)
		(fp_rect
			(start -0.508 0.9398)
			(end 0.508 -0.9398)
			(stroke
				(width 0)
				(type default)
			)
			(fill no)
			(layer "F.Fab")
		)
		(pad "1" smd custom
			(at 0 -0.4445 180)
			(size 0.1397 0.1397)
			(layers "F.Cu" "F.Mask" "F.Paste")
			(net "VDD_DIFF_2")
			(options
				(clearance outline)
				(anchor circle)
			)
			(primitives
				(gr_poly
					(pts
						(arc
							(start -0.1778 -0.2794)
							(mid -0.249642 -0.249642)
							(end -0.2794 -0.1778)
						)
						(arc
							(start -0.2794 0.1778)
							(mid -0.249642 0.249642)
							(end -0.1778 0.2794)
						)
						(arc
							(start 0.1778 0.2794)
							(mid 0.249642 0.249642)
							(end 0.2794 0.1778)
						)
						(arc
							(start 0.2794 -0.1778)
							(mid 0.249642 -0.249642)
							(end 0.1778 -0.2794)
						)
					)
					(width 0)
					(fill yes)
				)
			)
		)
		(pad "2" smd custom
			(at 0 0.4445 180)
			(size 0.1397 0.1397)
			(layers "F.Cu" "F.Mask" "F.Paste")
			(net "PE_100M_CLK3_N")
			(options
				(clearance outline)
				(anchor circle)
			)
			(primitives
				(gr_poly
					(pts
						(arc
							(start -0.1778 -0.2794)
							(mid -0.249642 -0.249642)
							(end -0.2794 -0.1778)
						)
						(arc
							(start -0.2794 0.1778)
							(mid -0.249642 0.249642)
							(end -0.1778 0.2794)
						)
						(arc
							(start 0.1778 0.2794)
							(mid 0.249642 0.249642)
							(end 0.2794 0.1778)
						)
						(arc
							(start 0.2794 -0.1778)
							(mid 0.249642 -0.249642)
							(end 0.1778 -0.2794)
						)
					)
					(width 0)
					(fill yes)
				)
			)
		)
	)
	(footprint ""
		(layer "F.Cu")
		(at 234.061 -445.008 90)
		(property "Reference" "R9781"
			(at 0 0 90)
			(layer "F.SilkS")
			(hide yes)
			(effects
				(font
					(size 1.27 1.27)
				)
			)
		)
		(property "Value" "0R2J-2-GP"
			(at 0.064008 -3.993896 90)
			(unlocked yes)
			(layer "F.Fab")
			(hide yes)
			(effects
				(font
					(size 1.016 1.016)
					(thickness 0.1524)
				)
			)
		)
		(property "Device Type" "R402H16"
			(at 0.064008 -5.517896 90)
			(unlocked yes)
			(layer "F.Fab")
			(hide yes)
			(effects
				(font
					(size 1.016 1.016)
					(thickness 0.1524)
				)
			)
		)
		(duplicate_pad_numbers_are_jumpers no)
		(fp_line
			(start 0.508 -0.9398)
			(end -0.508 -0.9398)
			(stroke
				(width 0.1524)
				(type default)
			)
			(layer "F.SilkS")
		)
		(fp_line
			(start -0.508 -0.9398)
			(end -0.508 0.9398)
			(stroke
				(width 0.1524)
				(type default)
			)
			(layer "F.SilkS")
		)
		(fp_rect
			(start -0.508 0.9398)
			(end 0.508 -0.9398)
			(stroke
				(width 0)
				(type default)
			)
			(fill no)
			(layer "F.CrtYd")
		)
		(fp_rect
			(start -0.508 0.9398)
			(end 0.508 -0.9398)
			(stroke
				(width 0)
				(type default)
			)
			(fill no)
			(layer "F.Fab")
		)
		(pad "1" smd custom
			(at 0 -0.4445 90)
			(size 0.1397 0.1397)
			(layers "F.Cu" "F.Mask" "F.Paste")
			(net "ATTN_LED_DR0_AND")
			(options
				(clearance outline)
				(anchor circle)
			)
			(primitives
				(gr_poly
					(pts
						(arc
							(start -0.1778 -0.2794)
							(mid -0.249642 -0.249642)
							(end -0.2794 -0.1778)
						)
						(arc
							(start -0.2794 0.1778)
							(mid -0.249642 0.249642)
							(end -0.1778 0.2794)
						)
						(arc
							(start 0.1778 0.2794)
							(mid 0.249642 0.249642)
							(end 0.2794 0.1778)
						)
						(arc
							(start 0.2794 -0.1778)
							(mid 0.249642 -0.249642)
							(end 0.1778 -0.2794)
						)
					)
					(width 0)
					(fill yes)
				)
			)
		)
		(pad "2" smd custom
			(at 0 0.4445 90)
			(size 0.1397 0.1397)
			(layers "F.Cu" "F.Mask" "F.Paste")
			(net "ATTN_LED_DR0_AND_R")
			(options
				(clearance outline)
				(anchor circle)
			)
			(primitives
				(gr_poly
					(pts
						(arc
							(start -0.1778 -0.2794)
							(mid -0.249642 -0.249642)
							(end -0.2794 -0.1778)
						)
						(arc
							(start -0.2794 0.1778)
							(mid -0.249642 0.249642)
							(end -0.1778 0.2794)
						)
						(arc
							(start 0.1778 0.2794)
							(mid 0.249642 0.249642)
							(end 0.2794 0.1778)
						)
						(arc
							(start 0.2794 -0.1778)
							(mid 0.249642 -0.249642)
							(end 0.1778 -0.2794)
						)
					)
					(width 0)
					(fill yes)
				)
			)
		)
	)
	(footprint ""
		(layer "F.Cu")
		(at 38.8366 -212.8774 180)
		(property "Reference" "R563"
			(at 0 0 180)
			(layer "F.SilkS")
			(hide yes)
			(effects
				(font
					(size 1.27 1.27)
				)
			)
		)
		(property "Value" "200KR2F-L-GP"
			(at 0.064008 -3.993896 180)
			(unlocked yes)
			(layer "F.Fab")
			(hide yes)
			(effects
				(font
					(size 1.016 1.016)
					(thickness 0.1524)
				)
			)
		)
		(property "Device Type" "R402H16"
			(at 0.064008 -5.517896 180)
			(unlocked yes)
			(layer "F.Fab")
			(hide yes)
			(effects
				(font
					(size 1.016 1.016)
					(thickness 0.1524)
				)
			)
		)
		(duplicate_pad_numbers_are_jumpers no)
		(fp_line
			(start 0.508 -0.9398)
			(end -0.508 -0.9398)
			(stroke
				(width 0.1524)
				(type default)
			)
			(layer "F.SilkS")
		)
		(fp_line
			(start -0.508 -0.9398)
			(end -0.508 0.9398)
			(stroke
				(width 0.1524)
				(type default)
			)
			(layer "F.SilkS")
		)
		(fp_rect
			(start -0.508 0.9398)
			(end 0.508 -0.9398)
			(stroke
				(width 0)
				(type default)
			)
			(fill no)
			(layer "F.CrtYd")
		)
		(fp_rect
			(start -0.508 0.9398)
			(end 0.508 -0.9398)
			(stroke
				(width 0)
				(type default)
			)
			(fill no)
			(layer "F.Fab")
		)
		(pad "1" smd custom
			(at 0 -0.4445 180)
			(size 0.1397 0.1397)
			(layers "F.Cu" "F.Mask" "F.Paste")
			(net "SW_SSD12_R")
			(options
				(clearance outline)
				(anchor circle)
			)
			(primitives
				(gr_poly
					(pts
						(arc
							(start -0.1778 -0.2794)
							(mid -0.249642 -0.249642)
							(end -0.2794 -0.1778)
						)
						(arc
							(start -0.2794 0.1778)
							(mid -0.249642 0.249642)
							(end -0.1778 0.2794)
						)
						(arc
							(start 0.1778 0.2794)
							(mid 0.249642 0.249642)
							(end 0.2794 0.1778)
						)
						(arc
							(start 0.2794 -0.1778)
							(mid 0.249642 -0.249642)
							(end 0.1778 -0.2794)
						)
					)
					(width 0)
					(fill yes)
				)
			)
		)
		(pad "2" smd custom
			(at 0 0.4445 180)
			(size 0.1397 0.1397)
			(layers "F.Cu" "F.Mask" "F.Paste")
			(net "SW_SSD12_N")
			(options
				(clearance outline)
				(anchor circle)
			)
			(primitives
				(gr_poly
					(pts
						(arc
							(start -0.1778 -0.2794)
							(mid -0.249642 -0.249642)
							(end -0.2794 -0.1778)
						)
						(arc
							(start -0.2794 0.1778)
							(mid -0.249642 0.249642)
							(end -0.1778 0.2794)
						)
						(arc
							(start 0.1778 0.2794)
							(mid 0.249642 0.249642)
							(end 0.2794 0.1778)
						)
						(arc
							(start 0.2794 -0.1778)
							(mid 0.249642 -0.249642)
							(end 0.1778 -0.2794)
						)
					)
					(width 0)
					(fill yes)
				)
			)
		)
	)
	(footprint ""
		(layer "F.Cu")
		(at 77.216 -154.178)
		(property "Reference" "SR974"
			(at 0 0 0)
			(layer "F.SilkS")
			(hide yes)
			(effects
				(font
					(size 1.27 1.27)
				)
			)
		)
		(property "Value" "2KR2F-3-GP"
			(at 0.064008 -3.993896 0)
			(unlocked yes)
			(layer "F.Fab")
			(hide yes)
			(effects
				(font
					(size 1.016 1.016)
					(thickness 0.1524)
				)
			)
		)
		(property "Device Type" "R402H16"
			(at 0.064008 -5.517896 0)
			(unlocked yes)
			(layer "F.Fab")
			(hide yes)
			(effects
				(font
					(size 1.016 1.016)
					(thickness 0.1524)
				)
			)
		)
		(duplicate_pad_numbers_are_jumpers no)
		(fp_line
			(start -0.508 -0.9398)
			(end -0.508 0.9398)
			(stroke
				(width 0.1524)
				(type default)
			)
			(layer "F.SilkS")
		)
		(fp_line
			(start 0.508 -0.9398)
			(end -0.508 -0.9398)
			(stroke
				(width 0.1524)
				(type default)
			)
			(layer "F.SilkS")
		)
		(fp_rect
			(start -0.508 0.9398)
			(end 0.508 -0.9398)
			(stroke
				(width 0)
				(type default)
			)
			(fill no)
			(layer "F.CrtYd")
		)
		(fp_rect
			(start -0.508 0.9398)
			(end 0.508 -0.9398)
			(stroke
				(width 0)
				(type default)
			)
			(fill no)
			(layer "F.Fab")
		)
		(pad "1" smd custom
			(at 0 -0.4445)
			(size 0.1397 0.1397)
			(layers "F.Cu" "F.Mask" "F.Paste")
			(net "P3V3")
			(options
				(clearance outline)
				(anchor circle)
			)
			(primitives
				(gr_poly
					(pts
						(arc
							(start -0.1778 -0.2794)
							(mid -0.249642 -0.249642)
							(end -0.2794 -0.1778)
						)
						(arc
							(start -0.2794 0.1778)
							(mid -0.249642 0.249642)
							(end -0.1778 0.2794)
						)
						(arc
							(start 0.1778 0.2794)
							(mid 0.249642 0.249642)
							(end 0.2794 0.1778)
						)
						(arc
							(start 0.2794 -0.1778)
							(mid 0.249642 -0.249642)
							(end 0.1778 -0.2794)
						)
					)
					(width 0)
					(fill yes)
				)
			)
		)
		(pad "2" smd custom
			(at 0 0.4445)
			(size 0.1397 0.1397)
			(layers "F.Cu" "F.Mask" "F.Paste")
			(net "SDA_DR4")
			(options
				(clearance outline)
				(anchor circle)
			)
			(primitives
				(gr_poly
					(pts
						(arc
							(start -0.1778 -0.2794)
							(mid -0.249642 -0.249642)
							(end -0.2794 -0.1778)
						)
						(arc
							(start -0.2794 0.1778)
							(mid -0.249642 0.249642)
							(end -0.1778 0.2794)
						)
						(arc
							(start 0.1778 0.2794)
							(mid 0.249642 0.249642)
							(end 0.2794 0.1778)
						)
						(arc
							(start 0.2794 -0.1778)
							(mid 0.249642 -0.249642)
							(end 0.1778 -0.2794)
						)
					)
					(width 0)
					(fill yes)
				)
			)
		)
	)
	(footprint ""
		(layer "F.Cu")
		(at 247.1928 -360.6038)
		(property "Reference" "C348"
			(at 0 0 0)
			(layer "F.SilkS")
			(hide yes)
			(effects
				(font
					(size 1.27 1.27)
				)
			)
		)
		(property "Value" "SC22U25V6KX-GP-U"
			(at -2.860802 -5.279644 0)
			(unlocked yes)
			(layer "F.Fab")
			(hide yes)
			(effects
				(font
					(size 1.016 1.016)
					(thickness 0.1524)
				)
			)
		)
		(property "Device Type" "C1206-TO0D3H75"
			(at -2.860802 -6.803644 0)
			(unlocked yes)
			(layer "F.Fab")
			(hide yes)
			(effects
				(font
					(size 1.016 1.016)
					(thickness 0.1524)
				)
			)
		)
		(duplicate_pad_numbers_are_jumpers no)
		(fp_line
			(start -1.3081 -2.3749)
			(end 1.3081 -2.3749)
			(stroke
				(width 0.1524)
				(type default)
			)
			(layer "F.SilkS")
		)
		(fp_line
			(start -1.3081 2.3749)
			(end -1.3081 -2.3749)
			(stroke
				(width 0.1524)
				(type default)
			)
			(layer "F.SilkS")
		)
		(fp_line
			(start 1.3081 -2.3749)
			(end 1.3081 2.3749)
			(stroke
				(width 0.1524)
				(type default)
			)
			(layer "F.SilkS")
		)
		(fp_line
			(start 1.3081 2.3749)
			(end -1.3081 2.3749)
			(stroke
				(width 0.1524)
				(type default)
			)
			(layer "F.SilkS")
		)
		(fp_rect
			(start -0.8001 1.6002)
			(end 0.8001 -1.6002)
			(stroke
				(width 0)
				(type default)
			)
			(fill no)
			(layer "F.CrtYd")
		)
		(fp_poly
			(pts
				(xy -1.5621 2.4511) (xy -1.5621 1.6002) (xy 0.8001 1.6002) (xy 0.8001 -1.6002) (xy -0.8001 -1.6002)
				(xy -0.8001 1.5875) (xy -1.5621 1.5875) (xy -1.5621 -2.4511) (xy 1.5621 -2.4511) (xy 1.5621 2.4511)
			)
			(stroke
				(width 0)
				(type default)
			)
			(fill no)
			(layer "F.CrtYd")
		)
		(fp_rect
			(start -1.5621 2.4511)
			(end 1.5621 -2.4511)
			(stroke
				(width 0)
				(type default)
			)
			(fill no)
			(layer "F.Fab")
		)
		(pad "1" smd rect
			(at 0 -1.392936)
			(size 2.1082 1.4478)
			(layers "F.Cu" "F.Mask" "F.Paste")
			(net "P12V")
		)
		(pad "2" smd rect
			(at 0 1.392936)
			(size 2.1082 1.4478)
			(layers "F.Cu" "F.Mask" "F.Paste")
			(net "GND")
		)
	)
	(footprint ""
		(layer "F.Cu")
		(at 83.185 -153.67 -90)
		(property "Reference" "PR9048"
			(at 0 0 270)
			(layer "F.SilkS")
			(hide yes)
			(effects
				(font
					(size 1.27 1.27)
				)
			)
		)
		(property "Value" "0R2J-2-GP"
			(at 0.064008 -3.993896 270)
			(unlocked yes)
			(layer "F.Fab")
			(hide yes)
			(effects
				(font
					(size 1.016 1.016)
					(thickness 0.1524)
				)
			)
		)
		(property "Device Type" "R402H16"
			(at 0.064008 -5.517896 270)
			(unlocked yes)
			(layer "F.Fab")
			(hide yes)
			(effects
				(font
					(size 1.016 1.016)
					(thickness 0.1524)
				)
			)
		)
		(duplicate_pad_numbers_are_jumpers no)
		(fp_line
			(start -0.508 -0.9398)
			(end -0.508 0.9398)
			(stroke
				(width 0.1524)
				(type default)
			)
			(layer "F.SilkS")
		)
		(fp_line
			(start 0.508 -0.9398)
			(end -0.508 -0.9398)
			(stroke
				(width 0.1524)
				(type default)
			)
			(layer "F.SilkS")
		)
		(fp_rect
			(start -0.508 0.9398)
			(end 0.508 -0.9398)
			(stroke
				(width 0)
				(type default)
			)
			(fill no)
			(layer "F.CrtYd")
		)
		(fp_rect
			(start -0.508 0.9398)
			(end 0.508 -0.9398)
			(stroke
				(width 0)
				(type default)
			)
			(fill no)
			(layer "F.Fab")
		)
		(pad "1" smd custom
			(at 0 -0.4445 270)
			(size 0.1397 0.1397)
			(layers "F.Cu" "F.Mask" "F.Paste")
			(net "I2C_MUX_RESET")
			(options
				(clearance outline)
				(anchor circle)
			)
			(primitives
				(gr_poly
					(pts
						(arc
							(start -0.1778 -0.2794)
							(mid -0.249642 -0.249642)
							(end -0.2794 -0.1778)
						)
						(arc
							(start -0.2794 0.1778)
							(mid -0.249642 0.249642)
							(end -0.1778 0.2794)
						)
						(arc
							(start 0.1778 0.2794)
							(mid 0.249642 0.249642)
							(end 0.2794 0.1778)
						)
						(arc
							(start 0.2794 -0.1778)
							(mid 0.249642 -0.249642)
							(end 0.1778 -0.2794)
						)
					)
					(width 0)
					(fill yes)
				)
			)
		)
		(pad "2" smd custom
			(at 0 0.4445 270)
			(size 0.1397 0.1397)
			(layers "F.Cu" "F.Mask" "F.Paste")
			(net "I2C_MUX_RESET_R_EU16")
			(options
				(clearance outline)
				(anchor circle)
			)
			(primitives
				(gr_poly
					(pts
						(arc
							(start -0.1778 -0.2794)
							(mid -0.249642 -0.249642)
							(end -0.2794 -0.1778)
						)
						(arc
							(start -0.2794 0.1778)
							(mid -0.249642 0.249642)
							(end -0.1778 0.2794)
						)
						(arc
							(start 0.1778 0.2794)
							(mid 0.249642 0.249642)
							(end 0.2794 0.1778)
						)
						(arc
							(start 0.2794 -0.1778)
							(mid 0.249642 -0.249642)
							(end 0.1778 -0.2794)
						)
					)
					(width 0)
					(fill yes)
				)
			)
		)
	)
	(footprint ""
		(layer "F.Cu")
		(at 95.377 -198.755 90)
		(property "Reference" "C9341"
			(at 0 0 90)
			(layer "F.SilkS")
			(hide yes)
			(effects
				(font
					(size 1.27 1.27)
				)
			)
		)
		(property "Value" "SC1KP50V2KX-1GP"
			(at 1.1811 -2.7051 90)
			(unlocked yes)
			(layer "F.Fab")
			(hide yes)
			(effects
				(font
					(size 1.016 1.016)
					(thickness 0.1524)
				)
			)
		)
		(property "Device Type" "C402H22"
			(at 1.1811 -4.2291 90)
			(unlocked yes)
			(layer "F.Fab")
			(hide yes)
			(effects
				(font
					(size 1.016 1.016)
					(thickness 0.1524)
				)
			)
		)
		(duplicate_pad_numbers_are_jumpers no)
		(fp_rect
			(start -0.4318 0.9525)
			(end 0.4318 -0.9525)
			(stroke
				(width 0)
				(type default)
			)
			(fill no)
			(layer "F.CrtYd")
		)
		(fp_rect
			(start -0.4318 0.9525)
			(end 0.4318 -0.9525)
			(stroke
				(width 0)
				(type default)
			)
			(fill no)
			(layer "F.Fab")
		)
		(pad "1" smd custom
			(at 0 -0.4445 90)
			(size 0.1524 0.1524)
			(layers "F.Cu" "F.Mask" "F.Paste")
			(net "SSD_PRSNT4")
			(options
				(clearance outline)
				(anchor circle)
			)
			(primitives
				(gr_poly
					(pts
						(arc
							(start 0.3048 -0.2032)
							(mid 0.275042 -0.275042)
							(end 0.2032 -0.3048)
						)
						(arc
							(start -0.2032 -0.3048)
							(mid -0.275042 -0.275042)
							(end -0.3048 -0.2032)
						)
						(arc
							(start -0.3048 0.2032)
							(mid -0.275042 0.275042)
							(end -0.2032 0.3048)
						)
						(arc
							(start 0.2032 0.3048)
							(mid 0.275042 0.275042)
							(end 0.3048 0.2032)
						)
					)
					(width 0)
					(fill yes)
				)
			)
		)
		(pad "2" smd custom
			(at 0 0.4445 90)
			(size 0.1524 0.1524)
			(layers "F.Cu" "F.Mask" "F.Paste")
			(net "GND")
			(options
				(clearance outline)
				(anchor circle)
			)
			(primitives
				(gr_poly
					(pts
						(arc
							(start 0.3048 -0.2032)
							(mid 0.275042 -0.275042)
							(end 0.2032 -0.3048)
						)
						(arc
							(start -0.2032 -0.3048)
							(mid -0.275042 -0.275042)
							(end -0.3048 -0.2032)
						)
						(arc
							(start -0.3048 0.2032)
							(mid -0.275042 0.275042)
							(end -0.2032 0.3048)
						)
						(arc
							(start 0.2032 0.3048)
							(mid 0.275042 0.275042)
							(end 0.3048 0.2032)
						)
					)
					(width 0)
					(fill yes)
				)
			)
		)
	)
	(footprint ""
		(layer "F.Cu")
		(at 70.739 -356.489 90)
		(property "Reference" "SR1155"
			(at 0 0 90)
			(layer "F.SilkS")
			(hide yes)
			(effects
				(font
					(size 1.27 1.27)
				)
			)
		)
		(property "Value" "4K7R2F-GP"
			(at 0.064008 -3.993896 90)
			(unlocked yes)
			(layer "F.Fab")
			(hide yes)
			(effects
				(font
					(size 1.016 1.016)
					(thickness 0.1524)
				)
			)
		)
		(property "Device Type" "R402H16"
			(at 0.064008 -5.517896 90)
			(unlocked yes)
			(layer "F.Fab")
			(hide yes)
			(effects
				(font
					(size 1.016 1.016)
					(thickness 0.1524)
				)
			)
		)
		(duplicate_pad_numbers_are_jumpers no)
		(fp_line
			(start 0.508 -0.9398)
			(end -0.508 -0.9398)
			(stroke
				(width 0.1524)
				(type default)
			)
			(layer "F.SilkS")
		)
		(fp_line
			(start -0.508 -0.9398)
			(end -0.508 0.9398)
			(stroke
				(width 0.1524)
				(type default)
			)
			(layer "F.SilkS")
		)
		(fp_rect
			(start -0.508 0.9398)
			(end 0.508 -0.9398)
			(stroke
				(width 0)
				(type default)
			)
			(fill no)
			(layer "F.CrtYd")
		)
		(fp_rect
			(start -0.508 0.9398)
			(end 0.508 -0.9398)
			(stroke
				(width 0)
				(type default)
			)
			(fill no)
			(layer "F.Fab")
		)
		(pad "1" smd custom
			(at 0 -0.4445 90)
			(size 0.1397 0.1397)
			(layers "F.Cu" "F.Mask" "F.Paste")
			(net "P3V3")
			(options
				(clearance outline)
				(anchor circle)
			)
			(primitives
				(gr_poly
					(pts
						(arc
							(start -0.1778 -0.2794)
							(mid -0.249642 -0.249642)
							(end -0.2794 -0.1778)
						)
						(arc
							(start -0.2794 0.1778)
							(mid -0.249642 0.249642)
							(end -0.1778 0.2794)
						)
						(arc
							(start 0.1778 0.2794)
							(mid 0.249642 0.249642)
							(end 0.2794 0.1778)
						)
						(arc
							(start 0.2794 -0.1778)
							(mid 0.249642 -0.249642)
							(end 0.1778 -0.2794)
						)
					)
					(width 0)
					(fill yes)
				)
			)
		)
		(pad "2" smd custom
			(at 0 0.4445 90)
			(size 0.1397 0.1397)
			(layers "F.Cu" "F.Mask" "F.Paste")
			(net "I2C_SW_EU17_ADDRESS_A2")
			(options
				(clearance outline)
				(anchor circle)
			)
			(primitives
				(gr_poly
					(pts
						(arc
							(start -0.1778 -0.2794)
							(mid -0.249642 -0.249642)
							(end -0.2794 -0.1778)
						)
						(arc
							(start -0.2794 0.1778)
							(mid -0.249642 0.249642)
							(end -0.1778 0.2794)
						)
						(arc
							(start 0.1778 0.2794)
							(mid 0.249642 0.249642)
							(end 0.2794 0.1778)
						)
						(arc
							(start 0.2794 -0.1778)
							(mid 0.249642 -0.249642)
							(end 0.1778 -0.2794)
						)
					)
					(width 0)
					(fill yes)
				)
			)
		)
	)
	(footprint ""
		(layer "F.Cu")
		(at 32.2326 -211.0994 90)
		(property "Reference" "U21"
			(at 0 0 90)
			(layer "F.SilkS")
			(hide yes)
			(effects
				(font
					(size 1.27 1.27)
				)
			)
		)
		(property "Value" "P2003EVG-GP"
			(at 0 -11.1252 90)
			(unlocked yes)
			(layer "F.Fab")
			(hide yes)
			(effects
				(font
					(size 1.016 1.016)
					(thickness 0.1524)
				)
			)
		)
		(property "Device Type" "SOIC8H79"
			(at 0 -12.6492 90)
			(unlocked yes)
			(layer "F.Fab")
			(hide yes)
			(effects
				(font
					(size 1.016 1.016)
					(thickness 0.1524)
				)
			)
		)
		(duplicate_pad_numbers_are_jumpers no)
		(fp_line
			(start 2.1336 -1.4224)
			(end -2.7432 -1.4224)
			(stroke
				(width 0.1524)
				(type default)
			)
			(layer "F.SilkS")
		)
		(fp_line
			(start -2.7432 -1.4224)
			(end -2.7432 1.4224)
			(stroke
				(width 0.1524)
				(type default)
			)
			(layer "F.SilkS")
		)
		(fp_line
			(start -2.7432 -0.508)
			(end -2.2352 0)
			(stroke
				(width 0.1524)
				(type default)
			)
			(layer "F.SilkS")
		)
		(fp_line
			(start -2.2352 0)
			(end -2.7432 0.508)
			(stroke
				(width 0.1524)
				(type default)
			)
			(layer "F.SilkS")
		)
		(fp_line
			(start 2.1336 1.4224)
			(end 2.1336 -1.4224)
			(stroke
				(width 0.1524)
				(type default)
			)
			(layer "F.SilkS")
		)
		(fp_line
			(start -2.7432 1.4224)
			(end 2.1336 1.4224)
			(stroke
				(width 0.1524)
				(type default)
			)
			(layer "F.SilkS")
		)
		(fp_line
			(start -2.6162 3.429)
			(end -2.6162 1.4732)
			(stroke
				(width 0.4064)
				(type default)
			)
			(layer "F.SilkS")
		)
		(fp_poly
			(pts
				(xy 2.2098 -1.4224) (xy 2.2098 1.4224) (xy -2.2225 1.4224) (xy -2.2225 -1.4224)
			)
			(stroke
				(width 0)
				(type default)
			)
			(fill yes)
			(layer "F.SilkS")
		)
		(fp_rect
			(start -2.4511 2.9972)
			(end 2.4511 -2.9972)
			(stroke
				(width 0)
				(type default)
			)
			(fill no)
			(layer "F.CrtYd")
		)
		(fp_poly
			(pts
				(xy -2.8194 3.6322) (xy -2.8194 -3.6322) (xy 2.8194 -3.6322) (xy 2.8194 -2.2987) (xy 2.4511 -2.2987)
				(xy 2.4511 -2.9972) (xy -2.4511 -2.9972) (xy -2.4511 2.9972) (xy 2.4511 2.9972) (xy 2.4511 -2.286)
				(xy 2.8194 -2.286) (xy 2.8194 3.6322)
			)
			(stroke
				(width 0)
				(type default)
			)
			(fill no)
			(layer "F.CrtYd")
		)
		(fp_rect
			(start -2.8194 3.6322)
			(end 2.8194 -3.6322)
			(stroke
				(width 0)
				(type default)
			)
			(fill no)
			(layer "F.Fab")
		)
		(pad "1" smd rect
			(at -1.905 2.54 90)
			(size 0.635 1.651)
			(layers "F.Cu" "F.Mask" "F.Paste")
			(net "P12V")
		)
		(pad "2" smd rect
			(at -0.635 2.54 90)
			(size 0.635 1.651)
			(layers "F.Cu" "F.Mask" "F.Paste")
			(net "P12V")
		)
		(pad "3" smd rect
			(at 0.635 2.54 90)
			(size 0.635 1.651)
			(layers "F.Cu" "F.Mask" "F.Paste")
			(net "P12V")
		)
		(pad "4" smd rect
			(at 1.905 2.54 90)
			(size 0.635 1.651)
			(layers "F.Cu" "F.Mask" "F.Paste")
			(net "SW_SSD12_N")
		)
		(pad "5" smd rect
			(at 1.905 -2.54 90)
			(size 0.635 1.651)
			(layers "F.Cu" "F.Mask" "F.Paste")
			(net "P12V_SSD12")
		)
		(pad "6" smd rect
			(at 0.635 -2.54 90)
			(size 0.635 1.651)
			(layers "F.Cu" "F.Mask" "F.Paste")
			(net "P12V_SSD12")
		)
		(pad "7" smd rect
			(at -0.635 -2.54 90)
			(size 0.635 1.651)
			(layers "F.Cu" "F.Mask" "F.Paste")
			(net "P12V_SSD12")
		)
		(pad "8" smd rect
			(at -1.905 -2.54 90)
			(size 0.635 1.651)
			(layers "F.Cu" "F.Mask" "F.Paste")
			(net "P12V_SSD12")
		)
	)
	(footprint ""
		(layer "F.Cu")
		(at 209.677 -498.475 180)
		(property "Reference" "PC1186"
			(at 0 0 180)
			(layer "F.SilkS")
			(hide yes)
			(effects
				(font
					(size 1.27 1.27)
				)
			)
		)
		(property "Value" "SC22U25V6KX-GP-U"
			(at -2.860802 -5.279644 180)
			(unlocked yes)
			(layer "F.Fab")
			(hide yes)
			(effects
				(font
					(size 1.016 1.016)
					(thickness 0.1524)
				)
			)
		)
		(property "Device Type" "C1206-TO0D3H75"
			(at -2.860802 -6.803644 180)
			(unlocked yes)
			(layer "F.Fab")
			(hide yes)
			(effects
				(font
					(size 1.016 1.016)
					(thickness 0.1524)
				)
			)
		)
		(duplicate_pad_numbers_are_jumpers no)
		(fp_line
			(start 1.3081 2.3749)
			(end -1.3081 2.3749)
			(stroke
				(width 0.1524)
				(type default)
			)
			(layer "F.SilkS")
		)
		(fp_line
			(start 1.3081 -2.3749)
			(end 1.3081 2.3749)
			(stroke
				(width 0.1524)
				(type default)
			)
			(layer "F.SilkS")
		)
		(fp_line
			(start -1.3081 2.3749)
			(end -1.3081 -2.3749)
			(stroke
				(width 0.1524)
				(type default)
			)
			(layer "F.SilkS")
		)
		(fp_line
			(start -1.3081 -2.3749)
			(end 1.3081 -2.3749)
			(stroke
				(width 0.1524)
				(type default)
			)
			(layer "F.SilkS")
		)
		(fp_rect
			(start -0.8001 1.6002)
			(end 0.8001 -1.6002)
			(stroke
				(width 0)
				(type default)
			)
			(fill no)
			(layer "F.CrtYd")
		)
		(fp_poly
			(pts
				(xy -1.5621 2.4511) (xy -1.5621 1.6002) (xy 0.8001 1.6002) (xy 0.8001 -1.6002) (xy -0.8001 -1.6002)
				(xy -0.8001 1.5875) (xy -1.5621 1.5875) (xy -1.5621 -2.4511) (xy 1.5621 -2.4511) (xy 1.5621 2.4511)
			)
			(stroke
				(width 0)
				(type default)
			)
			(fill no)
			(layer "F.CrtYd")
		)
		(fp_rect
			(start -1.5621 2.4511)
			(end 1.5621 -2.4511)
			(stroke
				(width 0)
				(type default)
			)
			(fill no)
			(layer "F.Fab")
		)
		(pad "1" smd rect
			(at 0 -1.392936 180)
			(size 2.1082 1.4478)
			(layers "F.Cu" "F.Mask" "F.Paste")
			(net "P12V_SSD0")
		)
		(pad "2" smd rect
			(at 0 1.392936 180)
			(size 2.1082 1.4478)
			(layers "F.Cu" "F.Mask" "F.Paste")
			(net "GND")
		)
	)
	(footprint ""
		(layer "F.Cu")
		(at 214.3887 -84.455)
		(property "Reference" "SR1099"
			(at 0 0 0)
			(layer "F.SilkS")
			(hide yes)
			(effects
				(font
					(size 1.27 1.27)
				)
			)
		)
		(property "Value" "4K7R2F-GP"
			(at 0.064008 -3.993896 0)
			(unlocked yes)
			(layer "F.Fab")
			(hide yes)
			(effects
				(font
					(size 1.016 1.016)
					(thickness 0.1524)
				)
			)
		)
		(property "Device Type" "R402H16"
			(at 0.064008 -5.517896 0)
			(unlocked yes)
			(layer "F.Fab")
			(hide yes)
			(effects
				(font
					(size 1.016 1.016)
					(thickness 0.1524)
				)
			)
		)
		(duplicate_pad_numbers_are_jumpers no)
		(fp_line
			(start -0.508 -0.9398)
			(end -0.508 0.9398)
			(stroke
				(width 0.1524)
				(type default)
			)
			(layer "F.SilkS")
		)
		(fp_line
			(start 0.508 -0.9398)
			(end -0.508 -0.9398)
			(stroke
				(width 0.1524)
				(type default)
			)
			(layer "F.SilkS")
		)
		(fp_rect
			(start -0.508 0.9398)
			(end 0.508 -0.9398)
			(stroke
				(width 0)
				(type default)
			)
			(fill no)
			(layer "F.CrtYd")
		)
		(fp_rect
			(start -0.508 0.9398)
			(end 0.508 -0.9398)
			(stroke
				(width 0)
				(type default)
			)
			(fill no)
			(layer "F.Fab")
		)
		(pad "1" smd custom
			(at 0 -0.4445)
			(size 0.1397 0.1397)
			(layers "F.Cu" "F.Mask" "F.Paste")
			(net "P3V3")
			(options
				(clearance outline)
				(anchor circle)
			)
			(primitives
				(gr_poly
					(pts
						(arc
							(start -0.1778 -0.2794)
							(mid -0.249642 -0.249642)
							(end -0.2794 -0.1778)
						)
						(arc
							(start -0.2794 0.1778)
							(mid -0.249642 0.249642)
							(end -0.1778 0.2794)
						)
						(arc
							(start 0.1778 0.2794)
							(mid 0.249642 0.249642)
							(end 0.2794 0.1778)
						)
						(arc
							(start 0.2794 -0.1778)
							(mid 0.249642 -0.249642)
							(end 0.1778 -0.2794)
						)
					)
					(width 0)
					(fill yes)
				)
			)
		)
		(pad "2" smd custom
			(at 0 0.4445)
			(size 0.1397 0.1397)
			(layers "F.Cu" "F.Mask" "F.Paste")
			(net "DUALPORTEN#4")
			(options
				(clearance outline)
				(anchor circle)
			)
			(primitives
				(gr_poly
					(pts
						(arc
							(start -0.1778 -0.2794)
							(mid -0.249642 -0.249642)
							(end -0.2794 -0.1778)
						)
						(arc
							(start -0.2794 0.1778)
							(mid -0.249642 0.249642)
							(end -0.1778 0.2794)
						)
						(arc
							(start 0.1778 0.2794)
							(mid 0.249642 0.249642)
							(end 0.2794 0.1778)
						)
						(arc
							(start 0.2794 -0.1778)
							(mid 0.249642 -0.249642)
							(end 0.1778 -0.2794)
						)
					)
					(width 0)
					(fill yes)
				)
			)
		)
	)
	(footprint ""
		(layer "F.Cu")
		(at 49.022 -453.644 -90)
		(property "Reference" "R9415"
			(at 0 0 270)
			(layer "F.SilkS")
			(hide yes)
			(effects
				(font
					(size 1.27 1.27)
				)
			)
		)
		(property "Value" "100R2J-2-GP"
			(at 0.064008 -3.993896 270)
			(unlocked yes)
			(layer "F.Fab")
			(hide yes)
			(effects
				(font
					(size 1.016 1.016)
					(thickness 0.1524)
				)
			)
		)
		(property "Device Type" "R402H14"
			(at 0.064008 -5.517896 270)
			(unlocked yes)
			(layer "F.Fab")
			(hide yes)
			(effects
				(font
					(size 1.016 1.016)
					(thickness 0.1524)
				)
			)
		)
		(duplicate_pad_numbers_are_jumpers no)
		(fp_line
			(start -0.508 -0.9398)
			(end -0.508 0.9398)
			(stroke
				(width 0.1524)
				(type default)
			)
			(layer "F.SilkS")
		)
		(fp_line
			(start 0.508 -0.9398)
			(end -0.508 -0.9398)
			(stroke
				(width 0.1524)
				(type default)
			)
			(layer "F.SilkS")
		)
		(fp_rect
			(start -0.508 0.9398)
			(end 0.508 -0.9398)
			(stroke
				(width 0)
				(type default)
			)
			(fill no)
			(layer "F.CrtYd")
		)
		(fp_rect
			(start -0.508 0.9398)
			(end 0.508 -0.9398)
			(stroke
				(width 0)
				(type default)
			)
			(fill no)
			(layer "F.Fab")
		)
		(pad "1" smd custom
			(at 0 -0.4445 270)
			(size 0.1397 0.1397)
			(layers "F.Cu" "F.Mask" "F.Paste")
			(net "P3V3")
			(options
				(clearance outline)
				(anchor circle)
			)
			(primitives
				(gr_poly
					(pts
						(arc
							(start -0.1778 -0.2794)
							(mid -0.249642 -0.249642)
							(end -0.2794 -0.1778)
						)
						(arc
							(start -0.2794 0.1778)
							(mid -0.249642 0.249642)
							(end -0.1778 0.2794)
						)
						(arc
							(start 0.1778 0.2794)
							(mid 0.249642 0.249642)
							(end 0.2794 0.1778)
						)
						(arc
							(start 0.2794 -0.1778)
							(mid 0.249642 -0.249642)
							(end 0.1778 -0.2794)
						)
					)
					(width 0)
					(fill yes)
				)
			)
		)
		(pad "2" smd custom
			(at 0 0.4445 270)
			(size 0.1397 0.1397)
			(layers "F.Cu" "F.Mask" "F.Paste")
			(net "DRV_ACT_5")
			(options
				(clearance outline)
				(anchor circle)
			)
			(primitives
				(gr_poly
					(pts
						(arc
							(start -0.1778 -0.2794)
							(mid -0.249642 -0.249642)
							(end -0.2794 -0.1778)
						)
						(arc
							(start -0.2794 0.1778)
							(mid -0.249642 0.249642)
							(end -0.1778 0.2794)
						)
						(arc
							(start 0.1778 0.2794)
							(mid 0.249642 0.249642)
							(end 0.2794 0.1778)
						)
						(arc
							(start 0.2794 -0.1778)
							(mid 0.249642 -0.249642)
							(end 0.1778 -0.2794)
						)
					)
					(width 0)
					(fill yes)
				)
			)
		)
	)
	(footprint ""
		(layer "F.Cu")
		(at 8.7376 -462.2038 90)
		(property "Reference" "PC1169"
			(at 0 0 90)
			(layer "F.SilkS")
			(hide yes)
			(effects
				(font
					(size 1.27 1.27)
				)
			)
		)
		(property "Value" "SCD01U50V2KX-1GP"
			(at 1.1811 -2.7051 90)
			(unlocked yes)
			(layer "F.Fab")
			(hide yes)
			(effects
				(font
					(size 1.016 1.016)
					(thickness 0.1524)
				)
			)
		)
		(property "Device Type" "C402H22"
			(at 1.1811 -4.2291 90)
			(unlocked yes)
			(layer "F.Fab")
			(hide yes)
			(effects
				(font
					(size 1.016 1.016)
					(thickness 0.1524)
				)
			)
		)
		(duplicate_pad_numbers_are_jumpers no)
		(fp_rect
			(start -0.4318 0.9525)
			(end 0.4318 -0.9525)
			(stroke
				(width 0)
				(type default)
			)
			(fill no)
			(layer "F.CrtYd")
		)
		(fp_rect
			(start -0.4318 0.9525)
			(end 0.4318 -0.9525)
			(stroke
				(width 0)
				(type default)
			)
			(fill no)
			(layer "F.Fab")
		)
		(pad "1" smd custom
			(at 0 -0.4445 90)
			(size 0.1524 0.1524)
			(layers "F.Cu" "F.Mask" "F.Paste")
			(net "P12V")
			(options
				(clearance outline)
				(anchor circle)
			)
			(primitives
				(gr_poly
					(pts
						(arc
							(start 0.3048 -0.2032)
							(mid 0.275042 -0.275042)
							(end 0.2032 -0.3048)
						)
						(arc
							(start -0.2032 -0.3048)
							(mid -0.275042 -0.275042)
							(end -0.3048 -0.2032)
						)
						(arc
							(start -0.3048 0.2032)
							(mid -0.275042 0.275042)
							(end -0.2032 0.3048)
						)
						(arc
							(start 0.2032 0.3048)
							(mid 0.275042 0.275042)
							(end 0.3048 0.2032)
						)
					)
					(width 0)
					(fill yes)
				)
			)
		)
		(pad "2" smd custom
			(at 0 0.4445 90)
			(size 0.1524 0.1524)
			(layers "F.Cu" "F.Mask" "F.Paste")
			(net "GND")
			(options
				(clearance outline)
				(anchor circle)
			)
			(primitives
				(gr_poly
					(pts
						(arc
							(start 0.3048 -0.2032)
							(mid 0.275042 -0.275042)
							(end 0.2032 -0.3048)
						)
						(arc
							(start -0.2032 -0.3048)
							(mid -0.275042 -0.275042)
							(end -0.3048 -0.2032)
						)
						(arc
							(start -0.3048 0.2032)
							(mid -0.275042 0.275042)
							(end -0.2032 0.3048)
						)
						(arc
							(start 0.2032 0.3048)
							(mid 0.275042 0.275042)
							(end 0.3048 0.2032)
						)
					)
					(width 0)
					(fill yes)
				)
			)
		)
	)
	(footprint ""
		(layer "F.Cu")
		(at 78.9686 -105.7148 -90)
		(property "Reference" "C8935"
			(at 0 0 270)
			(layer "F.SilkS")
			(hide yes)
			(effects
				(font
					(size 1.27 1.27)
				)
			)
		)
		(property "Value" "SC10U25V3MX-GP"
			(at 0 -2.8194 270)
			(unlocked yes)
			(layer "F.Fab")
			(hide yes)
			(effects
				(font
					(size 1.016 1.016)
					(thickness 0.1524)
				)
			)
		)
		(property "Device Type" "C603H40"
			(at 0 -4.3434 270)
			(unlocked yes)
			(layer "F.Fab")
			(hide yes)
			(effects
				(font
					(size 1.016 1.016)
					(thickness 0.1524)
				)
			)
		)
		(duplicate_pad_numbers_are_jumpers no)
		(fp_line
			(start 0.508 0)
			(end -0.508 0)
			(stroke
				(width 0.2032)
				(type default)
			)
			(layer "F.SilkS")
		)
		(fp_rect
			(start -0.5842 1.3335)
			(end 0.5842 -1.3335)
			(stroke
				(width 0)
				(type default)
			)
			(fill no)
			(layer "F.CrtYd")
		)
		(fp_rect
			(start -0.5842 1.3335)
			(end 0.5842 -1.3335)
			(stroke
				(width 0)
				(type default)
			)
			(fill no)
			(layer "F.Fab")
		)
		(pad "1" smd custom
			(at 0 -0.762 270)
			(size 0.2159 0.2159)
			(layers "F.Cu" "F.Mask" "F.Paste")
			(net "VDD_DIFF_4")
			(options
				(clearance outline)
				(anchor circle)
			)
			(primitives
				(gr_poly
					(pts
						(arc
							(start -0.3302 -0.4318)
							(mid -0.402042 -0.402042)
							(end -0.4318 -0.3302)
						)
						(arc
							(start -0.4318 0.3302)
							(mid -0.402042 0.402042)
							(end -0.3302 0.4318)
						)
						(arc
							(start 0.3302 0.4318)
							(mid 0.402042 0.402042)
							(end 0.4318 0.3302)
						)
						(arc
							(start 0.4318 -0.3302)
							(mid 0.402042 -0.402042)
							(end 0.3302 -0.4318)
						)
					)
					(width 0)
					(fill yes)
				)
			)
		)
		(pad "2" smd custom
			(at 0 0.762 270)
			(size 0.2159 0.2159)
			(layers "F.Cu" "F.Mask" "F.Paste")
			(net "GND")
			(options
				(clearance outline)
				(anchor circle)
			)
			(primitives
				(gr_poly
					(pts
						(arc
							(start -0.3302 -0.4318)
							(mid -0.402042 -0.402042)
							(end -0.4318 -0.3302)
						)
						(arc
							(start -0.4318 0.3302)
							(mid -0.402042 0.402042)
							(end -0.3302 0.4318)
						)
						(arc
							(start 0.3302 0.4318)
							(mid 0.402042 0.402042)
							(end 0.4318 0.3302)
						)
						(arc
							(start 0.4318 -0.3302)
							(mid 0.402042 -0.402042)
							(end 0.3302 -0.4318)
						)
					)
					(width 0)
					(fill yes)
				)
			)
		)
	)
	(footprint ""
		(layer "F.Cu")
		(at 95.504 -296.545)
		(property "Reference" "R9078"
			(at 0 0 0)
			(layer "F.SilkS")
			(hide yes)
			(effects
				(font
					(size 1.27 1.27)
				)
			)
		)
		(property "Value" "27R2F-GP"
			(at 0.064008 -3.993896 0)
			(unlocked yes)
			(layer "F.Fab")
			(hide yes)
			(effects
				(font
					(size 1.016 1.016)
					(thickness 0.1524)
				)
			)
		)
		(property "Device Type" "R402H16"
			(at 0.064008 -5.517896 0)
			(unlocked yes)
			(layer "F.Fab")
			(hide yes)
			(effects
				(font
					(size 1.016 1.016)
					(thickness 0.1524)
				)
			)
		)
		(duplicate_pad_numbers_are_jumpers no)
		(fp_line
			(start -0.508 -0.9398)
			(end -0.508 0.9398)
			(stroke
				(width 0.1524)
				(type default)
			)
			(layer "F.SilkS")
		)
		(fp_line
			(start 0.508 -0.9398)
			(end -0.508 -0.9398)
			(stroke
				(width 0.1524)
				(type default)
			)
			(layer "F.SilkS")
		)
		(fp_rect
			(start -0.508 0.9398)
			(end 0.508 -0.9398)
			(stroke
				(width 0)
				(type default)
			)
			(fill no)
			(layer "F.CrtYd")
		)
		(fp_rect
			(start -0.508 0.9398)
			(end 0.508 -0.9398)
			(stroke
				(width 0)
				(type default)
			)
			(fill no)
			(layer "F.Fab")
		)
		(pad "1" smd custom
			(at 0 -0.4445)
			(size 0.1397 0.1397)
			(layers "F.Cu" "F.Mask" "F.Paste")
			(net "PE_CLK_100M_DR2_2_R_P")
			(options
				(clearance outline)
				(anchor circle)
			)
			(primitives
				(gr_poly
					(pts
						(arc
							(start -0.1778 -0.2794)
							(mid -0.249642 -0.249642)
							(end -0.2794 -0.1778)
						)
						(arc
							(start -0.2794 0.1778)
							(mid -0.249642 0.249642)
							(end -0.1778 0.2794)
						)
						(arc
							(start 0.1778 0.2794)
							(mid 0.249642 0.249642)
							(end 0.2794 0.1778)
						)
						(arc
							(start 0.2794 -0.1778)
							(mid 0.249642 -0.249642)
							(end 0.1778 -0.2794)
						)
					)
					(width 0)
					(fill yes)
				)
			)
		)
		(pad "2" smd custom
			(at 0 0.4445)
			(size 0.1397 0.1397)
			(layers "F.Cu" "F.Mask" "F.Paste")
			(net "PE_CLK100M_DR2_2_P")
			(options
				(clearance outline)
				(anchor circle)
			)
			(primitives
				(gr_poly
					(pts
						(arc
							(start -0.1778 -0.2794)
							(mid -0.249642 -0.249642)
							(end -0.2794 -0.1778)
						)
						(arc
							(start -0.2794 0.1778)
							(mid -0.249642 0.249642)
							(end -0.1778 0.2794)
						)
						(arc
							(start 0.1778 0.2794)
							(mid 0.249642 0.249642)
							(end 0.2794 0.1778)
						)
						(arc
							(start 0.2794 -0.1778)
							(mid 0.249642 -0.249642)
							(end 0.1778 -0.2794)
						)
					)
					(width 0)
					(fill yes)
				)
			)
		)
	)
	(footprint ""
		(layer "F.Cu")
		(at 98.679 -202.184)
		(property "Reference" "R9086"
			(at 0 0 0)
			(layer "F.SilkS")
			(hide yes)
			(effects
				(font
					(size 1.27 1.27)
				)
			)
		)
		(property "Value" "27R2F-GP"
			(at 0.064008 -3.993896 0)
			(unlocked yes)
			(layer "F.Fab")
			(hide yes)
			(effects
				(font
					(size 1.016 1.016)
					(thickness 0.1524)
				)
			)
		)
		(property "Device Type" "R402H16"
			(at 0.064008 -5.517896 0)
			(unlocked yes)
			(layer "F.Fab")
			(hide yes)
			(effects
				(font
					(size 1.016 1.016)
					(thickness 0.1524)
				)
			)
		)
		(duplicate_pad_numbers_are_jumpers no)
		(fp_line
			(start -0.508 -0.9398)
			(end -0.508 0.9398)
			(stroke
				(width 0.1524)
				(type default)
			)
			(layer "F.SilkS")
		)
		(fp_line
			(start 0.508 -0.9398)
			(end -0.508 -0.9398)
			(stroke
				(width 0.1524)
				(type default)
			)
			(layer "F.SilkS")
		)
		(fp_rect
			(start -0.508 0.9398)
			(end 0.508 -0.9398)
			(stroke
				(width 0)
				(type default)
			)
			(fill no)
			(layer "F.CrtYd")
		)
		(fp_rect
			(start -0.508 0.9398)
			(end 0.508 -0.9398)
			(stroke
				(width 0)
				(type default)
			)
			(fill no)
			(layer "F.Fab")
		)
		(pad "1" smd custom
			(at 0 -0.4445)
			(size 0.1397 0.1397)
			(layers "F.Cu" "F.Mask" "F.Paste")
			(net "PE_CLK_100M_DR4_1_R_N")
			(options
				(clearance outline)
				(anchor circle)
			)
			(primitives
				(gr_poly
					(pts
						(arc
							(start -0.1778 -0.2794)
							(mid -0.249642 -0.249642)
							(end -0.2794 -0.1778)
						)
						(arc
							(start -0.2794 0.1778)
							(mid -0.249642 0.249642)
							(end -0.1778 0.2794)
						)
						(arc
							(start 0.1778 0.2794)
							(mid 0.249642 0.249642)
							(end 0.2794 0.1778)
						)
						(arc
							(start 0.2794 -0.1778)
							(mid 0.249642 -0.249642)
							(end 0.1778 -0.2794)
						)
					)
					(width 0)
					(fill yes)
				)
			)
		)
		(pad "2" smd custom
			(at 0 0.4445)
			(size 0.1397 0.1397)
			(layers "F.Cu" "F.Mask" "F.Paste")
			(net "PE_CLK100M_DR4_1_N")
			(options
				(clearance outline)
				(anchor circle)
			)
			(primitives
				(gr_poly
					(pts
						(arc
							(start -0.1778 -0.2794)
							(mid -0.249642 -0.249642)
							(end -0.2794 -0.1778)
						)
						(arc
							(start -0.2794 0.1778)
							(mid -0.249642 0.249642)
							(end -0.1778 0.2794)
						)
						(arc
							(start 0.1778 0.2794)
							(mid 0.249642 0.249642)
							(end 0.2794 0.1778)
						)
						(arc
							(start 0.2794 -0.1778)
							(mid 0.249642 -0.249642)
							(end 0.1778 -0.2794)
						)
					)
					(width 0)
					(fill yes)
				)
			)
		)
	)
	(footprint ""
		(layer "F.Cu")
		(at 26.416 -300.9646 -90)
		(property "Reference" "Q62"
			(at 0 0 270)
			(layer "F.SilkS")
			(hide yes)
			(effects
				(font
					(size 1.27 1.27)
				)
			)
		)
		(property "Value" "2N7002A-7-GP"
			(at 0.127 -8.9662 270)
			(unlocked yes)
			(layer "F.Fab")
			(hide yes)
			(effects
				(font
					(size 1.016 1.016)
					(thickness 0.1524)
				)
			)
		)
		(property "Device Type" "SOT23DGS2D4H48"
			(at 0.127 -10.4902 270)
			(unlocked yes)
			(layer "F.Fab")
			(hide yes)
			(effects
				(font
					(size 1.016 1.016)
					(thickness 0.1524)
				)
			)
		)
		(duplicate_pad_numbers_are_jumpers no)
		(fp_line
			(start -1.651 1.778)
			(end 1.651 1.778)
			(stroke
				(width 0.1524)
				(type default)
			)
			(layer "F.SilkS")
		)
		(fp_line
			(start 1.651 1.778)
			(end 1.651 -1.778)
			(stroke
				(width 0.1524)
				(type default)
			)
			(layer "F.SilkS")
		)
		(fp_line
			(start -1.651 -1.778)
			(end -1.651 1.778)
			(stroke
				(width 0.1524)
				(type default)
			)
			(layer "F.SilkS")
		)
		(fp_line
			(start 1.651 -1.778)
			(end -1.651 -1.778)
			(stroke
				(width 0.1524)
				(type default)
			)
			(layer "F.SilkS")
		)
		(fp_poly
			(pts
				(xy -1.778 1.8796) (xy -1.778 -1.8796) (xy 1.778 -1.8796) (xy 1.778 1.8796)
			)
			(stroke
				(width 0)
				(type default)
			)
			(fill no)
			(layer "F.CrtYd")
		)
		(fp_poly
			(pts
				(xy -1.778 1.8796) (xy -1.778 -1.8796) (xy 1.778 -1.8796) (xy 1.778 1.8796)
			)
			(stroke
				(width 0)
				(type default)
			)
			(fill no)
			(layer "F.Fab")
		)
		(pad "D" smd custom
			(at 0 -0.9525 270)
			(size 0.1905 0.1905)
			(layers "F.Cu" "F.Mask" "F.Paste")
			(net "P12V_MOST7_GATE")
			(options
				(clearance outline)
				(anchor circle)
			)
			(primitives
				(gr_poly
					(pts
						(arc
							(start -0.1778 0.5715)
							(mid -0.321484 0.511984)
							(end -0.381 0.3683)
						)
						(arc
							(start -0.381 -0.3683)
							(mid -0.321484 -0.511984)
							(end -0.1778 -0.5715)
						)
						(arc
							(start 0.1778 -0.5715)
							(mid 0.321484 -0.511984)
							(end 0.381 -0.3683)
						)
						(arc
							(start 0.381 0.3683)
							(mid 0.321484 0.511984)
							(end 0.1778 0.5715)
						)
					)
					(width 0)
					(fill yes)
				)
			)
		)
		(pad "G" smd custom
			(at -0.98425 0.9525 270)
			(size 0.1905 0.1905)
			(layers "F.Cu" "F.Mask" "F.Paste")
			(net "SSD7_PWREN_R")
			(options
				(clearance outline)
				(anchor circle)
			)
			(primitives
				(gr_poly
					(pts
						(arc
							(start -0.1778 0.5715)
							(mid -0.321484 0.511984)
							(end -0.381 0.3683)
						)
						(arc
							(start -0.381 -0.3683)
							(mid -0.321484 -0.511984)
							(end -0.1778 -0.5715)
						)
						(arc
							(start 0.1778 -0.5715)
							(mid 0.321484 -0.511984)
							(end 0.381 -0.3683)
						)
						(arc
							(start 0.381 0.3683)
							(mid 0.321484 0.511984)
							(end 0.1778 0.5715)
						)
					)
					(width 0)
					(fill yes)
				)
			)
		)
		(pad "S" smd custom
			(at 0.98425 0.9525 270)
			(size 0.1905 0.1905)
			(layers "F.Cu" "F.Mask" "F.Paste")
			(net "GND")
			(options
				(clearance outline)
				(anchor circle)
			)
			(primitives
				(gr_poly
					(pts
						(arc
							(start -0.1778 0.5715)
							(mid -0.321484 0.511984)
							(end -0.381 0.3683)
						)
						(arc
							(start -0.381 -0.3683)
							(mid -0.321484 -0.511984)
							(end -0.1778 -0.5715)
						)
						(arc
							(start 0.1778 -0.5715)
							(mid 0.321484 -0.511984)
							(end 0.381 -0.3683)
						)
						(arc
							(start 0.381 0.3683)
							(mid 0.321484 0.511984)
							(end 0.1778 0.5715)
						)
					)
					(width 0)
					(fill yes)
				)
			)
		)
	)
	(footprint ""
		(layer "F.Cu")
		(at 77.7748 -432.2445 180)
		(property "Reference" "R9961"
			(at 0 0 180)
			(layer "F.SilkS")
			(hide yes)
			(effects
				(font
					(size 1.27 1.27)
				)
			)
		)
		(property "Value" "56R2F-1-GP"
			(at 0.064008 -3.993896 180)
			(unlocked yes)
			(layer "F.Fab")
			(hide yes)
			(effects
				(font
					(size 1.016 1.016)
					(thickness 0.1524)
				)
			)
		)
		(property "Device Type" "R402H16"
			(at 0.064008 -5.517896 180)
			(unlocked yes)
			(layer "F.Fab")
			(hide yes)
			(effects
				(font
					(size 1.016 1.016)
					(thickness 0.1524)
				)
			)
		)
		(duplicate_pad_numbers_are_jumpers no)
		(fp_line
			(start 0.508 -0.9398)
			(end -0.508 -0.9398)
			(stroke
				(width 0.1524)
				(type default)
			)
			(layer "F.SilkS")
		)
		(fp_line
			(start -0.508 -0.9398)
			(end -0.508 0.9398)
			(stroke
				(width 0.1524)
				(type default)
			)
			(layer "F.SilkS")
		)
		(fp_rect
			(start -0.508 0.9398)
			(end 0.508 -0.9398)
			(stroke
				(width 0)
				(type default)
			)
			(fill no)
			(layer "F.CrtYd")
		)
		(fp_rect
			(start -0.508 0.9398)
			(end 0.508 -0.9398)
			(stroke
				(width 0)
				(type default)
			)
			(fill no)
			(layer "F.Fab")
		)
		(pad "1" smd custom
			(at 0 -0.4445 180)
			(size 0.1397 0.1397)
			(layers "F.Cu" "F.Mask" "F.Paste")
			(net "PE_100M_CLK4_P")
			(options
				(clearance outline)
				(anchor circle)
			)
			(primitives
				(gr_poly
					(pts
						(arc
							(start -0.1778 -0.2794)
							(mid -0.249642 -0.249642)
							(end -0.2794 -0.1778)
						)
						(arc
							(start -0.2794 0.1778)
							(mid -0.249642 0.249642)
							(end -0.1778 0.2794)
						)
						(arc
							(start 0.1778 0.2794)
							(mid 0.249642 0.249642)
							(end 0.2794 0.1778)
						)
						(arc
							(start 0.2794 -0.1778)
							(mid 0.249642 -0.249642)
							(end 0.1778 -0.2794)
						)
					)
					(width 0)
					(fill yes)
				)
			)
		)
		(pad "2" smd custom
			(at 0 0.4445 180)
			(size 0.1397 0.1397)
			(layers "F.Cu" "F.Mask" "F.Paste")
			(net "GND")
			(options
				(clearance outline)
				(anchor circle)
			)
			(primitives
				(gr_poly
					(pts
						(arc
							(start -0.1778 -0.2794)
							(mid -0.249642 -0.249642)
							(end -0.2794 -0.1778)
						)
						(arc
							(start -0.2794 0.1778)
							(mid -0.249642 0.249642)
							(end -0.1778 0.2794)
						)
						(arc
							(start 0.1778 0.2794)
							(mid 0.249642 0.249642)
							(end 0.2794 0.1778)
						)
						(arc
							(start 0.2794 -0.1778)
							(mid 0.249642 -0.249642)
							(end 0.1778 -0.2794)
						)
					)
					(width 0)
					(fill yes)
				)
			)
		)
	)
	(footprint ""
		(layer "F.Cu")
		(at 27.94 -374.65 180)
		(property "Reference" "R333"
			(at 0 0 180)
			(layer "F.SilkS")
			(hide yes)
			(effects
				(font
					(size 1.27 1.27)
				)
			)
		)
		(property "Value" "4K7R2J-2-GP"
			(at 0.064008 -3.993896 180)
			(unlocked yes)
			(layer "F.Fab")
			(hide yes)
			(effects
				(font
					(size 1.016 1.016)
					(thickness 0.1524)
				)
			)
		)
		(property "Device Type" "R402H16"
			(at 0.064008 -5.517896 180)
			(unlocked yes)
			(layer "F.Fab")
			(hide yes)
			(effects
				(font
					(size 1.016 1.016)
					(thickness 0.1524)
				)
			)
		)
		(duplicate_pad_numbers_are_jumpers no)
		(fp_line
			(start 0.508 -0.9398)
			(end -0.508 -0.9398)
			(stroke
				(width 0.1524)
				(type default)
			)
			(layer "F.SilkS")
		)
		(fp_line
			(start -0.508 -0.9398)
			(end -0.508 0.9398)
			(stroke
				(width 0.1524)
				(type default)
			)
			(layer "F.SilkS")
		)
		(fp_rect
			(start -0.508 0.9398)
			(end 0.508 -0.9398)
			(stroke
				(width 0)
				(type default)
			)
			(fill no)
			(layer "F.CrtYd")
		)
		(fp_rect
			(start -0.508 0.9398)
			(end 0.508 -0.9398)
			(stroke
				(width 0)
				(type default)
			)
			(fill no)
			(layer "F.Fab")
		)
		(pad "1" smd custom
			(at 0 -0.4445 180)
			(size 0.1397 0.1397)
			(layers "F.Cu" "F.Mask" "F.Paste")
			(net "P3V3")
			(options
				(clearance outline)
				(anchor circle)
			)
			(primitives
				(gr_poly
					(pts
						(arc
							(start -0.1778 -0.2794)
							(mid -0.249642 -0.249642)
							(end -0.2794 -0.1778)
						)
						(arc
							(start -0.2794 0.1778)
							(mid -0.249642 0.249642)
							(end -0.1778 0.2794)
						)
						(arc
							(start 0.1778 0.2794)
							(mid 0.249642 0.249642)
							(end 0.2794 0.1778)
						)
						(arc
							(start 0.2794 -0.1778)
							(mid 0.249642 -0.249642)
							(end 0.1778 -0.2794)
						)
					)
					(width 0)
					(fill yes)
				)
			)
		)
		(pad "2" smd custom
			(at 0 0.4445 180)
			(size 0.1397 0.1397)
			(layers "F.Cu" "F.Mask" "F.Paste")
			(net "I2C_B_TMP4_A0")
			(options
				(clearance outline)
				(anchor circle)
			)
			(primitives
				(gr_poly
					(pts
						(arc
							(start -0.1778 -0.2794)
							(mid -0.249642 -0.249642)
							(end -0.2794 -0.1778)
						)
						(arc
							(start -0.2794 0.1778)
							(mid -0.249642 0.249642)
							(end -0.1778 0.2794)
						)
						(arc
							(start 0.1778 0.2794)
							(mid 0.249642 0.249642)
							(end 0.2794 0.1778)
						)
						(arc
							(start 0.2794 -0.1778)
							(mid 0.249642 -0.249642)
							(end 0.1778 -0.2794)
						)
					)
					(width 0)
					(fill yes)
				)
			)
		)
	)
	(footprint ""
		(layer "F.Cu")
		(at 82.931 -102.7176 90)
		(property "Reference" "R9357"
			(at 0 0 90)
			(layer "F.SilkS")
			(hide yes)
			(effects
				(font
					(size 1.27 1.27)
				)
			)
		)
		(property "Value" "2D2R2F-GP"
			(at 0.064008 -3.993896 90)
			(unlocked yes)
			(layer "F.Fab")
			(hide yes)
			(effects
				(font
					(size 1.016 1.016)
					(thickness 0.1524)
				)
			)
		)
		(property "Device Type" "R402H16"
			(at 0.064008 -5.517896 90)
			(unlocked yes)
			(layer "F.Fab")
			(hide yes)
			(effects
				(font
					(size 1.016 1.016)
					(thickness 0.1524)
				)
			)
		)
		(duplicate_pad_numbers_are_jumpers no)
		(fp_line
			(start 0.508 -0.9398)
			(end -0.508 -0.9398)
			(stroke
				(width 0.1524)
				(type default)
			)
			(layer "F.SilkS")
		)
		(fp_line
			(start -0.508 -0.9398)
			(end -0.508 0.9398)
			(stroke
				(width 0.1524)
				(type default)
			)
			(layer "F.SilkS")
		)
		(fp_rect
			(start -0.508 0.9398)
			(end 0.508 -0.9398)
			(stroke
				(width 0)
				(type default)
			)
			(fill no)
			(layer "F.CrtYd")
		)
		(fp_rect
			(start -0.508 0.9398)
			(end 0.508 -0.9398)
			(stroke
				(width 0)
				(type default)
			)
			(fill no)
			(layer "F.Fab")
		)
		(pad "1" smd custom
			(at 0 -0.4445 90)
			(size 0.1397 0.1397)
			(layers "F.Cu" "F.Mask" "F.Paste")
			(net "VDD_DIFF_4")
			(options
				(clearance outline)
				(anchor circle)
			)
			(primitives
				(gr_poly
					(pts
						(arc
							(start -0.1778 -0.2794)
							(mid -0.249642 -0.249642)
							(end -0.2794 -0.1778)
						)
						(arc
							(start -0.2794 0.1778)
							(mid -0.249642 0.249642)
							(end -0.1778 0.2794)
						)
						(arc
							(start 0.1778 0.2794)
							(mid 0.249642 0.249642)
							(end 0.2794 0.1778)
						)
						(arc
							(start 0.2794 -0.1778)
							(mid 0.249642 -0.249642)
							(end 0.1778 -0.2794)
						)
					)
					(width 0)
					(fill yes)
				)
			)
		)
		(pad "2" smd custom
			(at 0 0.4445 90)
			(size 0.1397 0.1397)
			(layers "F.Cu" "F.Mask" "F.Paste")
			(net "VDDR_4")
			(options
				(clearance outline)
				(anchor circle)
			)
			(primitives
				(gr_poly
					(pts
						(arc
							(start -0.1778 -0.2794)
							(mid -0.249642 -0.249642)
							(end -0.2794 -0.1778)
						)
						(arc
							(start -0.2794 0.1778)
							(mid -0.249642 0.249642)
							(end -0.1778 0.2794)
						)
						(arc
							(start 0.1778 0.2794)
							(mid 0.249642 0.249642)
							(end 0.2794 0.1778)
						)
						(arc
							(start 0.2794 -0.1778)
							(mid 0.249642 -0.249642)
							(end 0.1778 -0.2794)
						)
					)
					(width 0)
					(fill yes)
				)
			)
		)
	)
	(footprint ""
		(layer "F.Cu")
		(at 216.789 -491.6932 -90)
		(property "Reference" "R380"
			(at 0 0 270)
			(layer "F.SilkS")
			(hide yes)
			(effects
				(font
					(size 1.27 1.27)
				)
			)
		)
		(property "Value" "0R2J-2-GP"
			(at 0.064008 -3.993896 270)
			(unlocked yes)
			(layer "F.Fab")
			(hide yes)
			(effects
				(font
					(size 1.016 1.016)
					(thickness 0.1524)
				)
			)
		)
		(property "Device Type" "R402H16"
			(at 0.064008 -5.517896 270)
			(unlocked yes)
			(layer "F.Fab")
			(hide yes)
			(effects
				(font
					(size 1.016 1.016)
					(thickness 0.1524)
				)
			)
		)
		(duplicate_pad_numbers_are_jumpers no)
		(fp_line
			(start -0.508 -0.9398)
			(end -0.508 0.9398)
			(stroke
				(width 0.1524)
				(type default)
			)
			(layer "F.SilkS")
		)
		(fp_line
			(start 0.508 -0.9398)
			(end -0.508 -0.9398)
			(stroke
				(width 0.1524)
				(type default)
			)
			(layer "F.SilkS")
		)
		(fp_rect
			(start -0.508 0.9398)
			(end 0.508 -0.9398)
			(stroke
				(width 0)
				(type default)
			)
			(fill no)
			(layer "F.CrtYd")
		)
		(fp_rect
			(start -0.508 0.9398)
			(end 0.508 -0.9398)
			(stroke
				(width 0)
				(type default)
			)
			(fill no)
			(layer "F.Fab")
		)
		(pad "1" smd custom
			(at 0 -0.4445 270)
			(size 0.1397 0.1397)
			(layers "F.Cu" "F.Mask" "F.Paste")
			(net "SCL_DR0_R")
			(options
				(clearance outline)
				(anchor circle)
			)
			(primitives
				(gr_poly
					(pts
						(arc
							(start -0.1778 -0.2794)
							(mid -0.249642 -0.249642)
							(end -0.2794 -0.1778)
						)
						(arc
							(start -0.2794 0.1778)
							(mid -0.249642 0.249642)
							(end -0.1778 0.2794)
						)
						(arc
							(start 0.1778 0.2794)
							(mid 0.249642 0.249642)
							(end 0.2794 0.1778)
						)
						(arc
							(start 0.2794 -0.1778)
							(mid 0.249642 -0.249642)
							(end 0.1778 -0.2794)
						)
					)
					(width 0)
					(fill yes)
				)
			)
		)
		(pad "2" smd custom
			(at 0 0.4445 270)
			(size 0.1397 0.1397)
			(layers "F.Cu" "F.Mask" "F.Paste")
			(net "SCL_DR0")
			(options
				(clearance outline)
				(anchor circle)
			)
			(primitives
				(gr_poly
					(pts
						(arc
							(start -0.1778 -0.2794)
							(mid -0.249642 -0.249642)
							(end -0.2794 -0.1778)
						)
						(arc
							(start -0.2794 0.1778)
							(mid -0.249642 0.249642)
							(end -0.1778 0.2794)
						)
						(arc
							(start 0.1778 0.2794)
							(mid 0.249642 0.249642)
							(end 0.2794 0.1778)
						)
						(arc
							(start 0.2794 -0.1778)
							(mid 0.249642 -0.249642)
							(end 0.1778 -0.2794)
						)
					)
					(width 0)
					(fill yes)
				)
			)
		)
	)
	(footprint ""
		(layer "F.Cu")
		(at 87.503 -211.963 180)
		(property "Reference" "C8929"
			(at 0 0 180)
			(layer "F.SilkS")
			(hide yes)
			(effects
				(font
					(size 1.27 1.27)
				)
			)
		)
		(property "Value" "SCD1U16V2KX-3GP"
			(at 1.1811 -2.7051 180)
			(unlocked yes)
			(layer "F.Fab")
			(hide yes)
			(effects
				(font
					(size 1.016 1.016)
					(thickness 0.1524)
				)
			)
		)
		(property "Device Type" "C402H22"
			(at 1.1811 -4.2291 180)
			(unlocked yes)
			(layer "F.Fab")
			(hide yes)
			(effects
				(font
					(size 1.016 1.016)
					(thickness 0.1524)
				)
			)
		)
		(duplicate_pad_numbers_are_jumpers no)
		(fp_rect
			(start -0.4318 0.9525)
			(end 0.4318 -0.9525)
			(stroke
				(width 0)
				(type default)
			)
			(fill no)
			(layer "F.CrtYd")
		)
		(fp_rect
			(start -0.4318 0.9525)
			(end 0.4318 -0.9525)
			(stroke
				(width 0)
				(type default)
			)
			(fill no)
			(layer "F.Fab")
		)
		(pad "1" smd custom
			(at 0 -0.4445 180)
			(size 0.1524 0.1524)
			(layers "F.Cu" "F.Mask" "F.Paste")
			(net "VDDR_3")
			(options
				(clearance outline)
				(anchor circle)
			)
			(primitives
				(gr_poly
					(pts
						(arc
							(start 0.3048 -0.2032)
							(mid 0.275042 -0.275042)
							(end 0.2032 -0.3048)
						)
						(arc
							(start -0.2032 -0.3048)
							(mid -0.275042 -0.275042)
							(end -0.3048 -0.2032)
						)
						(arc
							(start -0.3048 0.2032)
							(mid -0.275042 0.275042)
							(end -0.2032 0.3048)
						)
						(arc
							(start 0.2032 0.3048)
							(mid 0.275042 0.275042)
							(end 0.3048 0.2032)
						)
					)
					(width 0)
					(fill yes)
				)
			)
		)
		(pad "2" smd custom
			(at 0 0.4445 180)
			(size 0.1524 0.1524)
			(layers "F.Cu" "F.Mask" "F.Paste")
			(net "GND")
			(options
				(clearance outline)
				(anchor circle)
			)
			(primitives
				(gr_poly
					(pts
						(arc
							(start 0.3048 -0.2032)
							(mid 0.275042 -0.275042)
							(end 0.2032 -0.3048)
						)
						(arc
							(start -0.2032 -0.3048)
							(mid -0.275042 -0.275042)
							(end -0.3048 -0.2032)
						)
						(arc
							(start -0.3048 0.2032)
							(mid -0.275042 0.275042)
							(end -0.2032 0.3048)
						)
						(arc
							(start 0.2032 0.3048)
							(mid 0.275042 0.275042)
							(end 0.3048 0.2032)
						)
					)
					(width 0)
					(fill yes)
				)
			)
		)
	)
	(footprint ""
		(layer "F.Cu")
		(at 40.321484 -248.157746 -90)
		(property "Reference" "R9942"
			(at 0 0 270)
			(layer "F.SilkS")
			(hide yes)
			(effects
				(font
					(size 1.27 1.27)
				)
			)
		)
		(property "Value" "4K7R2J-2-GP"
			(at 0.064008 -3.993896 270)
			(unlocked yes)
			(layer "F.Fab")
			(hide yes)
			(effects
				(font
					(size 1.016 1.016)
					(thickness 0.1524)
				)
			)
		)
		(property "Device Type" "R402H16"
			(at 0.064008 -5.517896 270)
			(unlocked yes)
			(layer "F.Fab")
			(hide yes)
			(effects
				(font
					(size 1.016 1.016)
					(thickness 0.1524)
				)
			)
		)
		(duplicate_pad_numbers_are_jumpers no)
		(fp_line
			(start -0.508 -0.9398)
			(end -0.508 0.9398)
			(stroke
				(width 0.1524)
				(type default)
			)
			(layer "F.SilkS")
		)
		(fp_line
			(start 0.508 -0.9398)
			(end -0.508 -0.9398)
			(stroke
				(width 0.1524)
				(type default)
			)
			(layer "F.SilkS")
		)
		(fp_rect
			(start -0.508 0.9398)
			(end 0.508 -0.9398)
			(stroke
				(width 0)
				(type default)
			)
			(fill no)
			(layer "F.CrtYd")
		)
		(fp_rect
			(start -0.508 0.9398)
			(end 0.508 -0.9398)
			(stroke
				(width 0)
				(type default)
			)
			(fill no)
			(layer "F.Fab")
		)
		(pad "1" smd custom
			(at 0 -0.4445 270)
			(size 0.1397 0.1397)
			(layers "F.Cu" "F.Mask" "F.Paste")
			(net "P3V3")
			(options
				(clearance outline)
				(anchor circle)
			)
			(primitives
				(gr_poly
					(pts
						(arc
							(start -0.1778 -0.2794)
							(mid -0.249642 -0.249642)
							(end -0.2794 -0.1778)
						)
						(arc
							(start -0.2794 0.1778)
							(mid -0.249642 0.249642)
							(end -0.1778 0.2794)
						)
						(arc
							(start 0.1778 0.2794)
							(mid 0.249642 0.249642)
							(end 0.2794 0.1778)
						)
						(arc
							(start 0.2794 -0.1778)
							(mid 0.249642 -0.249642)
							(end 0.1778 -0.2794)
						)
					)
					(width 0)
					(fill yes)
				)
			)
		)
		(pad "2" smd custom
			(at 0 0.4445 270)
			(size 0.1397 0.1397)
			(layers "F.Cu" "F.Mask" "F.Paste")
			(net "SSD_ACT_DR7_MOS_N")
			(options
				(clearance outline)
				(anchor circle)
			)
			(primitives
				(gr_poly
					(pts
						(arc
							(start -0.1778 -0.2794)
							(mid -0.249642 -0.249642)
							(end -0.2794 -0.1778)
						)
						(arc
							(start -0.2794 0.1778)
							(mid -0.249642 0.249642)
							(end -0.1778 0.2794)
						)
						(arc
							(start 0.1778 0.2794)
							(mid 0.249642 0.249642)
							(end 0.2794 0.1778)
						)
						(arc
							(start 0.2794 -0.1778)
							(mid 0.249642 -0.249642)
							(end 0.1778 -0.2794)
						)
					)
					(width 0)
					(fill yes)
				)
			)
		)
	)
	(footprint ""
		(layer "F.Cu")
		(at 106.045 -436.88 180)
		(property "Reference" "C111"
			(at 0 0 180)
			(layer "F.SilkS")
			(hide yes)
			(effects
				(font
					(size 1.27 1.27)
				)
			)
		)
		(property "Value" "SC1KP50V2KX-1GP"
			(at 1.1811 -2.7051 180)
			(unlocked yes)
			(layer "F.Fab")
			(hide yes)
			(effects
				(font
					(size 1.016 1.016)
					(thickness 0.1524)
				)
			)
		)
		(property "Device Type" "C402H22"
			(at 1.1811 -4.2291 180)
			(unlocked yes)
			(layer "F.Fab")
			(hide yes)
			(effects
				(font
					(size 1.016 1.016)
					(thickness 0.1524)
				)
			)
		)
		(duplicate_pad_numbers_are_jumpers no)
		(fp_rect
			(start -0.4318 0.9525)
			(end 0.4318 -0.9525)
			(stroke
				(width 0)
				(type default)
			)
			(fill no)
			(layer "F.CrtYd")
		)
		(fp_rect
			(start -0.4318 0.9525)
			(end 0.4318 -0.9525)
			(stroke
				(width 0)
				(type default)
			)
			(fill no)
			(layer "F.Fab")
		)
		(pad "1" smd custom
			(at 0 -0.4445 180)
			(size 0.1524 0.1524)
			(layers "F.Cu" "F.Mask" "F.Paste")
			(net "SSD0_CLK0_OE_R_N")
			(options
				(clearance outline)
				(anchor circle)
			)
			(primitives
				(gr_poly
					(pts
						(arc
							(start 0.3048 -0.2032)
							(mid 0.275042 -0.275042)
							(end 0.2032 -0.3048)
						)
						(arc
							(start -0.2032 -0.3048)
							(mid -0.275042 -0.275042)
							(end -0.3048 -0.2032)
						)
						(arc
							(start -0.3048 0.2032)
							(mid -0.275042 0.275042)
							(end -0.2032 0.3048)
						)
						(arc
							(start 0.2032 0.3048)
							(mid 0.275042 0.275042)
							(end 0.3048 0.2032)
						)
					)
					(width 0)
					(fill yes)
				)
			)
		)
		(pad "2" smd custom
			(at 0 0.4445 180)
			(size 0.1524 0.1524)
			(layers "F.Cu" "F.Mask" "F.Paste")
			(net "GND")
			(options
				(clearance outline)
				(anchor circle)
			)
			(primitives
				(gr_poly
					(pts
						(arc
							(start 0.3048 -0.2032)
							(mid 0.275042 -0.275042)
							(end 0.2032 -0.3048)
						)
						(arc
							(start -0.2032 -0.3048)
							(mid -0.275042 -0.275042)
							(end -0.3048 -0.2032)
						)
						(arc
							(start -0.3048 0.2032)
							(mid -0.275042 0.275042)
							(end -0.2032 0.3048)
						)
						(arc
							(start 0.2032 0.3048)
							(mid 0.275042 0.275042)
							(end 0.3048 0.2032)
						)
					)
					(width 0)
					(fill yes)
				)
			)
		)
	)
	(footprint ""
		(layer "F.Cu")
		(at 221.615 -165.354 180)
		(property "Reference" "PC1229"
			(at 0 0 180)
			(layer "F.SilkS")
			(hide yes)
			(effects
				(font
					(size 1.27 1.27)
				)
			)
		)
		(property "Value" "SCD1U25V3KX-GP"
			(at 0 -2.8194 180)
			(unlocked yes)
			(layer "F.Fab")
			(hide yes)
			(effects
				(font
					(size 1.016 1.016)
					(thickness 0.1524)
				)
			)
		)
		(property "Device Type" "C603H36"
			(at 0 -4.3434 180)
			(unlocked yes)
			(layer "F.Fab")
			(hide yes)
			(effects
				(font
					(size 1.016 1.016)
					(thickness 0.1524)
				)
			)
		)
		(duplicate_pad_numbers_are_jumpers no)
		(fp_line
			(start 0.508 0)
			(end -0.508 0)
			(stroke
				(width 0.2032)
				(type default)
			)
			(layer "F.SilkS")
		)
		(fp_rect
			(start -0.5842 1.3335)
			(end 0.5842 -1.3335)
			(stroke
				(width 0)
				(type default)
			)
			(fill no)
			(layer "F.CrtYd")
		)
		(fp_rect
			(start -0.5842 1.3335)
			(end 0.5842 -1.3335)
			(stroke
				(width 0)
				(type default)
			)
			(fill no)
			(layer "F.Fab")
		)
		(pad "1" smd custom
			(at 0 -0.762 180)
			(size 0.2159 0.2159)
			(layers "F.Cu" "F.Mask" "F.Paste")
			(net "P3V3")
			(options
				(clearance outline)
				(anchor circle)
			)
			(primitives
				(gr_poly
					(pts
						(arc
							(start -0.3302 -0.4318)
							(mid -0.402042 -0.402042)
							(end -0.4318 -0.3302)
						)
						(arc
							(start -0.4318 0.3302)
							(mid -0.402042 0.402042)
							(end -0.3302 0.4318)
						)
						(arc
							(start 0.3302 0.4318)
							(mid 0.402042 0.402042)
							(end 0.4318 0.3302)
						)
						(arc
							(start 0.4318 -0.3302)
							(mid 0.402042 -0.402042)
							(end 0.3302 -0.4318)
						)
					)
					(width 0)
					(fill yes)
				)
			)
		)
		(pad "2" smd custom
			(at 0 0.762 180)
			(size 0.2159 0.2159)
			(layers "F.Cu" "F.Mask" "F.Paste")
			(net "GND")
			(options
				(clearance outline)
				(anchor circle)
			)
			(primitives
				(gr_poly
					(pts
						(arc
							(start -0.3302 -0.4318)
							(mid -0.402042 -0.402042)
							(end -0.4318 -0.3302)
						)
						(arc
							(start -0.4318 0.3302)
							(mid -0.402042 0.402042)
							(end -0.3302 0.4318)
						)
						(arc
							(start 0.3302 0.4318)
							(mid 0.402042 0.402042)
							(end 0.4318 0.3302)
						)
						(arc
							(start 0.4318 -0.3302)
							(mid 0.402042 -0.402042)
							(end 0.3302 -0.4318)
						)
					)
					(width 0)
					(fill yes)
				)
			)
		)
	)
	(footprint ""
		(layer "F.Cu")
		(at 20.850098 -129.329942 -90)
		(property "Reference" "J13"
			(at 0 0 270)
			(layer "F.SilkS")
			(hide yes)
			(effects
				(font
					(size 1.27 1.27)
				)
			)
		)
		(property "Value" "PCISLT68-14-GP-U1"
			(at -22.225 12.7508 270)
			(unlocked yes)
			(layer "F.Fab")
			(hide yes)
			(effects
				(font
					(size 1.016 1.016)
					(thickness 0.1524)
				)
			)
		)
		(property "Device Type" "SD-78827-0001"
			(at -22.225 11.2268 270)
			(unlocked yes)
			(layer "F.Fab")
			(hide yes)
			(effects
				(font
					(size 1.016 1.016)
					(thickness 0.1524)
				)
			)
		)
		(duplicate_pad_numbers_are_jumpers no)
		(fp_line
			(start -20.4724 12.0142)
			(end -20.4724 4.6736)
			(stroke
				(width 0.1524)
				(type default)
			)
			(layer "F.SilkS")
		)
		(fp_line
			(start -17.8435 12.0142)
			(end -20.4724 12.0142)
			(stroke
				(width 0.1524)
				(type default)
			)
			(layer "F.SilkS")
		)
		(fp_line
			(start 17.8435 12.0142)
			(end 17.8435 10.3124)
			(stroke
				(width 0.1524)
				(type default)
			)
			(layer "F.SilkS")
		)
		(fp_line
			(start 20.4724 12.0142)
			(end 17.8435 12.0142)
			(stroke
				(width 0.1524)
				(type default)
			)
			(layer "F.SilkS")
		)
		(fp_line
			(start -17.8435 10.3124)
			(end -17.8435 12.0142)
			(stroke
				(width 0.1524)
				(type default)
			)
			(layer "F.SilkS")
		)
		(fp_line
			(start 17.8435 10.3124)
			(end -17.8435 10.3124)
			(stroke
				(width 0.1524)
				(type default)
			)
			(layer "F.SilkS")
		)
		(fp_line
			(start -23.749 4.6736)
			(end -23.749 0.0254)
			(stroke
				(width 0.1524)
				(type default)
			)
			(layer "F.SilkS")
		)
		(fp_line
			(start -20.4724 4.6736)
			(end -23.749 4.6736)
			(stroke
				(width 0.1524)
				(type default)
			)
			(layer "F.SilkS")
		)
		(fp_line
			(start 20.4724 4.6736)
			(end 20.4724 12.0142)
			(stroke
				(width 0.1524)
				(type default)
			)
			(layer "F.SilkS")
		)
		(fp_line
			(start 23.749 4.6736)
			(end 20.4724 4.6736)
			(stroke
				(width 0.1524)
				(type default)
			)
			(layer "F.SilkS")
		)
		(fp_line
			(start -23.117556 2.896108)
			(end -23.117556 1.803908)
			(stroke
				(width 0.3048)
				(type default)
			)
			(layer "F.SilkS")
		)
		(fp_line
			(start 20.882356 2.896108)
			(end 20.882356 1.803908)
			(stroke
				(width 0.3048)
				(type default)
			)
			(layer "F.SilkS")
		)
		(fp_line
			(start -20.882356 1.803908)
			(end -20.882356 2.896108)
			(stroke
				(width 0.3048)
				(type default)
			)
			(layer "F.SilkS")
		)
		(fp_line
			(start 23.117556 1.803908)
			(end 23.117556 2.896108)
			(stroke
				(width 0.3048)
				(type default)
			)
			(layer "F.SilkS")
		)
		(fp_line
			(start -23.749 0.0254)
			(end -20.4724 0.0254)
			(stroke
				(width 0.1524)
				(type default)
			)
			(layer "F.SilkS")
		)
		(fp_line
			(start -20.4724 0.0254)
			(end -20.4724 -3.4036)
			(stroke
				(width 0.1524)
				(type default)
			)
			(layer "F.SilkS")
		)
		(fp_line
			(start 20.4724 0.0254)
			(end 23.749 0.0254)
			(stroke
				(width 0.1524)
				(type default)
			)
			(layer "F.SilkS")
		)
		(fp_line
			(start 23.749 0.0254)
			(end 23.749 4.6736)
			(stroke
				(width 0.1524)
				(type default)
			)
			(layer "F.SilkS")
		)
		(fp_line
			(start -20.4724 -3.4036)
			(end 20.4724 -3.4036)
			(stroke
				(width 0.1524)
				(type default)
			)
			(layer "F.SilkS")
		)
		(fp_line
			(start 20.4724 -3.4036)
			(end 20.4724 0.0254)
			(stroke
				(width 0.1524)
				(type default)
			)
			(layer "F.SilkS")
		)
		(fp_arc
			(start -20.882356 2.896108)
			(mid -21.999956 4.013708)
			(end -23.117556 2.896108)
			(stroke
				(width 0.3048)
				(type default)
			)
			(layer "F.SilkS")
		)
		(fp_arc
			(start 23.117556 2.896108)
			(mid 21.999956 4.013708)
			(end 20.882356 2.896108)
			(stroke
				(width 0.3048)
				(type default)
			)
			(layer "F.SilkS")
		)
		(fp_arc
			(start -23.117556 1.803908)
			(mid -21.999956 0.686308)
			(end -20.882356 1.803908)
			(stroke
				(width 0.3048)
				(type default)
			)
			(layer "F.SilkS")
		)
		(fp_arc
			(start 20.882356 1.803908)
			(mid 21.999956 0.686308)
			(end 23.117556 1.803908)
			(stroke
				(width 0.3048)
				(type default)
			)
			(layer "F.SilkS")
		)
		(fp_poly
			(pts
				(xy -20.2184 11.7602) (xy -20.2184 4.4196) (xy -23.495 4.4196) (xy -23.495 0.2794) (xy -20.2184 0.2794)
				(xy -20.2184 -3.1496) (xy 20.2184 -3.1496) (xy 20.2184 0.2794) (xy 23.495 0.2794) (xy 23.495 4.4196)
				(xy 20.2184 4.4196) (xy 20.2184 11.7602) (xy 18.0975 11.7602) (xy 18.0975 10.0584) (xy -18.0975 10.0584)
				(xy -18.0975 11.7602)
			)
			(stroke
				(width 0)
				(type default)
			)
			(fill no)
			(layer "F.CrtYd")
		)
		(fp_poly
			(pts
				(xy -21.2471 16.256) (xy -21.2471 4.9276) (xy -24.003 4.9276) (xy -24.003 -0.2286) (xy -20.7264 -0.2286)
				(xy -20.7264 -3.6576) (xy 20.7264 -3.6576) (xy 20.7264 -0.2286) (xy 24.003 -0.2286) (xy 24.003 -0.00635)
				(xy 20.2184 -0.00635) (xy 20.2184 -3.1496) (xy -20.2184 -3.1496) (xy -20.2184 0.2794) (xy -23.495 0.2794)
				(xy -23.495 4.4196) (xy -20.2184 4.4196) (xy -20.2184 11.7602) (xy -18.0975 11.7602) (xy -18.0975 10.0584)
				(xy 18.0975 10.0584) (xy 18.0975 11.7602) (xy 20.2184 11.7602) (xy 20.2184 4.4196) (xy 23.495 4.4196)
				(xy 23.495 0.2794) (xy 20.2184 0.2794) (xy 20.2184 0.00635) (xy 24.003 0.00635) (xy 24.003 4.9276)
				(xy 21.2471 4.9276) (xy 21.2471 16.256)
			)
			(stroke
				(width 0)
				(type default)
			)
			(fill no)
			(layer "F.CrtYd")
		)
		(fp_poly
			(pts
				(xy -21.2471 16.256) (xy -21.2471 4.9276) (xy -24.003 4.9276) (xy -24.003 -0.2286) (xy -20.7264 -0.2286)
				(xy -20.7264 -3.6576) (xy 20.7264 -3.6576) (xy 20.7264 -0.2286) (xy 24.003 -0.2286) (xy 24.003 4.9276)
				(xy 21.2471 4.9276) (xy 21.2471 16.256)
			)
			(stroke
				(width 0)
				(type default)
			)
			(fill no)
			(layer "F.Fab")
		)
		(pad "" np_thru_hole circle
			(at -18.999962 0 270)
			(size 0.254 0.254)
			(drill 1.8542)
			(layers "*.Cu" "*.Mask")
			(clearance 1.1557)
			(thermal_gap 1.1557)
		)
		(pad "" np_thru_hole circle
			(at 18.999962 0 270)
			(size 0.254 0.254)
			(drill 1.8542)
			(layers "*.Cu" "*.Mask")
			(clearance 1.1557)
			(thermal_gap 1.1557)
		)
		(pad "E1" smd rect
			(at -7.079996 1.240028 270)
			(size 0.508 2.0066)
			(layers "F.Cu" "F.Mask" "F.Paste")
			(net "PE_CLK100M_DR13_2_P")
		)
		(pad "E2" smd rect
			(at -6.279896 1.240028 270)
			(size 0.508 2.0066)
			(layers "F.Cu" "F.Mask" "F.Paste")
			(net "PE_CLK100M_DR13_2_N")
		)
		(pad "E3" smd rect
			(at -5.48005 1.240028 270)
			(size 0.508 2.0066)
			(layers "F.Cu" "F.Mask" "F.Paste")
			(net "P3V3")
		)
		(pad "E4" smd rect
			(at -4.67995 1.240028 270)
			(size 0.508 2.0066)
			(layers "F.Cu" "F.Mask" "F.Paste")
			(net "SSD13_PERST_N")
		)
		(pad "E5" smd rect
			(at -3.880104 1.240028 270)
			(size 0.508 2.0066)
			(layers "F.Cu" "F.Mask" "F.Paste")
			(net "SSD13_PERST_N")
		)
		(pad "E6" smd rect
			(at -3.080004 1.240028 270)
			(size 0.508 2.0066)
			(layers "F.Cu" "F.Mask" "F.Paste")
			(net "Net_1233")
		)
		(pad "E7" smd rect
			(at -15.48003 -1.949958 270)
			(size 0.508 2.0066)
			(layers "F.Cu" "F.Mask" "F.Paste")
			(net "PE_CLK100M_DR13_1_P")
		)
		(pad "E8" smd rect
			(at -14.67993 -1.949958 270)
			(size 0.508 2.0066)
			(layers "F.Cu" "F.Mask" "F.Paste")
			(net "PE_CLK100M_DR13_1_N")
		)
		(pad "E9" smd rect
			(at -13.880084 -1.949958 270)
			(size 0.508 2.0066)
			(layers "F.Cu" "F.Mask" "F.Paste")
			(net "GND")
		)
		(pad "E10" smd rect
			(at -13.079984 -1.949958 270)
			(size 0.508 2.0066)
			(layers "F.Cu" "F.Mask" "F.Paste")
			(net "PE_TX1_DR13_N")
		)
		(pad "E11" smd rect
			(at -12.279884 -1.949958 270)
			(size 0.508 2.0066)
			(layers "F.Cu" "F.Mask" "F.Paste")
			(net "PE_TX1_DR13_P")
		)
		(pad "E12" smd rect
			(at -11.480038 -1.949958 270)
			(size 0.508 2.0066)
			(layers "F.Cu" "F.Mask" "F.Paste")
			(net "GND")
		)
		(pad "E13" smd rect
			(at -10.679938 -1.949958 270)
			(size 0.508 2.0066)
			(layers "F.Cu" "F.Mask" "F.Paste")
			(net "PE_RX1_DR13_N")
		)
		(pad "E14" smd rect
			(at -9.880092 -1.949958 270)
			(size 0.508 2.0066)
			(layers "F.Cu" "F.Mask" "F.Paste")
			(net "PE_RX1_DR13_P")
		)
		(pad "E15" smd rect
			(at -9.079992 -1.949958 270)
			(size 0.508 2.0066)
			(layers "F.Cu" "F.Mask" "F.Paste")
			(net "GND")
		)
		(pad "E16" smd rect
			(at -8.279892 -1.949958 270)
			(size 0.508 2.0066)
			(layers "F.Cu" "F.Mask" "F.Paste")
			(net "Net_1240")
		)
		(pad "E17" smd rect
			(at 9.320022 -1.949958 270)
			(size 0.508 2.0066)
			(layers "F.Cu" "F.Mask" "F.Paste")
			(net "PE_TX4_DR13_N")
		)
		(pad "E18" smd rect
			(at 10.120122 -1.949958 270)
			(size 0.508 2.0066)
			(layers "F.Cu" "F.Mask" "F.Paste")
			(net "PE_TX4_DR13_P")
		)
		(pad "E19" smd rect
			(at 10.919968 -1.949958 270)
			(size 0.508 2.0066)
			(layers "F.Cu" "F.Mask" "F.Paste")
			(net "GND")
		)
		(pad "E20" smd rect
			(at 11.720068 -1.949958 270)
			(size 0.508 2.0066)
			(layers "F.Cu" "F.Mask" "F.Paste")
			(net "PE_RX4_DR13_N")
		)
		(pad "E21" smd rect
			(at 12.519914 -1.949958 270)
			(size 0.508 2.0066)
			(layers "F.Cu" "F.Mask" "F.Paste")
			(net "PE_RX4_DR13_P")
		)
		(pad "E22" smd rect
			(at 13.320014 -1.949958 270)
			(size 0.508 2.0066)
			(layers "F.Cu" "F.Mask" "F.Paste")
			(net "GND")
		)
		(pad "E23" smd rect
			(at 14.120114 -1.949958 270)
			(size 0.508 2.0066)
			(layers "F.Cu" "F.Mask" "F.Paste")
			(net "SCL_DR13_R")
		)
		(pad "E24" smd rect
			(at 14.91996 -1.949958 270)
			(size 0.508 2.0066)
			(layers "F.Cu" "F.Mask" "F.Paste")
			(net "SDA_DR13_R")
		)
		(pad "E25" smd rect
			(at 15.72006 -1.949958 270)
			(size 0.508 2.0066)
			(layers "F.Cu" "F.Mask" "F.Paste")
			(net "DUALPORTEN#13")
		)
		(pad "P1" smd rect
			(at -1.905 0.824992 270)
			(size 0.6604 2.0574)
			(layers "F.Cu" "F.Mask" "F.Paste")
			(net "Net_1236")
		)
		(pad "P2" smd rect
			(at -0.635 0.824992 270)
			(size 0.6604 2.0574)
			(layers "F.Cu" "F.Mask" "F.Paste")
			(net "Net_1235")
		)
		(pad "P3" smd rect
			(at 0.635 0.824992 270)
			(size 0.6604 2.0574)
			(layers "F.Cu" "F.Mask" "F.Paste")
			(net "Net_1234")
		)
		(pad "P4" smd rect
			(at 1.905 0.824992 270)
			(size 0.6604 2.0574)
			(layers "F.Cu" "F.Mask" "F.Paste")
			(net "SSD13_CLK0_OE_N")
		)
		(pad "P5" smd rect
			(at 3.175 0.824992 270)
			(size 0.6604 2.0574)
			(layers "F.Cu" "F.Mask" "F.Paste")
			(net "GND")
		)
		(pad "P6" smd rect
			(at 4.445 0.824992 270)
			(size 0.6604 2.0574)
			(layers "F.Cu" "F.Mask" "F.Paste")
			(net "GND")
		)
		(pad "P7" smd rect
			(at 5.715 0.824992 270)
			(size 0.6604 2.0574)
			(layers "F.Cu" "F.Mask" "F.Paste")
			(net "Net_102")
		)
		(pad "P8" smd rect
			(at 6.985 0.824992 270)
			(size 0.6604 2.0574)
			(layers "F.Cu" "F.Mask" "F.Paste")
			(net "Net_74")
		)
		(pad "P9" smd rect
			(at 8.255 0.824992 270)
			(size 0.6604 2.0574)
			(layers "F.Cu" "F.Mask" "F.Paste")
			(net "Net_88")
		)
		(pad "P10" smd rect
			(at 9.525 0.824992 270)
			(size 0.6604 2.0574)
			(layers "F.Cu" "F.Mask" "F.Paste")
			(net "SSD_PRSNT_NET13")
		)
		(pad "P11" smd rect
			(at 10.795 0.824992 270)
			(size 0.6604 2.0574)
			(layers "F.Cu" "F.Mask" "F.Paste")
			(net "SSD_ACT_DR13")
		)
		(pad "P12" smd rect
			(at 12.065 0.824992 270)
			(size 0.6604 2.0574)
			(layers "F.Cu" "F.Mask" "F.Paste")
			(net "GND")
		)
		(pad "P13" smd rect
			(at 13.335 0.824992 270)
			(size 0.6604 2.0574)
			(layers "F.Cu" "F.Mask" "F.Paste")
			(net "12V_PRECH_SSD13")
		)
		(pad "P14" smd rect
			(at 14.605 0.824992 270)
			(size 0.6604 2.0574)
			(layers "F.Cu" "F.Mask" "F.Paste")
			(net "P12V_SSD13")
		)
		(pad "P15" smd rect
			(at 15.875 0.824992 270)
			(size 0.6604 2.0574)
			(layers "F.Cu" "F.Mask" "F.Paste")
			(net "P12V_SSD13")
		)
		(pad "PTH1" thru_hole oval
			(at -21.999956 2.350008 270)
			(size 1.524 2.6162)
			(drill oval 0.8128 1.905)
			(layers "*.Cu" "*.Mask")
			(remove_unused_layers no)
			(net "Net_1245")
			(clearance 0.1524)
			(thermal_gap 0.1524)
		)
		(pad "PTH2" thru_hole oval
			(at 21.999956 2.350008 270)
			(size 1.524 2.6162)
			(drill oval 0.8128 1.905)
			(layers "*.Cu" "*.Mask")
			(remove_unused_layers no)
			(net "Net_1229")
			(clearance 0.1524)
			(thermal_gap 0.1524)
		)
		(pad "S1" smd rect
			(at -15.875 0.824992 270)
			(size 0.6604 2.0574)
			(layers "F.Cu" "F.Mask" "F.Paste")
			(net "GND")
		)
		(pad "S2" smd rect
			(at -14.605 0.824992 270)
			(size 0.6604 2.0574)
			(layers "F.Cu" "F.Mask" "F.Paste")
			(net "Net_1244")
		)
		(pad "S3" smd rect
			(at -13.335 0.824992 270)
			(size 0.6604 2.0574)
			(layers "F.Cu" "F.Mask" "F.Paste")
			(net "Net_1243")
		)
		(pad "S4" smd rect
			(at -12.065 0.824992 270)
			(size 0.6604 2.0574)
			(layers "F.Cu" "F.Mask" "F.Paste")
			(net "GND")
		)
		(pad "S5" smd rect
			(at -10.795 0.824992 270)
			(size 0.6604 2.0574)
			(layers "F.Cu" "F.Mask" "F.Paste")
			(net "Net_1242")
		)
		(pad "S6" smd rect
			(at -9.525 0.824992 270)
			(size 0.6604 2.0574)
			(layers "F.Cu" "F.Mask" "F.Paste")
			(net "Net_1241")
		)
		(pad "S7" smd rect
			(at -8.255 0.824992 270)
			(size 0.6604 2.0574)
			(layers "F.Cu" "F.Mask" "F.Paste")
			(net "GND")
		)
		(pad "S8" smd rect
			(at -7.480046 -1.949958 270)
			(size 0.508 2.0066)
			(layers "F.Cu" "F.Mask" "F.Paste")
			(net "GND")
		)
		(pad "S9" smd rect
			(at -6.679946 -1.949958 270)
			(size 0.508 2.0066)
			(layers "F.Cu" "F.Mask" "F.Paste")
			(net "Net_1239")
		)
		(pad "S10" smd rect
			(at -5.8801 -1.949958 270)
			(size 0.508 2.0066)
			(layers "F.Cu" "F.Mask" "F.Paste")
			(net "Net_1238")
		)
		(pad "S11" smd rect
			(at -5.08 -1.949958 270)
			(size 0.508 2.0066)
			(layers "F.Cu" "F.Mask" "F.Paste")
			(net "GND")
		)
		(pad "S12" smd rect
			(at -4.2799 -1.949958 270)
			(size 0.508 2.0066)
			(layers "F.Cu" "F.Mask" "F.Paste")
			(net "Net_1237")
		)
		(pad "S13" smd rect
			(at -3.480054 -1.949958 270)
			(size 0.508 2.0066)
			(layers "F.Cu" "F.Mask" "F.Paste")
			(net "Net_1232")
		)
		(pad "S14" smd rect
			(at -2.679954 -1.949958 270)
			(size 0.508 2.0066)
			(layers "F.Cu" "F.Mask" "F.Paste")
			(net "GND")
		)
		(pad "S15" smd rect
			(at -1.880108 -1.949958 270)
			(size 0.508 2.0066)
			(layers "F.Cu" "F.Mask" "F.Paste")
			(net "Net_1231")
		)
		(pad "S16" smd rect
			(at -1.080008 -1.949958 270)
			(size 0.508 2.0066)
			(layers "F.Cu" "F.Mask" "F.Paste")
			(net "GND")
		)
		(pad "S17" smd rect
			(at -0.279908 -1.949958 270)
			(size 0.508 2.0066)
			(layers "F.Cu" "F.Mask" "F.Paste")
			(net "PE_TX2_DR13_N")
		)
		(pad "S18" smd rect
			(at 0.519938 -1.949958 270)
			(size 0.508 2.0066)
			(layers "F.Cu" "F.Mask" "F.Paste")
			(net "PE_TX2_DR13_P")
		)
		(pad "S19" smd rect
			(at 1.320038 -1.949958 270)
			(size 0.508 2.0066)
			(layers "F.Cu" "F.Mask" "F.Paste")
			(net "GND")
		)
		(pad "S20" smd rect
			(at 2.119884 -1.949958 270)
			(size 0.508 2.0066)
			(layers "F.Cu" "F.Mask" "F.Paste")
			(net "PE_RX2_DR13_N")
		)
		(pad "S21" smd rect
			(at 2.919984 -1.949958 270)
			(size 0.508 2.0066)
			(layers "F.Cu" "F.Mask" "F.Paste")
			(net "PE_RX2_DR13_P")
		)
		(pad "S22" smd rect
			(at 3.720084 -1.949958 270)
			(size 0.508 2.0066)
			(layers "F.Cu" "F.Mask" "F.Paste")
			(net "GND")
		)
		(pad "S23" smd rect
			(at 4.51993 -1.949958 270)
			(size 0.508 2.0066)
			(layers "F.Cu" "F.Mask" "F.Paste")
			(net "PE_TX3_DR13_N")
		)
		(pad "S24" smd rect
			(at 5.32003 -1.949958 270)
			(size 0.508 2.0066)
			(layers "F.Cu" "F.Mask" "F.Paste")
			(net "PE_TX3_DR13_P")
		)
		(pad "S25" smd rect
			(at 6.119876 -1.949958 270)
			(size 0.508 2.0066)
			(layers "F.Cu" "F.Mask" "F.Paste")
			(net "GND")
		)
		(pad "S26" smd rect
			(at 6.919976 -1.949958 270)
			(size 0.508 2.0066)
			(layers "F.Cu" "F.Mask" "F.Paste")
			(net "PE_RX3_DR13_N")
		)
		(pad "S27" smd rect
			(at 7.720076 -1.949958 270)
			(size 0.508 2.0066)
			(layers "F.Cu" "F.Mask" "F.Paste")
			(net "PE_RX3_DR13_P")
		)
		(pad "S28" smd rect
			(at 8.519922 -1.949958 270)
			(size 0.508 2.0066)
			(layers "F.Cu" "F.Mask" "F.Paste")
			(net "GND")
		)
		(zone
			(layers "F.Cu" "B.Cu" "In1.Cu" "In2.Cu" "In3.Cu" "In4.Cu" "In5.Cu" "In6.Cu")
			(hatch none 0.5)
			(connect_pads
				(clearance 0)
			)
			(min_thickness 0.25)
			(keepout
				(tracks not_allowed)
				(vias allowed)
				(pads allowed)
				(copperpour not_allowed)
				(footprints allowed)
			)
			(placement
				(enabled no)
				(sheetname "")
			)
			(fill
				(thermal_gap 0.5)
				(thermal_bridge_width 0.5)
				(island_removal_mode 0)
			)
			(polygon
				(pts
					(arc
						(start 22.081998 -148.329904)
						(mid 19.618198 -148.329904)
						(end 22.081998 -148.329904)
					)
				)
			)
		)
		(zone
			(layers "F.Cu" "B.Cu" "In1.Cu" "In2.Cu" "In3.Cu" "In4.Cu" "In5.Cu" "In6.Cu")
			(hatch none 0.5)
			(connect_pads
				(clearance 0)
			)
			(min_thickness 0.25)
			(keepout
				(tracks not_allowed)
				(vias allowed)
				(pads allowed)
				(copperpour not_allowed)
				(footprints allowed)
			)
			(placement
				(enabled no)
				(sheetname "")
			)
			(fill
				(thermal_gap 0.5)
				(thermal_bridge_width 0.5)
				(island_removal_mode 0)
			)
			(polygon
				(pts
					(arc
						(start 22.081998 -110.32998)
						(mid 19.618198 -110.32998)
						(end 22.081998 -110.32998)
					)
				)
			)
		)
	)
	(footprint ""
		(layer "F.Cu")
		(at 38.481 -245.745)
		(property "Reference" "Q63"
			(at 0 0 0)
			(layer "F.SilkS")
			(hide yes)
			(effects
				(font
					(size 1.27 1.27)
				)
			)
		)
		(property "Value" "2N7002A-7-GP"
			(at 0.127 -8.9662 0)
			(unlocked yes)
			(layer "F.Fab")
			(hide yes)
			(effects
				(font
					(size 1.016 1.016)
					(thickness 0.1524)
				)
			)
		)
		(property "Device Type" "SOT23DGS2D4H48"
			(at 0.127 -10.4902 0)
			(unlocked yes)
			(layer "F.Fab")
			(hide yes)
			(effects
				(font
					(size 1.016 1.016)
					(thickness 0.1524)
				)
			)
		)
		(duplicate_pad_numbers_are_jumpers no)
		(fp_line
			(start -1.651 -1.778)
			(end -1.651 1.778)
			(stroke
				(width 0.1524)
				(type default)
			)
			(layer "F.SilkS")
		)
		(fp_line
			(start -1.651 1.778)
			(end 1.651 1.778)
			(stroke
				(width 0.1524)
				(type default)
			)
			(layer "F.SilkS")
		)
		(fp_line
			(start 1.651 -1.778)
			(end -1.651 -1.778)
			(stroke
				(width 0.1524)
				(type default)
			)
			(layer "F.SilkS")
		)
		(fp_line
			(start 1.651 1.778)
			(end 1.651 -1.778)
			(stroke
				(width 0.1524)
				(type default)
			)
			(layer "F.SilkS")
		)
		(fp_poly
			(pts
				(xy -1.778 1.8796) (xy -1.778 -1.8796) (xy 1.778 -1.8796) (xy 1.778 1.8796)
			)
			(stroke
				(width 0)
				(type default)
			)
			(fill no)
			(layer "F.CrtYd")
		)
		(fp_poly
			(pts
				(xy -1.778 1.8796) (xy -1.778 -1.8796) (xy 1.778 -1.8796) (xy 1.778 1.8796)
			)
			(stroke
				(width 0)
				(type default)
			)
			(fill no)
			(layer "F.Fab")
		)
		(pad "D" smd custom
			(at 0 -0.9525)
			(size 0.1905 0.1905)
			(layers "F.Cu" "F.Mask" "F.Paste")
			(net "SSD_ACT_DR7_MOS_N")
			(options
				(clearance outline)
				(anchor circle)
			)
			(primitives
				(gr_poly
					(pts
						(arc
							(start -0.1778 0.5715)
							(mid -0.321484 0.511984)
							(end -0.381 0.3683)
						)
						(arc
							(start -0.381 -0.3683)
							(mid -0.321484 -0.511984)
							(end -0.1778 -0.5715)
						)
						(arc
							(start 0.1778 -0.5715)
							(mid 0.321484 -0.511984)
							(end 0.381 -0.3683)
						)
						(arc
							(start 0.381 0.3683)
							(mid 0.321484 0.511984)
							(end 0.1778 0.5715)
						)
					)
					(width 0)
					(fill yes)
				)
			)
		)
		(pad "G" smd custom
			(at -0.98425 0.9525)
			(size 0.1905 0.1905)
			(layers "F.Cu" "F.Mask" "F.Paste")
			(net "ATTN_LED_DR7_AND_R")
			(options
				(clearance outline)
				(anchor circle)
			)
			(primitives
				(gr_poly
					(pts
						(arc
							(start -0.1778 0.5715)
							(mid -0.321484 0.511984)
							(end -0.381 0.3683)
						)
						(arc
							(start -0.381 -0.3683)
							(mid -0.321484 -0.511984)
							(end -0.1778 -0.5715)
						)
						(arc
							(start 0.1778 -0.5715)
							(mid 0.321484 -0.511984)
							(end 0.381 -0.3683)
						)
						(arc
							(start 0.381 0.3683)
							(mid 0.321484 0.511984)
							(end 0.1778 0.5715)
						)
					)
					(width 0)
					(fill yes)
				)
			)
		)
		(pad "S" smd custom
			(at 0.98425 0.9525)
			(size 0.1905 0.1905)
			(layers "F.Cu" "F.Mask" "F.Paste")
			(net "SSD_ACT_DR7_R")
			(options
				(clearance outline)
				(anchor circle)
			)
			(primitives
				(gr_poly
					(pts
						(arc
							(start -0.1778 0.5715)
							(mid -0.321484 0.511984)
							(end -0.381 0.3683)
						)
						(arc
							(start -0.381 -0.3683)
							(mid -0.321484 -0.511984)
							(end -0.1778 -0.5715)
						)
						(arc
							(start 0.1778 -0.5715)
							(mid 0.321484 -0.511984)
							(end 0.381 -0.3683)
						)
						(arc
							(start 0.381 0.3683)
							(mid 0.321484 0.511984)
							(end 0.1778 0.5715)
						)
					)
					(width 0)
					(fill yes)
				)
			)
		)
	)
	(footprint ""
		(layer "F.Cu")
		(at 77.343 -211.2772 180)
		(property "Reference" "R9970"
			(at 0 0 180)
			(layer "F.SilkS")
			(hide yes)
			(effects
				(font
					(size 1.27 1.27)
				)
			)
		)
		(property "Value" "56R2F-1-GP"
			(at 0.064008 -3.993896 180)
			(unlocked yes)
			(layer "F.Fab")
			(hide yes)
			(effects
				(font
					(size 1.016 1.016)
					(thickness 0.1524)
				)
			)
		)
		(property "Device Type" "R402H16"
			(at 0.064008 -5.517896 180)
			(unlocked yes)
			(layer "F.Fab")
			(hide yes)
			(effects
				(font
					(size 1.016 1.016)
					(thickness 0.1524)
				)
			)
		)
		(duplicate_pad_numbers_are_jumpers no)
		(fp_line
			(start 0.508 -0.9398)
			(end -0.508 -0.9398)
			(stroke
				(width 0.1524)
				(type default)
			)
			(layer "F.SilkS")
		)
		(fp_line
			(start -0.508 -0.9398)
			(end -0.508 0.9398)
			(stroke
				(width 0.1524)
				(type default)
			)
			(layer "F.SilkS")
		)
		(fp_rect
			(start -0.508 0.9398)
			(end 0.508 -0.9398)
			(stroke
				(width 0)
				(type default)
			)
			(fill no)
			(layer "F.CrtYd")
		)
		(fp_rect
			(start -0.508 0.9398)
			(end 0.508 -0.9398)
			(stroke
				(width 0)
				(type default)
			)
			(fill no)
			(layer "F.Fab")
		)
		(pad "1" smd custom
			(at 0 -0.4445 180)
			(size 0.1397 0.1397)
			(layers "F.Cu" "F.Mask" "F.Paste")
			(net "PE_100M_CLK2_P")
			(options
				(clearance outline)
				(anchor circle)
			)
			(primitives
				(gr_poly
					(pts
						(arc
							(start -0.1778 -0.2794)
							(mid -0.249642 -0.249642)
							(end -0.2794 -0.1778)
						)
						(arc
							(start -0.2794 0.1778)
							(mid -0.249642 0.249642)
							(end -0.1778 0.2794)
						)
						(arc
							(start 0.1778 0.2794)
							(mid 0.249642 0.249642)
							(end 0.2794 0.1778)
						)
						(arc
							(start 0.2794 -0.1778)
							(mid 0.249642 -0.249642)
							(end 0.1778 -0.2794)
						)
					)
					(width 0)
					(fill yes)
				)
			)
		)
		(pad "2" smd custom
			(at 0 0.4445 180)
			(size 0.1397 0.1397)
			(layers "F.Cu" "F.Mask" "F.Paste")
			(net "GND")
			(options
				(clearance outline)
				(anchor circle)
			)
			(primitives
				(gr_poly
					(pts
						(arc
							(start -0.1778 -0.2794)
							(mid -0.249642 -0.249642)
							(end -0.2794 -0.1778)
						)
						(arc
							(start -0.2794 0.1778)
							(mid -0.249642 0.249642)
							(end -0.1778 0.2794)
						)
						(arc
							(start 0.1778 0.2794)
							(mid 0.249642 0.249642)
							(end 0.2794 0.1778)
						)
						(arc
							(start 0.2794 -0.1778)
							(mid 0.249642 -0.249642)
							(end 0.1778 -0.2794)
						)
					)
					(width 0)
					(fill yes)
				)
			)
		)
	)
	(footprint ""
		(layer "F.Cu")
		(at 217.043 -287.528 -90)
		(property "Reference" "R391"
			(at 0 0 270)
			(layer "F.SilkS")
			(hide yes)
			(effects
				(font
					(size 1.27 1.27)
				)
			)
		)
		(property "Value" "0R2J-2-GP"
			(at 0.064008 -3.993896 270)
			(unlocked yes)
			(layer "F.Fab")
			(hide yes)
			(effects
				(font
					(size 1.016 1.016)
					(thickness 0.1524)
				)
			)
		)
		(property "Device Type" "R402H16"
			(at 0.064008 -5.517896 270)
			(unlocked yes)
			(layer "F.Fab")
			(hide yes)
			(effects
				(font
					(size 1.016 1.016)
					(thickness 0.1524)
				)
			)
		)
		(duplicate_pad_numbers_are_jumpers no)
		(fp_line
			(start -0.508 -0.9398)
			(end -0.508 0.9398)
			(stroke
				(width 0.1524)
				(type default)
			)
			(layer "F.SilkS")
		)
		(fp_line
			(start 0.508 -0.9398)
			(end -0.508 -0.9398)
			(stroke
				(width 0.1524)
				(type default)
			)
			(layer "F.SilkS")
		)
		(fp_rect
			(start -0.508 0.9398)
			(end 0.508 -0.9398)
			(stroke
				(width 0)
				(type default)
			)
			(fill no)
			(layer "F.CrtYd")
		)
		(fp_rect
			(start -0.508 0.9398)
			(end 0.508 -0.9398)
			(stroke
				(width 0)
				(type default)
			)
			(fill no)
			(layer "F.Fab")
		)
		(pad "1" smd custom
			(at 0 -0.4445 270)
			(size 0.1397 0.1397)
			(layers "F.Cu" "F.Mask" "F.Paste")
			(net "SCL_DR2_R")
			(options
				(clearance outline)
				(anchor circle)
			)
			(primitives
				(gr_poly
					(pts
						(arc
							(start -0.1778 -0.2794)
							(mid -0.249642 -0.249642)
							(end -0.2794 -0.1778)
						)
						(arc
							(start -0.2794 0.1778)
							(mid -0.249642 0.249642)
							(end -0.1778 0.2794)
						)
						(arc
							(start 0.1778 0.2794)
							(mid 0.249642 0.249642)
							(end 0.2794 0.1778)
						)
						(arc
							(start 0.2794 -0.1778)
							(mid 0.249642 -0.249642)
							(end 0.1778 -0.2794)
						)
					)
					(width 0)
					(fill yes)
				)
			)
		)
		(pad "2" smd custom
			(at 0 0.4445 270)
			(size 0.1397 0.1397)
			(layers "F.Cu" "F.Mask" "F.Paste")
			(net "SCL_DR2")
			(options
				(clearance outline)
				(anchor circle)
			)
			(primitives
				(gr_poly
					(pts
						(arc
							(start -0.1778 -0.2794)
							(mid -0.249642 -0.249642)
							(end -0.2794 -0.1778)
						)
						(arc
							(start -0.2794 0.1778)
							(mid -0.249642 0.249642)
							(end -0.1778 0.2794)
						)
						(arc
							(start 0.1778 0.2794)
							(mid 0.249642 0.249642)
							(end 0.2794 0.1778)
						)
						(arc
							(start 0.2794 -0.1778)
							(mid 0.249642 -0.249642)
							(end 0.1778 -0.2794)
						)
					)
					(width 0)
					(fill yes)
				)
			)
		)
	)
	(footprint ""
		(layer "F.Cu")
		(at 101.727 -302.768 -90)
		(property "Reference" "R9512"
			(at 0 0 270)
			(layer "F.SilkS")
			(hide yes)
			(effects
				(font
					(size 1.27 1.27)
				)
			)
		)
		(property "Value" "4K7R2F-GP"
			(at 0.064008 -3.993896 270)
			(unlocked yes)
			(layer "F.Fab")
			(hide yes)
			(effects
				(font
					(size 1.016 1.016)
					(thickness 0.1524)
				)
			)
		)
		(property "Device Type" "R402H16"
			(at 0.064008 -5.517896 270)
			(unlocked yes)
			(layer "F.Fab")
			(hide yes)
			(effects
				(font
					(size 1.016 1.016)
					(thickness 0.1524)
				)
			)
		)
		(duplicate_pad_numbers_are_jumpers no)
		(fp_line
			(start -0.508 -0.9398)
			(end -0.508 0.9398)
			(stroke
				(width 0.1524)
				(type default)
			)
			(layer "F.SilkS")
		)
		(fp_line
			(start 0.508 -0.9398)
			(end -0.508 -0.9398)
			(stroke
				(width 0.1524)
				(type default)
			)
			(layer "F.SilkS")
		)
		(fp_rect
			(start -0.508 0.9398)
			(end 0.508 -0.9398)
			(stroke
				(width 0)
				(type default)
			)
			(fill no)
			(layer "F.CrtYd")
		)
		(fp_rect
			(start -0.508 0.9398)
			(end 0.508 -0.9398)
			(stroke
				(width 0)
				(type default)
			)
			(fill no)
			(layer "F.Fab")
		)
		(pad "1" smd custom
			(at 0 -0.4445 270)
			(size 0.1397 0.1397)
			(layers "F.Cu" "F.Mask" "F.Paste")
			(net "P3V3")
			(options
				(clearance outline)
				(anchor circle)
			)
			(primitives
				(gr_poly
					(pts
						(arc
							(start -0.1778 -0.2794)
							(mid -0.249642 -0.249642)
							(end -0.2794 -0.1778)
						)
						(arc
							(start -0.2794 0.1778)
							(mid -0.249642 0.249642)
							(end -0.1778 0.2794)
						)
						(arc
							(start 0.1778 0.2794)
							(mid 0.249642 0.249642)
							(end 0.2794 0.1778)
						)
						(arc
							(start 0.2794 -0.1778)
							(mid 0.249642 -0.249642)
							(end 0.1778 -0.2794)
						)
					)
					(width 0)
					(fill yes)
				)
			)
		)
		(pad "2" smd custom
			(at 0 0.4445 270)
			(size 0.1397 0.1397)
			(layers "F.Cu" "F.Mask" "F.Paste")
			(net "CLK_BUFFER_EU2_VOE_N")
			(options
				(clearance outline)
				(anchor circle)
			)
			(primitives
				(gr_poly
					(pts
						(arc
							(start -0.1778 -0.2794)
							(mid -0.249642 -0.249642)
							(end -0.2794 -0.1778)
						)
						(arc
							(start -0.2794 0.1778)
							(mid -0.249642 0.249642)
							(end -0.1778 0.2794)
						)
						(arc
							(start 0.1778 0.2794)
							(mid 0.249642 0.249642)
							(end 0.2794 0.1778)
						)
						(arc
							(start 0.2794 -0.1778)
							(mid 0.249642 -0.249642)
							(end 0.1778 -0.2794)
						)
					)
					(width 0)
					(fill yes)
				)
			)
		)
	)
	(footprint ""
		(layer "F.Cu")
		(at 93.345 -297.942)
		(property "Reference" "C9424"
			(at 0 0 0)
			(layer "F.SilkS")
			(hide yes)
			(effects
				(font
					(size 1.27 1.27)
				)
			)
		)
		(property "Value" "SCD1U16V2KX-3GP"
			(at 1.1811 -2.7051 0)
			(unlocked yes)
			(layer "F.Fab")
			(hide yes)
			(effects
				(font
					(size 1.016 1.016)
					(thickness 0.1524)
				)
			)
		)
		(property "Device Type" "C402H22"
			(at 1.1811 -4.2291 0)
			(unlocked yes)
			(layer "F.Fab")
			(hide yes)
			(effects
				(font
					(size 1.016 1.016)
					(thickness 0.1524)
				)
			)
		)
		(duplicate_pad_numbers_are_jumpers no)
		(fp_rect
			(start -0.4318 0.9525)
			(end 0.4318 -0.9525)
			(stroke
				(width 0)
				(type default)
			)
			(fill no)
			(layer "F.CrtYd")
		)
		(fp_rect
			(start -0.4318 0.9525)
			(end 0.4318 -0.9525)
			(stroke
				(width 0)
				(type default)
			)
			(fill no)
			(layer "F.Fab")
		)
		(pad "1" smd custom
			(at 0 -0.4445)
			(size 0.1524 0.1524)
			(layers "F.Cu" "F.Mask" "F.Paste")
			(net "VDD_DIFF_2")
			(options
				(clearance outline)
				(anchor circle)
			)
			(primitives
				(gr_poly
					(pts
						(arc
							(start 0.3048 -0.2032)
							(mid 0.275042 -0.275042)
							(end 0.2032 -0.3048)
						)
						(arc
							(start -0.2032 -0.3048)
							(mid -0.275042 -0.275042)
							(end -0.3048 -0.2032)
						)
						(arc
							(start -0.3048 0.2032)
							(mid -0.275042 0.275042)
							(end -0.2032 0.3048)
						)
						(arc
							(start 0.2032 0.3048)
							(mid 0.275042 0.275042)
							(end 0.3048 0.2032)
						)
					)
					(width 0)
					(fill yes)
				)
			)
		)
		(pad "2" smd custom
			(at 0 0.4445)
			(size 0.1524 0.1524)
			(layers "F.Cu" "F.Mask" "F.Paste")
			(net "GND")
			(options
				(clearance outline)
				(anchor circle)
			)
			(primitives
				(gr_poly
					(pts
						(arc
							(start 0.3048 -0.2032)
							(mid 0.275042 -0.275042)
							(end 0.2032 -0.3048)
						)
						(arc
							(start -0.2032 -0.3048)
							(mid -0.275042 -0.275042)
							(end -0.3048 -0.2032)
						)
						(arc
							(start -0.3048 0.2032)
							(mid -0.275042 0.275042)
							(end -0.2032 0.3048)
						)
						(arc
							(start 0.2032 0.3048)
							(mid 0.275042 0.275042)
							(end 0.3048 0.2032)
						)
					)
					(width 0)
					(fill yes)
				)
			)
		)
	)
	(footprint ""
		(layer "F.Cu")
		(at 93.98 -431.8 90)
		(property "Reference" "EU1"
			(at 0 0 90)
			(layer "F.SilkS")
			(hide yes)
			(effects
				(font
					(size 1.27 1.27)
				)
			)
		)
		(property "Value" "9ZXL1231AKLFT-GP"
			(at -6.5278 -7.2009 90)
			(unlocked yes)
			(layer "F.Fab")
			(hide yes)
			(effects
				(font
					(size 1.016 1.016)
					(thickness 0.1524)
				)
			)
		)
		(property "Device Type" "QFN64G9-G6D25H40"
			(at -6.5278 -8.7249 90)
			(unlocked yes)
			(layer "F.Fab")
			(hide yes)
			(effects
				(font
					(size 1.016 1.016)
					(thickness 0.1524)
				)
			)
		)
		(duplicate_pad_numbers_are_jumpers no)
		(fp_line
			(start 1.7526 -5.71881)
			(end 1.7526 -5.21081)
			(stroke
				(width 0.1524)
				(type default)
			)
			(layer "F.SilkS")
		)
		(fp_line
			(start -3.2639 -5.71881)
			(end -3.2639 -5.21081)
			(stroke
				(width 0.1524)
				(type default)
			)
			(layer "F.SilkS")
		)
		(fp_line
			(start -3.9878 -5.5118)
			(end -5.5118 -5.5118)
			(stroke
				(width 0.1524)
				(type default)
			)
			(layer "F.SilkS")
		)
		(fp_line
			(start -5.5118 -5.5118)
			(end -5.5118 -3.9243)
			(stroke
				(width 0.1524)
				(type default)
			)
			(layer "F.SilkS")
		)
		(fp_line
			(start -0.74041 -5.21081)
			(end -0.74041 -5.97281)
			(stroke
				(width 0.1524)
				(type default)
			)
			(layer "F.SilkS")
		)
		(fp_line
			(start -5.97281 -2.2606)
			(end -5.21081 -2.2606)
			(stroke
				(width 0.1524)
				(type default)
			)
			(layer "F.SilkS")
		)
		(fp_line
			(start 5.21081 -1.778)
			(end 5.97281 -1.778)
			(stroke
				(width 0.1524)
				(type default)
			)
			(layer "F.SilkS")
		)
		(fp_line
			(start -5.21081 0.254)
			(end -5.71881 0.254)
			(stroke
				(width 0.1524)
				(type default)
			)
			(layer "F.SilkS")
		)
		(fp_line
			(start 5.71881 0.7112)
			(end 5.21081 0.7112)
			(stroke
				(width 0.1524)
				(type default)
			)
			(layer "F.SilkS")
		)
		(fp_line
			(start -5.97281 2.7432)
			(end -5.21081 2.7432)
			(stroke
				(width 0.1524)
				(type default)
			)
			(layer "F.SilkS")
		)
		(fp_line
			(start 5.21081 3.22961)
			(end 5.97281 3.22961)
			(stroke
				(width 0.1524)
				(type default)
			)
			(layer "F.SilkS")
		)
		(fp_line
			(start -5.4991 4.1148)
			(end -5.4991 5.5118)
			(stroke
				(width 0.1524)
				(type default)
			)
			(layer "F.SilkS")
		)
		(fp_line
			(start 2.2352 5.21081)
			(end 2.2352 5.71881)
			(stroke
				(width 0.1524)
				(type default)
			)
			(layer "F.SilkS")
		)
		(fp_line
			(start -2.7432 5.21081)
			(end -2.7432 5.71881)
			(stroke
				(width 0.1524)
				(type default)
			)
			(layer "F.SilkS")
		)
		(fp_line
			(start 5.5118 5.4991)
			(end 5.5118 3.9878)
			(stroke
				(width 0.1524)
				(type default)
			)
			(layer "F.SilkS")
		)
		(fp_line
			(start 4.0767 5.4991)
			(end 5.5118 5.4991)
			(stroke
				(width 0.1524)
				(type default)
			)
			(layer "F.SilkS")
		)
		(fp_line
			(start -5.4991 5.5118)
			(end -4.2037 5.5118)
			(stroke
				(width 0.1524)
				(type default)
			)
			(layer "F.SilkS")
		)
		(fp_line
			(start -0.7366 5.97281)
			(end -0.7366 5.21081)
			(stroke
				(width 0.1524)
				(type default)
			)
			(layer "F.SilkS")
		)
		(fp_poly
			(pts
				(xy 5.481828 -4.084828) (xy 4.05511 -5.5118) (xy 5.481828 -5.5118)
			)
			(stroke
				(width 0)
				(type default)
			)
			(fill yes)
			(layer "F.SilkS")
		)
		(fp_rect
			(start -4.4958 4.4958)
			(end 4.4958 -4.4958)
			(stroke
				(width 0)
				(type default)
			)
			(fill no)
			(layer "F.CrtYd")
		)
		(fp_poly
			(pts
				(xy -5.5118 5.5118) (xy -5.5118 -5.5118) (xy 5.5118 -5.5118) (xy 5.5118 -0.5461) (xy 4.4958 -0.5461)
				(xy 4.4958 -4.4958) (xy -4.4958 -4.4958) (xy -4.4958 4.4958) (xy 4.4958 4.4958) (xy 4.4958 -0.5334)
				(xy 5.5118 -0.5334) (xy 5.5118 5.5118)
			)
			(stroke
				(width 0)
				(type default)
			)
			(fill no)
			(layer "F.CrtYd")
		)
		(fp_rect
			(start -5.5118 5.5118)
			(end 5.5118 -5.5118)
			(stroke
				(width 0)
				(type default)
			)
			(fill no)
			(layer "F.Fab")
		)
		(pad "1" smd rect
			(at 3.75031 -4.550918 90)
			(size 0.3048 0.9144)
			(layers "F.Cu" "F.Mask" "F.Paste")
			(net "VDDA_1")
		)
		(pad "2" smd rect
			(at 3.24993 -4.42341 90)
			(size 0.3048 1.1684)
			(layers "F.Cu" "F.Mask" "F.Paste")
			(net "GND")
		)
		(pad "3" smd rect
			(at 2.74955 -4.42341 90)
			(size 0.3048 1.1684)
			(layers "F.Cu" "F.Mask" "F.Paste")
			(net "Net_1332")
		)
		(pad "4" smd rect
			(at 2.25044 -4.42341 90)
			(size 0.3048 1.1684)
			(layers "F.Cu" "F.Mask" "F.Paste")
			(net "CLK_BUF_EU1_100M_133M#")
		)
		(pad "5" smd rect
			(at 1.75006 -4.42341 90)
			(size 0.3048 1.1684)
			(layers "F.Cu" "F.Mask" "F.Paste")
			(net "CLK_BUF_EU1_HIBW_BYPM_LOBW#")
		)
		(pad "6" smd rect
			(at 1.24968 -4.42341 90)
			(size 0.3048 1.1684)
			(layers "F.Cu" "F.Mask" "F.Paste")
			(net "P3V3_PG")
		)
		(pad "7" smd rect
			(at 0.75057 -4.42341 90)
			(size 0.3048 1.1684)
			(layers "F.Cu" "F.Mask" "F.Paste")
			(net "GND")
		)
		(pad "8" smd rect
			(at 0.25019 -4.42341 90)
			(size 0.3048 1.1684)
			(layers "F.Cu" "F.Mask" "F.Paste")
			(net "VDDR_1")
		)
		(pad "9" smd rect
			(at -0.25019 -4.42341 90)
			(size 0.3048 1.1684)
			(layers "F.Cu" "F.Mask" "F.Paste")
			(net "PE_100M_CLK4_P")
		)
		(pad "10" smd rect
			(at -0.75057 -4.42341 90)
			(size 0.3048 1.1684)
			(layers "F.Cu" "F.Mask" "F.Paste")
			(net "PE_100M_CLK4_N")
		)
		(pad "11" smd rect
			(at -1.24968 -4.42341 90)
			(size 0.3048 1.1684)
			(layers "F.Cu" "F.Mask" "F.Paste")
			(net "CLK_BUF_EU1_SMB_A0_TRI")
		)
		(pad "12" smd rect
			(at -1.75006 -4.42341 90)
			(size 0.3048 1.1684)
			(layers "F.Cu" "F.Mask" "F.Paste")
			(net "I2C_SDA_BUF_9_EU1_R")
		)
		(pad "13" smd rect
			(at -2.25044 -4.42341 90)
			(size 0.3048 1.1684)
			(layers "F.Cu" "F.Mask" "F.Paste")
			(net "I2C_SCL_BUF_9_EU1_R")
		)
		(pad "14" smd rect
			(at -2.74955 -4.42341 90)
			(size 0.3048 1.1684)
			(layers "F.Cu" "F.Mask" "F.Paste")
			(net "CLK_BUF_EU1_SMB_A1_TRI")
		)
		(pad "15" smd rect
			(at -3.24993 -4.42341 90)
			(size 0.3048 1.1684)
			(layers "F.Cu" "F.Mask" "F.Paste")
			(net "Net_1338")
		)
		(pad "16" smd rect
			(at -3.75031 -4.550918 90)
			(size 0.3048 0.9144)
			(layers "F.Cu" "F.Mask" "F.Paste")
			(net "Net_1337")
		)
		(pad "17" smd rect
			(at -4.550918 -3.75031 90)
			(size 0.9144 0.3048)
			(layers "F.Cu" "F.Mask" "F.Paste")
			(net "PE_CLK_100M_DR10_2_R_P")
		)
		(pad "18" smd rect
			(at -4.42341 -3.24993 90)
			(size 1.1684 0.3048)
			(layers "F.Cu" "F.Mask" "F.Paste")
			(net "PE_CLK_100M_DR10_2_R_N")
		)
		(pad "19" smd rect
			(at -4.42341 -2.74955 90)
			(size 1.1684 0.3048)
			(layers "F.Cu" "F.Mask" "F.Paste")
			(net "SSD_PRSNT10")
		)
		(pad "20" smd rect
			(at -4.42341 -2.25044 90)
			(size 1.1684 0.3048)
			(layers "F.Cu" "F.Mask" "F.Paste")
			(net "SSD10_CLK0_OE_R_N")
		)
		(pad "21" smd rect
			(at -4.42341 -1.75006 90)
			(size 1.1684 0.3048)
			(layers "F.Cu" "F.Mask" "F.Paste")
			(net "PE_CLK_100M_DR10_1_R_P")
		)
		(pad "22" smd rect
			(at -4.42341 -1.24968 90)
			(size 1.1684 0.3048)
			(layers "F.Cu" "F.Mask" "F.Paste")
			(net "PE_CLK_100M_DR10_1_R_N")
		)
		(pad "23" smd rect
			(at -4.42341 -0.75057 90)
			(size 1.1684 0.3048)
			(layers "F.Cu" "F.Mask" "F.Paste")
			(net "GND")
		)
		(pad "24" smd rect
			(at -4.42341 -0.25019 90)
			(size 1.1684 0.3048)
			(layers "F.Cu" "F.Mask" "F.Paste")
			(net "VDD_DIFF_1")
		)
		(pad "25" smd rect
			(at -4.42341 0.25019 90)
			(size 1.1684 0.3048)
			(layers "F.Cu" "F.Mask" "F.Paste")
			(net "VDD_IO_1")
		)
		(pad "26" smd rect
			(at -4.42341 0.75057 90)
			(size 1.1684 0.3048)
			(layers "F.Cu" "F.Mask" "F.Paste")
			(net "Net_307")
		)
		(pad "27" smd rect
			(at -4.42341 1.24968 90)
			(size 1.1684 0.3048)
			(layers "F.Cu" "F.Mask" "F.Paste")
			(net "Net_306")
		)
		(pad "28" smd rect
			(at -4.42341 1.75006 90)
			(size 1.1684 0.3048)
			(layers "F.Cu" "F.Mask" "F.Paste")
			(net "CLK_BUFFER_EU1_VOE_N")
		)
		(pad "29" smd rect
			(at -4.42341 2.25044 90)
			(size 1.1684 0.3048)
			(layers "F.Cu" "F.Mask" "F.Paste")
			(net "CLK_BUFFER_EU1_VOE_N")
		)
		(pad "30" smd rect
			(at -4.42341 2.74955 90)
			(size 1.1684 0.3048)
			(layers "F.Cu" "F.Mask" "F.Paste")
			(net "Net_305")
		)
		(pad "31" smd rect
			(at -4.42341 3.24993 90)
			(size 1.1684 0.3048)
			(layers "F.Cu" "F.Mask" "F.Paste")
			(net "Net_304")
		)
		(pad "32" smd rect
			(at -4.550918 3.75031 90)
			(size 0.9144 0.3048)
			(layers "F.Cu" "F.Mask" "F.Paste")
			(net "VDD_IO_1")
		)
		(pad "33" smd rect
			(at -3.75031 4.550918 90)
			(size 0.3048 0.9144)
			(layers "F.Cu" "F.Mask" "F.Paste")
			(net "GND")
		)
		(pad "34" smd rect
			(at -3.24993 4.42341 90)
			(size 0.3048 1.1684)
			(layers "F.Cu" "F.Mask" "F.Paste")
			(net "Net_323")
		)
		(pad "35" smd rect
			(at -2.74955 4.42341 90)
			(size 0.3048 1.1684)
			(layers "F.Cu" "F.Mask" "F.Paste")
			(net "Net_322")
		)
		(pad "36" smd rect
			(at -2.25044 4.42341 90)
			(size 0.3048 1.1684)
			(layers "F.Cu" "F.Mask" "F.Paste")
			(net "CLK_BUFFER_EU1_VOE_N")
		)
		(pad "37" smd rect
			(at -1.75006 4.42341 90)
			(size 0.3048 1.1684)
			(layers "F.Cu" "F.Mask" "F.Paste")
			(net "CLK_BUFFER_EU1_VOE_N")
		)
		(pad "38" smd rect
			(at -1.24968 4.42341 90)
			(size 0.3048 1.1684)
			(layers "F.Cu" "F.Mask" "F.Paste")
			(net "Net_321")
		)
		(pad "39" smd rect
			(at -0.75057 4.42341 90)
			(size 0.3048 1.1684)
			(layers "F.Cu" "F.Mask" "F.Paste")
			(net "Net_320")
		)
		(pad "40" smd rect
			(at -0.25019 4.42341 90)
			(size 0.3048 1.1684)
			(layers "F.Cu" "F.Mask" "F.Paste")
			(net "VDD_DIFF_1")
		)
		(pad "41" smd rect
			(at 0.25019 4.42341 90)
			(size 0.3048 1.1684)
			(layers "F.Cu" "F.Mask" "F.Paste")
			(net "GND")
		)
		(pad "42" smd rect
			(at 0.75057 4.42341 90)
			(size 0.3048 1.1684)
			(layers "F.Cu" "F.Mask" "F.Paste")
			(net "PE_CLK_100M_DR0_2_R_P")
		)
		(pad "43" smd rect
			(at 1.24968 4.42341 90)
			(size 0.3048 1.1684)
			(layers "F.Cu" "F.Mask" "F.Paste")
			(net "PE_CLK_100M_DR0_2_R_N")
		)
		(pad "44" smd rect
			(at 1.75006 4.42341 90)
			(size 0.3048 1.1684)
			(layers "F.Cu" "F.Mask" "F.Paste")
			(net "SSD_PRSNT0")
		)
		(pad "45" smd rect
			(at 2.25044 4.42341 90)
			(size 0.3048 1.1684)
			(layers "F.Cu" "F.Mask" "F.Paste")
			(net "SSD0_CLK0_OE_R_N")
		)
		(pad "46" smd rect
			(at 2.74955 4.42341 90)
			(size 0.3048 1.1684)
			(layers "F.Cu" "F.Mask" "F.Paste")
			(net "PE_CLK_100M_DR0_1_R_P")
		)
		(pad "47" smd rect
			(at 3.24993 4.42341 90)
			(size 0.3048 1.1684)
			(layers "F.Cu" "F.Mask" "F.Paste")
			(net "PE_CLK_100M_DR0_1_R_N")
		)
		(pad "48" smd rect
			(at 3.75031 4.550918 90)
			(size 0.3048 0.9144)
			(layers "F.Cu" "F.Mask" "F.Paste")
			(net "GND")
		)
		(pad "49" smd rect
			(at 4.550918 3.75031 90)
			(size 0.9144 0.3048)
			(layers "F.Cu" "F.Mask" "F.Paste")
			(net "VDD_IO_1")
		)
		(pad "50" smd rect
			(at 4.42341 3.24993 90)
			(size 1.1684 0.3048)
			(layers "F.Cu" "F.Mask" "F.Paste")
			(net "Net_1333")
		)
		(pad "51" smd rect
			(at 4.42341 2.74955 90)
			(size 1.1684 0.3048)
			(layers "F.Cu" "F.Mask" "F.Paste")
			(net "Net_1334")
		)
		(pad "52" smd rect
			(at 4.42341 2.25044 90)
			(size 1.1684 0.3048)
			(layers "F.Cu" "F.Mask" "F.Paste")
			(net "CLK_BUFFER_EU1_VOE_N")
		)
		(pad "53" smd rect
			(at 4.42341 1.75006 90)
			(size 1.1684 0.3048)
			(layers "F.Cu" "F.Mask" "F.Paste")
			(net "CLK_BUFFER_EU1_VOE_N")
		)
		(pad "54" smd rect
			(at 4.42341 1.24968 90)
			(size 1.1684 0.3048)
			(layers "F.Cu" "F.Mask" "F.Paste")
			(net "Net_1335")
		)
		(pad "55" smd rect
			(at 4.42341 0.75057 90)
			(size 1.1684 0.3048)
			(layers "F.Cu" "F.Mask" "F.Paste")
			(net "Net_1336")
		)
		(pad "56" smd rect
			(at 4.42341 0.25019 90)
			(size 1.1684 0.3048)
			(layers "F.Cu" "F.Mask" "F.Paste")
			(net "VDD_IO_1")
		)
		(pad "57" smd rect
			(at 4.42341 -0.25019 90)
			(size 1.1684 0.3048)
			(layers "F.Cu" "F.Mask" "F.Paste")
			(net "VDD_DIFF_1")
		)
		(pad "58" smd rect
			(at 4.42341 -0.75057 90)
			(size 1.1684 0.3048)
			(layers "F.Cu" "F.Mask" "F.Paste")
			(net "GND")
		)
		(pad "59" smd rect
			(at 4.42341 -1.24968 90)
			(size 1.1684 0.3048)
			(layers "F.Cu" "F.Mask" "F.Paste")
			(net "PE_CLK_100M_DR5_2_R_P")
		)
		(pad "60" smd rect
			(at 4.42341 -1.75006 90)
			(size 1.1684 0.3048)
			(layers "F.Cu" "F.Mask" "F.Paste")
			(net "PE_CLK_100M_DR5_2_R_N")
		)
		(pad "61" smd rect
			(at 4.42341 -2.25044 90)
			(size 1.1684 0.3048)
			(layers "F.Cu" "F.Mask" "F.Paste")
			(net "SSD_PRSNT5")
		)
		(pad "62" smd rect
			(at 4.42341 -2.74955 90)
			(size 1.1684 0.3048)
			(layers "F.Cu" "F.Mask" "F.Paste")
			(net "SSD5_CLK0_OE_R_N")
		)
		(pad "63" smd rect
			(at 4.42341 -3.24993 90)
			(size 1.1684 0.3048)
			(layers "F.Cu" "F.Mask" "F.Paste")
			(net "PE_CLK_100M_DR5_1_R_P")
		)
		(pad "64" smd rect
			(at 4.550918 -3.75031 90)
			(size 0.9144 0.3048)
			(layers "F.Cu" "F.Mask" "F.Paste")
			(net "PE_CLK_100M_DR5_1_R_N")
		)
		(pad "65" smd rect
			(at 0 0 90)
			(size 6.2484 6.2484)
			(layers "F.Cu" "F.Mask" "F.Paste")
			(net "GND")
		)
	)
	(footprint ""
		(layer "F.Cu")
		(at 233.045 -435.61 90)
		(property "Reference" "PR9079"
			(at 0 0 90)
			(layer "F.SilkS")
			(hide yes)
			(effects
				(font
					(size 1.27 1.27)
				)
			)
		)
		(property "Value" "10KR2F-2-GP"
			(at 0.064008 -3.993896 90)
			(unlocked yes)
			(layer "F.Fab")
			(hide yes)
			(effects
				(font
					(size 1.016 1.016)
					(thickness 0.1524)
				)
			)
		)
		(property "Device Type" "R402H16"
			(at 0.064008 -5.517896 90)
			(unlocked yes)
			(layer "F.Fab")
			(hide yes)
			(effects
				(font
					(size 1.016 1.016)
					(thickness 0.1524)
				)
			)
		)
		(duplicate_pad_numbers_are_jumpers no)
		(fp_line
			(start 0.508 -0.9398)
			(end -0.508 -0.9398)
			(stroke
				(width 0.1524)
				(type default)
			)
			(layer "F.SilkS")
		)
		(fp_line
			(start -0.508 -0.9398)
			(end -0.508 0.9398)
			(stroke
				(width 0.1524)
				(type default)
			)
			(layer "F.SilkS")
		)
		(fp_rect
			(start -0.508 0.9398)
			(end 0.508 -0.9398)
			(stroke
				(width 0)
				(type default)
			)
			(fill no)
			(layer "F.CrtYd")
		)
		(fp_rect
			(start -0.508 0.9398)
			(end 0.508 -0.9398)
			(stroke
				(width 0)
				(type default)
			)
			(fill no)
			(layer "F.Fab")
		)
		(pad "1" smd custom
			(at 0 -0.4445 90)
			(size 0.1397 0.1397)
			(layers "F.Cu" "F.Mask" "F.Paste")
			(net "P3V3_VRG5")
			(options
				(clearance outline)
				(anchor circle)
			)
			(primitives
				(gr_poly
					(pts
						(arc
							(start -0.1778 -0.2794)
							(mid -0.249642 -0.249642)
							(end -0.2794 -0.1778)
						)
						(arc
							(start -0.2794 0.1778)
							(mid -0.249642 0.249642)
							(end -0.1778 0.2794)
						)
						(arc
							(start 0.1778 0.2794)
							(mid 0.249642 0.249642)
							(end 0.2794 0.1778)
						)
						(arc
							(start 0.2794 -0.1778)
							(mid 0.249642 -0.249642)
							(end 0.1778 -0.2794)
						)
					)
					(width 0)
					(fill yes)
				)
			)
		)
		(pad "2" smd custom
			(at 0 0.4445 90)
			(size 0.1397 0.1397)
			(layers "F.Cu" "F.Mask" "F.Paste")
			(net "TPS53312_P3V3_PG")
			(options
				(clearance outline)
				(anchor circle)
			)
			(primitives
				(gr_poly
					(pts
						(arc
							(start -0.1778 -0.2794)
							(mid -0.249642 -0.249642)
							(end -0.2794 -0.1778)
						)
						(arc
							(start -0.2794 0.1778)
							(mid -0.249642 0.249642)
							(end -0.1778 0.2794)
						)
						(arc
							(start 0.1778 0.2794)
							(mid 0.249642 0.249642)
							(end 0.2794 0.1778)
						)
						(arc
							(start 0.2794 -0.1778)
							(mid 0.249642 -0.249642)
							(end 0.1778 -0.2794)
						)
					)
					(width 0)
					(fill yes)
				)
			)
		)
	)
	(footprint ""
		(layer "F.Cu")
		(at 228.219 -439.166)
		(property "Reference" "PR96"
			(at 0 0 0)
			(layer "F.SilkS")
			(hide yes)
			(effects
				(font
					(size 1.27 1.27)
				)
			)
		)
		(property "Value" "37K4R2F-1-GP"
			(at 0.064008 -3.993896 0)
			(unlocked yes)
			(layer "F.Fab")
			(hide yes)
			(effects
				(font
					(size 1.016 1.016)
					(thickness 0.1524)
				)
			)
		)
		(property "Device Type" "R402H16"
			(at 0.064008 -5.517896 0)
			(unlocked yes)
			(layer "F.Fab")
			(hide yes)
			(effects
				(font
					(size 1.016 1.016)
					(thickness 0.1524)
				)
			)
		)
		(duplicate_pad_numbers_are_jumpers no)
		(fp_line
			(start -0.508 -0.9398)
			(end -0.508 0.9398)
			(stroke
				(width 0.1524)
				(type default)
			)
			(layer "F.SilkS")
		)
		(fp_line
			(start 0.508 -0.9398)
			(end -0.508 -0.9398)
			(stroke
				(width 0.1524)
				(type default)
			)
			(layer "F.SilkS")
		)
		(fp_rect
			(start -0.508 0.9398)
			(end 0.508 -0.9398)
			(stroke
				(width 0)
				(type default)
			)
			(fill no)
			(layer "F.CrtYd")
		)
		(fp_rect
			(start -0.508 0.9398)
			(end 0.508 -0.9398)
			(stroke
				(width 0)
				(type default)
			)
			(fill no)
			(layer "F.Fab")
		)
		(pad "1" smd custom
			(at 0 -0.4445)
			(size 0.1397 0.1397)
			(layers "F.Cu" "F.Mask" "F.Paste")
			(net "P12V")
			(options
				(clearance outline)
				(anchor circle)
			)
			(primitives
				(gr_poly
					(pts
						(arc
							(start -0.1778 -0.2794)
							(mid -0.249642 -0.249642)
							(end -0.2794 -0.1778)
						)
						(arc
							(start -0.2794 0.1778)
							(mid -0.249642 0.249642)
							(end -0.1778 0.2794)
						)
						(arc
							(start 0.1778 0.2794)
							(mid 0.249642 0.249642)
							(end 0.2794 0.1778)
						)
						(arc
							(start 0.2794 -0.1778)
							(mid 0.249642 -0.249642)
							(end 0.1778 -0.2794)
						)
					)
					(width 0)
					(fill yes)
				)
			)
		)
		(pad "2" smd custom
			(at 0 0.4445)
			(size 0.1397 0.1397)
			(layers "F.Cu" "F.Mask" "F.Paste")
			(net "P3V3_EN_R")
			(options
				(clearance outline)
				(anchor circle)
			)
			(primitives
				(gr_poly
					(pts
						(arc
							(start -0.1778 -0.2794)
							(mid -0.249642 -0.249642)
							(end -0.2794 -0.1778)
						)
						(arc
							(start -0.2794 0.1778)
							(mid -0.249642 0.249642)
							(end -0.1778 0.2794)
						)
						(arc
							(start 0.1778 0.2794)
							(mid 0.249642 0.249642)
							(end 0.2794 0.1778)
						)
						(arc
							(start 0.2794 -0.1778)
							(mid 0.249642 -0.249642)
							(end 0.1778 -0.2794)
						)
					)
					(width 0)
					(fill yes)
				)
			)
		)
	)
	(footprint ""
		(layer "F.Cu")
		(at 78.3844 -209.3722 180)
		(property "Reference" "R9967"
			(at 0 0 180)
			(layer "F.SilkS")
			(hide yes)
			(effects
				(font
					(size 1.27 1.27)
				)
			)
		)
		(property "Value" "470R2F-GP"
			(at 0.064008 -3.993896 180)
			(unlocked yes)
			(layer "F.Fab")
			(hide yes)
			(effects
				(font
					(size 1.016 1.016)
					(thickness 0.1524)
				)
			)
		)
		(property "Device Type" "R402H16"
			(at 0.064008 -5.517896 180)
			(unlocked yes)
			(layer "F.Fab")
			(hide yes)
			(effects
				(font
					(size 1.016 1.016)
					(thickness 0.1524)
				)
			)
		)
		(duplicate_pad_numbers_are_jumpers no)
		(fp_line
			(start 0.508 -0.9398)
			(end -0.508 -0.9398)
			(stroke
				(width 0.1524)
				(type default)
			)
			(layer "F.SilkS")
		)
		(fp_line
			(start -0.508 -0.9398)
			(end -0.508 0.9398)
			(stroke
				(width 0.1524)
				(type default)
			)
			(layer "F.SilkS")
		)
		(fp_rect
			(start -0.508 0.9398)
			(end 0.508 -0.9398)
			(stroke
				(width 0)
				(type default)
			)
			(fill no)
			(layer "F.CrtYd")
		)
		(fp_rect
			(start -0.508 0.9398)
			(end 0.508 -0.9398)
			(stroke
				(width 0)
				(type default)
			)
			(fill no)
			(layer "F.Fab")
		)
		(pad "1" smd custom
			(at 0 -0.4445 180)
			(size 0.1397 0.1397)
			(layers "F.Cu" "F.Mask" "F.Paste")
			(net "VDD_DIFF_3")
			(options
				(clearance outline)
				(anchor circle)
			)
			(primitives
				(gr_poly
					(pts
						(arc
							(start -0.1778 -0.2794)
							(mid -0.249642 -0.249642)
							(end -0.2794 -0.1778)
						)
						(arc
							(start -0.2794 0.1778)
							(mid -0.249642 0.249642)
							(end -0.1778 0.2794)
						)
						(arc
							(start 0.1778 0.2794)
							(mid 0.249642 0.249642)
							(end 0.2794 0.1778)
						)
						(arc
							(start 0.2794 -0.1778)
							(mid 0.249642 -0.249642)
							(end 0.1778 -0.2794)
						)
					)
					(width 0)
					(fill yes)
				)
			)
		)
		(pad "2" smd custom
			(at 0 0.4445 180)
			(size 0.1397 0.1397)
			(layers "F.Cu" "F.Mask" "F.Paste")
			(net "PE_100M_CLK2_N")
			(options
				(clearance outline)
				(anchor circle)
			)
			(primitives
				(gr_poly
					(pts
						(arc
							(start -0.1778 -0.2794)
							(mid -0.249642 -0.249642)
							(end -0.2794 -0.1778)
						)
						(arc
							(start -0.2794 0.1778)
							(mid -0.249642 0.249642)
							(end -0.1778 0.2794)
						)
						(arc
							(start 0.1778 0.2794)
							(mid 0.249642 0.249642)
							(end 0.2794 0.1778)
						)
						(arc
							(start 0.2794 -0.1778)
							(mid 0.249642 -0.249642)
							(end 0.1778 -0.2794)
						)
					)
					(width 0)
					(fill yes)
				)
			)
		)
	)
	(footprint ""
		(layer "F.Cu")
		(at 210.312 -396.113)
		(property "Reference" "C383"
			(at 0 0 0)
			(layer "F.SilkS")
			(hide yes)
			(effects
				(font
					(size 1.27 1.27)
				)
			)
		)
		(property "Value" "SCD1U25V2KX-2-GP"
			(at 1.1811 -2.7051 0)
			(unlocked yes)
			(layer "F.Fab")
			(hide yes)
			(effects
				(font
					(size 1.016 1.016)
					(thickness 0.1524)
				)
			)
		)
		(property "Device Type" "C402H22"
			(at 1.1811 -4.2291 0)
			(unlocked yes)
			(layer "F.Fab")
			(hide yes)
			(effects
				(font
					(size 1.016 1.016)
					(thickness 0.1524)
				)
			)
		)
		(duplicate_pad_numbers_are_jumpers no)
		(fp_rect
			(start -0.4318 0.9525)
			(end 0.4318 -0.9525)
			(stroke
				(width 0)
				(type default)
			)
			(fill no)
			(layer "F.CrtYd")
		)
		(fp_rect
			(start -0.4318 0.9525)
			(end 0.4318 -0.9525)
			(stroke
				(width 0)
				(type default)
			)
			(fill no)
			(layer "F.Fab")
		)
		(pad "1" smd custom
			(at 0 -0.4445)
			(size 0.1524 0.1524)
			(layers "F.Cu" "F.Mask" "F.Paste")
			(net "P12V")
			(options
				(clearance outline)
				(anchor circle)
			)
			(primitives
				(gr_poly
					(pts
						(arc
							(start 0.3048 -0.2032)
							(mid 0.275042 -0.275042)
							(end 0.2032 -0.3048)
						)
						(arc
							(start -0.2032 -0.3048)
							(mid -0.275042 -0.275042)
							(end -0.3048 -0.2032)
						)
						(arc
							(start -0.3048 0.2032)
							(mid -0.275042 0.275042)
							(end -0.2032 0.3048)
						)
						(arc
							(start 0.2032 0.3048)
							(mid 0.275042 0.275042)
							(end 0.3048 0.2032)
						)
					)
					(width 0)
					(fill yes)
				)
			)
		)
		(pad "2" smd custom
			(at 0 0.4445)
			(size 0.1524 0.1524)
			(layers "F.Cu" "F.Mask" "F.Paste")
			(net "SW_SSD1_N")
			(options
				(clearance outline)
				(anchor circle)
			)
			(primitives
				(gr_poly
					(pts
						(arc
							(start 0.3048 -0.2032)
							(mid 0.275042 -0.275042)
							(end 0.2032 -0.3048)
						)
						(arc
							(start -0.2032 -0.3048)
							(mid -0.275042 -0.275042)
							(end -0.3048 -0.2032)
						)
						(arc
							(start -0.3048 0.2032)
							(mid -0.275042 0.275042)
							(end -0.2032 0.3048)
						)
						(arc
							(start 0.2032 0.3048)
							(mid 0.275042 0.275042)
							(end 0.3048 0.2032)
						)
					)
					(width 0)
					(fill yes)
				)
			)
		)
	)
	(footprint ""
		(layer "F.Cu")
		(at 212.471 -44.704)
		(property "Reference" "R336"
			(at 0 0 0)
			(layer "F.SilkS")
			(hide yes)
			(effects
				(font
					(size 1.27 1.27)
				)
			)
		)
		(property "Value" "4K7R2J-2-GP"
			(at 0.064008 -3.993896 0)
			(unlocked yes)
			(layer "F.Fab")
			(hide yes)
			(effects
				(font
					(size 1.016 1.016)
					(thickness 0.1524)
				)
			)
		)
		(property "Device Type" "R402H16"
			(at 0.064008 -5.517896 0)
			(unlocked yes)
			(layer "F.Fab")
			(hide yes)
			(effects
				(font
					(size 1.016 1.016)
					(thickness 0.1524)
				)
			)
		)
		(duplicate_pad_numbers_are_jumpers no)
		(fp_line
			(start -0.508 -0.9398)
			(end -0.508 0.9398)
			(stroke
				(width 0.1524)
				(type default)
			)
			(layer "F.SilkS")
		)
		(fp_line
			(start 0.508 -0.9398)
			(end -0.508 -0.9398)
			(stroke
				(width 0.1524)
				(type default)
			)
			(layer "F.SilkS")
		)
		(fp_rect
			(start -0.508 0.9398)
			(end 0.508 -0.9398)
			(stroke
				(width 0)
				(type default)
			)
			(fill no)
			(layer "F.CrtYd")
		)
		(fp_rect
			(start -0.508 0.9398)
			(end 0.508 -0.9398)
			(stroke
				(width 0)
				(type default)
			)
			(fill no)
			(layer "F.Fab")
		)
		(pad "1" smd custom
			(at 0 -0.4445)
			(size 0.1397 0.1397)
			(layers "F.Cu" "F.Mask" "F.Paste")
			(net "I2C_B_TMP3_A2")
			(options
				(clearance outline)
				(anchor circle)
			)
			(primitives
				(gr_poly
					(pts
						(arc
							(start -0.1778 -0.2794)
							(mid -0.249642 -0.249642)
							(end -0.2794 -0.1778)
						)
						(arc
							(start -0.2794 0.1778)
							(mid -0.249642 0.249642)
							(end -0.1778 0.2794)
						)
						(arc
							(start 0.1778 0.2794)
							(mid 0.249642 0.249642)
							(end 0.2794 0.1778)
						)
						(arc
							(start 0.2794 -0.1778)
							(mid 0.249642 -0.249642)
							(end 0.1778 -0.2794)
						)
					)
					(width 0)
					(fill yes)
				)
			)
		)
		(pad "2" smd custom
			(at 0 0.4445)
			(size 0.1397 0.1397)
			(layers "F.Cu" "F.Mask" "F.Paste")
			(net "GND")
			(options
				(clearance outline)
				(anchor circle)
			)
			(primitives
				(gr_poly
					(pts
						(arc
							(start -0.1778 -0.2794)
							(mid -0.249642 -0.249642)
							(end -0.2794 -0.1778)
						)
						(arc
							(start -0.2794 0.1778)
							(mid -0.249642 0.249642)
							(end -0.1778 0.2794)
						)
						(arc
							(start 0.1778 0.2794)
							(mid 0.249642 0.249642)
							(end 0.2794 0.1778)
						)
						(arc
							(start 0.2794 -0.1778)
							(mid 0.249642 -0.249642)
							(end 0.1778 -0.2794)
						)
					)
					(width 0)
					(fill yes)
				)
			)
		)
	)
	(footprint ""
		(layer "F.Cu")
		(at 20.850098 -335.330038 -90)
		(property "Reference" "J11"
			(at 0 0 270)
			(layer "F.SilkS")
			(hide yes)
			(effects
				(font
					(size 1.27 1.27)
				)
			)
		)
		(property "Value" "PCISLT68-14-GP-U1"
			(at -22.225 12.7508 270)
			(unlocked yes)
			(layer "F.Fab")
			(hide yes)
			(effects
				(font
					(size 1.016 1.016)
					(thickness 0.1524)
				)
			)
		)
		(property "Device Type" "SD-78827-0001"
			(at -22.225 11.2268 270)
			(unlocked yes)
			(layer "F.Fab")
			(hide yes)
			(effects
				(font
					(size 1.016 1.016)
					(thickness 0.1524)
				)
			)
		)
		(duplicate_pad_numbers_are_jumpers no)
		(fp_line
			(start -20.4724 12.0142)
			(end -20.4724 4.6736)
			(stroke
				(width 0.1524)
				(type default)
			)
			(layer "F.SilkS")
		)
		(fp_line
			(start -17.8435 12.0142)
			(end -20.4724 12.0142)
			(stroke
				(width 0.1524)
				(type default)
			)
			(layer "F.SilkS")
		)
		(fp_line
			(start 17.8435 12.0142)
			(end 17.8435 10.3124)
			(stroke
				(width 0.1524)
				(type default)
			)
			(layer "F.SilkS")
		)
		(fp_line
			(start 20.4724 12.0142)
			(end 17.8435 12.0142)
			(stroke
				(width 0.1524)
				(type default)
			)
			(layer "F.SilkS")
		)
		(fp_line
			(start -17.8435 10.3124)
			(end -17.8435 12.0142)
			(stroke
				(width 0.1524)
				(type default)
			)
			(layer "F.SilkS")
		)
		(fp_line
			(start 17.8435 10.3124)
			(end -17.8435 10.3124)
			(stroke
				(width 0.1524)
				(type default)
			)
			(layer "F.SilkS")
		)
		(fp_line
			(start -23.749 4.6736)
			(end -23.749 0.0254)
			(stroke
				(width 0.1524)
				(type default)
			)
			(layer "F.SilkS")
		)
		(fp_line
			(start -20.4724 4.6736)
			(end -23.749 4.6736)
			(stroke
				(width 0.1524)
				(type default)
			)
			(layer "F.SilkS")
		)
		(fp_line
			(start 20.4724 4.6736)
			(end 20.4724 12.0142)
			(stroke
				(width 0.1524)
				(type default)
			)
			(layer "F.SilkS")
		)
		(fp_line
			(start 23.749 4.6736)
			(end 20.4724 4.6736)
			(stroke
				(width 0.1524)
				(type default)
			)
			(layer "F.SilkS")
		)
		(fp_line
			(start -23.117556 2.896108)
			(end -23.117556 1.803908)
			(stroke
				(width 0.3048)
				(type default)
			)
			(layer "F.SilkS")
		)
		(fp_line
			(start 20.882356 2.896108)
			(end 20.882356 1.803908)
			(stroke
				(width 0.3048)
				(type default)
			)
			(layer "F.SilkS")
		)
		(fp_line
			(start -20.882356 1.803908)
			(end -20.882356 2.896108)
			(stroke
				(width 0.3048)
				(type default)
			)
			(layer "F.SilkS")
		)
		(fp_line
			(start 23.117556 1.803908)
			(end 23.117556 2.896108)
			(stroke
				(width 0.3048)
				(type default)
			)
			(layer "F.SilkS")
		)
		(fp_line
			(start -23.749 0.0254)
			(end -20.4724 0.0254)
			(stroke
				(width 0.1524)
				(type default)
			)
			(layer "F.SilkS")
		)
		(fp_line
			(start -20.4724 0.0254)
			(end -20.4724 -3.4036)
			(stroke
				(width 0.1524)
				(type default)
			)
			(layer "F.SilkS")
		)
		(fp_line
			(start 20.4724 0.0254)
			(end 23.749 0.0254)
			(stroke
				(width 0.1524)
				(type default)
			)
			(layer "F.SilkS")
		)
		(fp_line
			(start 23.749 0.0254)
			(end 23.749 4.6736)
			(stroke
				(width 0.1524)
				(type default)
			)
			(layer "F.SilkS")
		)
		(fp_line
			(start -20.4724 -3.4036)
			(end 20.4724 -3.4036)
			(stroke
				(width 0.1524)
				(type default)
			)
			(layer "F.SilkS")
		)
		(fp_line
			(start 20.4724 -3.4036)
			(end 20.4724 0.0254)
			(stroke
				(width 0.1524)
				(type default)
			)
			(layer "F.SilkS")
		)
		(fp_arc
			(start -20.882356 2.896108)
			(mid -21.999956 4.013708)
			(end -23.117556 2.896108)
			(stroke
				(width 0.3048)
				(type default)
			)
			(layer "F.SilkS")
		)
		(fp_arc
			(start 23.117556 2.896108)
			(mid 21.999956 4.013708)
			(end 20.882356 2.896108)
			(stroke
				(width 0.3048)
				(type default)
			)
			(layer "F.SilkS")
		)
		(fp_arc
			(start -23.117556 1.803908)
			(mid -21.999956 0.686308)
			(end -20.882356 1.803908)
			(stroke
				(width 0.3048)
				(type default)
			)
			(layer "F.SilkS")
		)
		(fp_arc
			(start 20.882356 1.803908)
			(mid 21.999956 0.686308)
			(end 23.117556 1.803908)
			(stroke
				(width 0.3048)
				(type default)
			)
			(layer "F.SilkS")
		)
		(fp_poly
			(pts
				(xy -20.2184 11.7602) (xy -20.2184 4.4196) (xy -23.495 4.4196) (xy -23.495 0.2794) (xy -20.2184 0.2794)
				(xy -20.2184 -3.1496) (xy 20.2184 -3.1496) (xy 20.2184 0.2794) (xy 23.495 0.2794) (xy 23.495 4.4196)
				(xy 20.2184 4.4196) (xy 20.2184 11.7602) (xy 18.0975 11.7602) (xy 18.0975 10.0584) (xy -18.0975 10.0584)
				(xy -18.0975 11.7602)
			)
			(stroke
				(width 0)
				(type default)
			)
			(fill no)
			(layer "F.CrtYd")
		)
		(fp_poly
			(pts
				(xy -21.2471 16.256) (xy -21.2471 4.9276) (xy -24.003 4.9276) (xy -24.003 -0.2286) (xy -20.7264 -0.2286)
				(xy -20.7264 -3.6576) (xy 20.7264 -3.6576) (xy 20.7264 -0.2286) (xy 24.003 -0.2286) (xy 24.003 -0.00635)
				(xy 20.2184 -0.00635) (xy 20.2184 -3.1496) (xy -20.2184 -3.1496) (xy -20.2184 0.2794) (xy -23.495 0.2794)
				(xy -23.495 4.4196) (xy -20.2184 4.4196) (xy -20.2184 11.7602) (xy -18.0975 11.7602) (xy -18.0975 10.0584)
				(xy 18.0975 10.0584) (xy 18.0975 11.7602) (xy 20.2184 11.7602) (xy 20.2184 4.4196) (xy 23.495 4.4196)
				(xy 23.495 0.2794) (xy 20.2184 0.2794) (xy 20.2184 0.00635) (xy 24.003 0.00635) (xy 24.003 4.9276)
				(xy 21.2471 4.9276) (xy 21.2471 16.256)
			)
			(stroke
				(width 0)
				(type default)
			)
			(fill no)
			(layer "F.CrtYd")
		)
		(fp_poly
			(pts
				(xy -21.2471 16.256) (xy -21.2471 4.9276) (xy -24.003 4.9276) (xy -24.003 -0.2286) (xy -20.7264 -0.2286)
				(xy -20.7264 -3.6576) (xy 20.7264 -3.6576) (xy 20.7264 -0.2286) (xy 24.003 -0.2286) (xy 24.003 4.9276)
				(xy 21.2471 4.9276) (xy 21.2471 16.256)
			)
			(stroke
				(width 0)
				(type default)
			)
			(fill no)
			(layer "F.Fab")
		)
		(pad "" np_thru_hole circle
			(at -18.999962 0 270)
			(size 0.254 0.254)
			(drill 1.8542)
			(layers "*.Cu" "*.Mask")
			(clearance 1.1557)
			(thermal_gap 1.1557)
		)
		(pad "" np_thru_hole circle
			(at 18.999962 0 270)
			(size 0.254 0.254)
			(drill 1.8542)
			(layers "*.Cu" "*.Mask")
			(clearance 1.1557)
			(thermal_gap 1.1557)
		)
		(pad "E1" smd rect
			(at -7.079996 1.240028 270)
			(size 0.508 2.0066)
			(layers "F.Cu" "F.Mask" "F.Paste")
			(net "PE_CLK100M_DR11_2_P")
		)
		(pad "E2" smd rect
			(at -6.279896 1.240028 270)
			(size 0.508 2.0066)
			(layers "F.Cu" "F.Mask" "F.Paste")
			(net "PE_CLK100M_DR11_2_N")
		)
		(pad "E3" smd rect
			(at -5.48005 1.240028 270)
			(size 0.508 2.0066)
			(layers "F.Cu" "F.Mask" "F.Paste")
			(net "P3V3")
		)
		(pad "E4" smd rect
			(at -4.67995 1.240028 270)
			(size 0.508 2.0066)
			(layers "F.Cu" "F.Mask" "F.Paste")
			(net "SSD11_PERST_N")
		)
		(pad "E5" smd rect
			(at -3.880104 1.240028 270)
			(size 0.508 2.0066)
			(layers "F.Cu" "F.Mask" "F.Paste")
			(net "SSD11_PERST_N")
		)
		(pad "E6" smd rect
			(at -3.080004 1.240028 270)
			(size 0.508 2.0066)
			(layers "F.Cu" "F.Mask" "F.Paste")
			(net "Net_1269")
		)
		(pad "E7" smd rect
			(at -15.48003 -1.949958 270)
			(size 0.508 2.0066)
			(layers "F.Cu" "F.Mask" "F.Paste")
			(net "PE_CLK100M_DR11_1_P")
		)
		(pad "E8" smd rect
			(at -14.67993 -1.949958 270)
			(size 0.508 2.0066)
			(layers "F.Cu" "F.Mask" "F.Paste")
			(net "PE_CLK100M_DR11_1_N")
		)
		(pad "E9" smd rect
			(at -13.880084 -1.949958 270)
			(size 0.508 2.0066)
			(layers "F.Cu" "F.Mask" "F.Paste")
			(net "GND")
		)
		(pad "E10" smd rect
			(at -13.079984 -1.949958 270)
			(size 0.508 2.0066)
			(layers "F.Cu" "F.Mask" "F.Paste")
			(net "PE_TX1_DR11_N")
		)
		(pad "E11" smd rect
			(at -12.279884 -1.949958 270)
			(size 0.508 2.0066)
			(layers "F.Cu" "F.Mask" "F.Paste")
			(net "PE_TX1_DR11_P")
		)
		(pad "E12" smd rect
			(at -11.480038 -1.949958 270)
			(size 0.508 2.0066)
			(layers "F.Cu" "F.Mask" "F.Paste")
			(net "GND")
		)
		(pad "E13" smd rect
			(at -10.679938 -1.949958 270)
			(size 0.508 2.0066)
			(layers "F.Cu" "F.Mask" "F.Paste")
			(net "PE_RX1_DR11_N")
		)
		(pad "E14" smd rect
			(at -9.880092 -1.949958 270)
			(size 0.508 2.0066)
			(layers "F.Cu" "F.Mask" "F.Paste")
			(net "PE_RX1_DR11_P")
		)
		(pad "E15" smd rect
			(at -9.079992 -1.949958 270)
			(size 0.508 2.0066)
			(layers "F.Cu" "F.Mask" "F.Paste")
			(net "GND")
		)
		(pad "E16" smd rect
			(at -8.279892 -1.949958 270)
			(size 0.508 2.0066)
			(layers "F.Cu" "F.Mask" "F.Paste")
			(net "Net_1276")
		)
		(pad "E17" smd rect
			(at 9.320022 -1.949958 270)
			(size 0.508 2.0066)
			(layers "F.Cu" "F.Mask" "F.Paste")
			(net "PE_TX4_DR11_N")
		)
		(pad "E18" smd rect
			(at 10.120122 -1.949958 270)
			(size 0.508 2.0066)
			(layers "F.Cu" "F.Mask" "F.Paste")
			(net "PE_TX4_DR11_P")
		)
		(pad "E19" smd rect
			(at 10.919968 -1.949958 270)
			(size 0.508 2.0066)
			(layers "F.Cu" "F.Mask" "F.Paste")
			(net "GND")
		)
		(pad "E20" smd rect
			(at 11.720068 -1.949958 270)
			(size 0.508 2.0066)
			(layers "F.Cu" "F.Mask" "F.Paste")
			(net "PE_RX4_DR11_N")
		)
		(pad "E21" smd rect
			(at 12.519914 -1.949958 270)
			(size 0.508 2.0066)
			(layers "F.Cu" "F.Mask" "F.Paste")
			(net "PE_RX4_DR11_P")
		)
		(pad "E22" smd rect
			(at 13.320014 -1.949958 270)
			(size 0.508 2.0066)
			(layers "F.Cu" "F.Mask" "F.Paste")
			(net "GND")
		)
		(pad "E23" smd rect
			(at 14.120114 -1.949958 270)
			(size 0.508 2.0066)
			(layers "F.Cu" "F.Mask" "F.Paste")
			(net "SCL_DR11_R")
		)
		(pad "E24" smd rect
			(at 14.91996 -1.949958 270)
			(size 0.508 2.0066)
			(layers "F.Cu" "F.Mask" "F.Paste")
			(net "SDA_DR11_R")
		)
		(pad "E25" smd rect
			(at 15.72006 -1.949958 270)
			(size 0.508 2.0066)
			(layers "F.Cu" "F.Mask" "F.Paste")
			(net "DUALPORTEN#11")
		)
		(pad "P1" smd rect
			(at -1.905 0.824992 270)
			(size 0.6604 2.0574)
			(layers "F.Cu" "F.Mask" "F.Paste")
			(net "Net_1272")
		)
		(pad "P2" smd rect
			(at -0.635 0.824992 270)
			(size 0.6604 2.0574)
			(layers "F.Cu" "F.Mask" "F.Paste")
			(net "Net_1271")
		)
		(pad "P3" smd rect
			(at 0.635 0.824992 270)
			(size 0.6604 2.0574)
			(layers "F.Cu" "F.Mask" "F.Paste")
			(net "Net_1270")
		)
		(pad "P4" smd rect
			(at 1.905 0.824992 270)
			(size 0.6604 2.0574)
			(layers "F.Cu" "F.Mask" "F.Paste")
			(net "SSD11_CLK0_OE_N")
		)
		(pad "P5" smd rect
			(at 3.175 0.824992 270)
			(size 0.6604 2.0574)
			(layers "F.Cu" "F.Mask" "F.Paste")
			(net "GND")
		)
		(pad "P6" smd rect
			(at 4.445 0.824992 270)
			(size 0.6604 2.0574)
			(layers "F.Cu" "F.Mask" "F.Paste")
			(net "GND")
		)
		(pad "P7" smd rect
			(at 5.715 0.824992 270)
			(size 0.6604 2.0574)
			(layers "F.Cu" "F.Mask" "F.Paste")
			(net "Net_99")
		)
		(pad "P8" smd rect
			(at 6.985 0.824992 270)
			(size 0.6604 2.0574)
			(layers "F.Cu" "F.Mask" "F.Paste")
			(net "Net_72")
		)
		(pad "P9" smd rect
			(at 8.255 0.824992 270)
			(size 0.6604 2.0574)
			(layers "F.Cu" "F.Mask" "F.Paste")
			(net "Net_86")
		)
		(pad "P10" smd rect
			(at 9.525 0.824992 270)
			(size 0.6604 2.0574)
			(layers "F.Cu" "F.Mask" "F.Paste")
			(net "SSD_PRSNT_NET11")
		)
		(pad "P11" smd rect
			(at 10.795 0.824992 270)
			(size 0.6604 2.0574)
			(layers "F.Cu" "F.Mask" "F.Paste")
			(net "SSD_ACT_DR11")
		)
		(pad "P12" smd rect
			(at 12.065 0.824992 270)
			(size 0.6604 2.0574)
			(layers "F.Cu" "F.Mask" "F.Paste")
			(net "GND")
		)
		(pad "P13" smd rect
			(at 13.335 0.824992 270)
			(size 0.6604 2.0574)
			(layers "F.Cu" "F.Mask" "F.Paste")
			(net "12V_PRECH_SSD11")
		)
		(pad "P14" smd rect
			(at 14.605 0.824992 270)
			(size 0.6604 2.0574)
			(layers "F.Cu" "F.Mask" "F.Paste")
			(net "P12V_SSD11")
		)
		(pad "P15" smd rect
			(at 15.875 0.824992 270)
			(size 0.6604 2.0574)
			(layers "F.Cu" "F.Mask" "F.Paste")
			(net "P12V_SSD11")
		)
		(pad "PTH1" thru_hole oval
			(at -21.999956 2.350008 270)
			(size 1.524 2.6162)
			(drill oval 0.8128 1.905)
			(layers "*.Cu" "*.Mask")
			(remove_unused_layers no)
			(net "Net_1281")
			(clearance 0.1524)
			(thermal_gap 0.1524)
		)
		(pad "PTH2" thru_hole oval
			(at 21.999956 2.350008 270)
			(size 1.524 2.6162)
			(drill oval 0.8128 1.905)
			(layers "*.Cu" "*.Mask")
			(remove_unused_layers no)
			(net "Net_1265")
			(clearance 0.1524)
			(thermal_gap 0.1524)
		)
		(pad "S1" smd rect
			(at -15.875 0.824992 270)
			(size 0.6604 2.0574)
			(layers "F.Cu" "F.Mask" "F.Paste")
			(net "GND")
		)
		(pad "S2" smd rect
			(at -14.605 0.824992 270)
			(size 0.6604 2.0574)
			(layers "F.Cu" "F.Mask" "F.Paste")
			(net "Net_1280")
		)
		(pad "S3" smd rect
			(at -13.335 0.824992 270)
			(size 0.6604 2.0574)
			(layers "F.Cu" "F.Mask" "F.Paste")
			(net "Net_1279")
		)
		(pad "S4" smd rect
			(at -12.065 0.824992 270)
			(size 0.6604 2.0574)
			(layers "F.Cu" "F.Mask" "F.Paste")
			(net "GND")
		)
		(pad "S5" smd rect
			(at -10.795 0.824992 270)
			(size 0.6604 2.0574)
			(layers "F.Cu" "F.Mask" "F.Paste")
			(net "Net_1278")
		)
		(pad "S6" smd rect
			(at -9.525 0.824992 270)
			(size 0.6604 2.0574)
			(layers "F.Cu" "F.Mask" "F.Paste")
			(net "Net_1277")
		)
		(pad "S7" smd rect
			(at -8.255 0.824992 270)
			(size 0.6604 2.0574)
			(layers "F.Cu" "F.Mask" "F.Paste")
			(net "GND")
		)
		(pad "S8" smd rect
			(at -7.480046 -1.949958 270)
			(size 0.508 2.0066)
			(layers "F.Cu" "F.Mask" "F.Paste")
			(net "GND")
		)
		(pad "S9" smd rect
			(at -6.679946 -1.949958 270)
			(size 0.508 2.0066)
			(layers "F.Cu" "F.Mask" "F.Paste")
			(net "Net_1275")
		)
		(pad "S10" smd rect
			(at -5.8801 -1.949958 270)
			(size 0.508 2.0066)
			(layers "F.Cu" "F.Mask" "F.Paste")
			(net "Net_1274")
		)
		(pad "S11" smd rect
			(at -5.08 -1.949958 270)
			(size 0.508 2.0066)
			(layers "F.Cu" "F.Mask" "F.Paste")
			(net "GND")
		)
		(pad "S12" smd rect
			(at -4.2799 -1.949958 270)
			(size 0.508 2.0066)
			(layers "F.Cu" "F.Mask" "F.Paste")
			(net "Net_1273")
		)
		(pad "S13" smd rect
			(at -3.480054 -1.949958 270)
			(size 0.508 2.0066)
			(layers "F.Cu" "F.Mask" "F.Paste")
			(net "Net_1268")
		)
		(pad "S14" smd rect
			(at -2.679954 -1.949958 270)
			(size 0.508 2.0066)
			(layers "F.Cu" "F.Mask" "F.Paste")
			(net "GND")
		)
		(pad "S15" smd rect
			(at -1.880108 -1.949958 270)
			(size 0.508 2.0066)
			(layers "F.Cu" "F.Mask" "F.Paste")
			(net "Net_1267")
		)
		(pad "S16" smd rect
			(at -1.080008 -1.949958 270)
			(size 0.508 2.0066)
			(layers "F.Cu" "F.Mask" "F.Paste")
			(net "GND")
		)
		(pad "S17" smd rect
			(at -0.279908 -1.949958 270)
			(size 0.508 2.0066)
			(layers "F.Cu" "F.Mask" "F.Paste")
			(net "PE_TX2_DR11_N")
		)
		(pad "S18" smd rect
			(at 0.519938 -1.949958 270)
			(size 0.508 2.0066)
			(layers "F.Cu" "F.Mask" "F.Paste")
			(net "PE_TX2_DR11_P")
		)
		(pad "S19" smd rect
			(at 1.320038 -1.949958 270)
			(size 0.508 2.0066)
			(layers "F.Cu" "F.Mask" "F.Paste")
			(net "GND")
		)
		(pad "S20" smd rect
			(at 2.119884 -1.949958 270)
			(size 0.508 2.0066)
			(layers "F.Cu" "F.Mask" "F.Paste")
			(net "PE_RX2_DR11_N")
		)
		(pad "S21" smd rect
			(at 2.919984 -1.949958 270)
			(size 0.508 2.0066)
			(layers "F.Cu" "F.Mask" "F.Paste")
			(net "PE_RX2_DR11_P")
		)
		(pad "S22" smd rect
			(at 3.720084 -1.949958 270)
			(size 0.508 2.0066)
			(layers "F.Cu" "F.Mask" "F.Paste")
			(net "GND")
		)
		(pad "S23" smd rect
			(at 4.51993 -1.949958 270)
			(size 0.508 2.0066)
			(layers "F.Cu" "F.Mask" "F.Paste")
			(net "PE_TX3_DR11_N")
		)
		(pad "S24" smd rect
			(at 5.32003 -1.949958 270)
			(size 0.508 2.0066)
			(layers "F.Cu" "F.Mask" "F.Paste")
			(net "PE_TX3_DR11_P")
		)
		(pad "S25" smd rect
			(at 6.119876 -1.949958 270)
			(size 0.508 2.0066)
			(layers "F.Cu" "F.Mask" "F.Paste")
			(net "GND")
		)
		(pad "S26" smd rect
			(at 6.919976 -1.949958 270)
			(size 0.508 2.0066)
			(layers "F.Cu" "F.Mask" "F.Paste")
			(net "PE_RX3_DR11_N")
		)
		(pad "S27" smd rect
			(at 7.720076 -1.949958 270)
			(size 0.508 2.0066)
			(layers "F.Cu" "F.Mask" "F.Paste")
			(net "PE_RX3_DR11_P")
		)
		(pad "S28" smd rect
			(at 8.519922 -1.949958 270)
			(size 0.508 2.0066)
			(layers "F.Cu" "F.Mask" "F.Paste")
			(net "GND")
		)
		(zone
			(layers "F.Cu" "B.Cu" "In1.Cu" "In2.Cu" "In3.Cu" "In4.Cu" "In5.Cu" "In6.Cu")
			(hatch none 0.5)
			(connect_pads
				(clearance 0)
			)
			(min_thickness 0.25)
			(keepout
				(tracks not_allowed)
				(vias allowed)
				(pads allowed)
				(copperpour not_allowed)
				(footprints allowed)
			)
			(placement
				(enabled no)
				(sheetname "")
			)
			(fill
				(thermal_gap 0.5)
				(thermal_bridge_width 0.5)
				(island_removal_mode 0)
			)
			(polygon
				(pts
					(arc
						(start 22.081998 -354.33)
						(mid 19.618198 -354.33)
						(end 22.081998 -354.33)
					)
				)
			)
		)
		(zone
			(layers "F.Cu" "B.Cu" "In1.Cu" "In2.Cu" "In3.Cu" "In4.Cu" "In5.Cu" "In6.Cu")
			(hatch none 0.5)
			(connect_pads
				(clearance 0)
			)
			(min_thickness 0.25)
			(keepout
				(tracks not_allowed)
				(vias allowed)
				(pads allowed)
				(copperpour not_allowed)
				(footprints allowed)
			)
			(placement
				(enabled no)
				(sheetname "")
			)
			(fill
				(thermal_gap 0.5)
				(thermal_bridge_width 0.5)
				(island_removal_mode 0)
			)
			(polygon
				(pts
					(arc
						(start 22.081998 -316.330076)
						(mid 19.618198 -316.330076)
						(end 22.081998 -316.330076)
					)
				)
			)
		)
	)
	(footprint ""
		(layer "F.Cu")
		(at 90.297 -92.964)
		(property "Reference" "R9127"
			(at 0 0 0)
			(layer "F.SilkS")
			(hide yes)
			(effects
				(font
					(size 1.27 1.27)
				)
			)
		)
		(property "Value" "27R2F-GP"
			(at 0.064008 -3.993896 0)
			(unlocked yes)
			(layer "F.Fab")
			(hide yes)
			(effects
				(font
					(size 1.016 1.016)
					(thickness 0.1524)
				)
			)
		)
		(property "Device Type" "R402H16"
			(at 0.064008 -5.517896 0)
			(unlocked yes)
			(layer "F.Fab")
			(hide yes)
			(effects
				(font
					(size 1.016 1.016)
					(thickness 0.1524)
				)
			)
		)
		(duplicate_pad_numbers_are_jumpers no)
		(fp_line
			(start -0.508 -0.9398)
			(end -0.508 0.9398)
			(stroke
				(width 0.1524)
				(type default)
			)
			(layer "F.SilkS")
		)
		(fp_line
			(start 0.508 -0.9398)
			(end -0.508 -0.9398)
			(stroke
				(width 0.1524)
				(type default)
			)
			(layer "F.SilkS")
		)
		(fp_rect
			(start -0.508 0.9398)
			(end 0.508 -0.9398)
			(stroke
				(width 0)
				(type default)
			)
			(fill no)
			(layer "F.CrtYd")
		)
		(fp_rect
			(start -0.508 0.9398)
			(end 0.508 -0.9398)
			(stroke
				(width 0)
				(type default)
			)
			(fill no)
			(layer "F.Fab")
		)
		(pad "1" smd custom
			(at 0 -0.4445)
			(size 0.1397 0.1397)
			(layers "F.Cu" "F.Mask" "F.Paste")
			(net "PE_CLK_100M_DR9_1_R_P")
			(options
				(clearance outline)
				(anchor circle)
			)
			(primitives
				(gr_poly
					(pts
						(arc
							(start -0.1778 -0.2794)
							(mid -0.249642 -0.249642)
							(end -0.2794 -0.1778)
						)
						(arc
							(start -0.2794 0.1778)
							(mid -0.249642 0.249642)
							(end -0.1778 0.2794)
						)
						(arc
							(start 0.1778 0.2794)
							(mid 0.249642 0.249642)
							(end 0.2794 0.1778)
						)
						(arc
							(start 0.2794 -0.1778)
							(mid 0.249642 -0.249642)
							(end 0.1778 -0.2794)
						)
					)
					(width 0)
					(fill yes)
				)
			)
		)
		(pad "2" smd custom
			(at 0 0.4445)
			(size 0.1397 0.1397)
			(layers "F.Cu" "F.Mask" "F.Paste")
			(net "PE_CLK100M_DR9_1_P")
			(options
				(clearance outline)
				(anchor circle)
			)
			(primitives
				(gr_poly
					(pts
						(arc
							(start -0.1778 -0.2794)
							(mid -0.249642 -0.249642)
							(end -0.2794 -0.1778)
						)
						(arc
							(start -0.2794 0.1778)
							(mid -0.249642 0.249642)
							(end -0.1778 0.2794)
						)
						(arc
							(start 0.1778 0.2794)
							(mid 0.249642 0.249642)
							(end 0.2794 0.1778)
						)
						(arc
							(start 0.2794 -0.1778)
							(mid 0.249642 -0.249642)
							(end 0.1778 -0.2794)
						)
					)
					(width 0)
					(fill yes)
				)
			)
		)
	)
	(footprint ""
		(layer "F.Cu")
		(at 101.092 -103.759)
		(property "Reference" "R9510"
			(at 0 0 0)
			(layer "F.SilkS")
			(hide yes)
			(effects
				(font
					(size 1.27 1.27)
				)
			)
		)
		(property "Value" "4K7R2F-GP"
			(at 0.064008 -3.993896 0)
			(unlocked yes)
			(layer "F.Fab")
			(hide yes)
			(effects
				(font
					(size 1.016 1.016)
					(thickness 0.1524)
				)
			)
		)
		(property "Device Type" "R402H16"
			(at 0.064008 -5.517896 0)
			(unlocked yes)
			(layer "F.Fab")
			(hide yes)
			(effects
				(font
					(size 1.016 1.016)
					(thickness 0.1524)
				)
			)
		)
		(duplicate_pad_numbers_are_jumpers no)
		(fp_line
			(start -0.508 -0.9398)
			(end -0.508 0.9398)
			(stroke
				(width 0.1524)
				(type default)
			)
			(layer "F.SilkS")
		)
		(fp_line
			(start 0.508 -0.9398)
			(end -0.508 -0.9398)
			(stroke
				(width 0.1524)
				(type default)
			)
			(layer "F.SilkS")
		)
		(fp_rect
			(start -0.508 0.9398)
			(end 0.508 -0.9398)
			(stroke
				(width 0)
				(type default)
			)
			(fill no)
			(layer "F.CrtYd")
		)
		(fp_rect
			(start -0.508 0.9398)
			(end 0.508 -0.9398)
			(stroke
				(width 0)
				(type default)
			)
			(fill no)
			(layer "F.Fab")
		)
		(pad "1" smd custom
			(at 0 -0.4445)
			(size 0.1397 0.1397)
			(layers "F.Cu" "F.Mask" "F.Paste")
			(net "P3V3")
			(options
				(clearance outline)
				(anchor circle)
			)
			(primitives
				(gr_poly
					(pts
						(arc
							(start -0.1778 -0.2794)
							(mid -0.249642 -0.249642)
							(end -0.2794 -0.1778)
						)
						(arc
							(start -0.2794 0.1778)
							(mid -0.249642 0.249642)
							(end -0.1778 0.2794)
						)
						(arc
							(start 0.1778 0.2794)
							(mid 0.249642 0.249642)
							(end 0.2794 0.1778)
						)
						(arc
							(start 0.2794 -0.1778)
							(mid 0.249642 -0.249642)
							(end 0.1778 -0.2794)
						)
					)
					(width 0)
					(fill yes)
				)
			)
		)
		(pad "2" smd custom
			(at 0 0.4445)
			(size 0.1397 0.1397)
			(layers "F.Cu" "F.Mask" "F.Paste")
			(net "CLK_BUFFER_EU4_VOE_N")
			(options
				(clearance outline)
				(anchor circle)
			)
			(primitives
				(gr_poly
					(pts
						(arc
							(start -0.1778 -0.2794)
							(mid -0.249642 -0.249642)
							(end -0.2794 -0.1778)
						)
						(arc
							(start -0.2794 0.1778)
							(mid -0.249642 0.249642)
							(end -0.1778 0.2794)
						)
						(arc
							(start 0.1778 0.2794)
							(mid 0.249642 0.249642)
							(end 0.2794 0.1778)
						)
						(arc
							(start 0.2794 -0.1778)
							(mid 0.249642 -0.249642)
							(end 0.1778 -0.2794)
						)
					)
					(width 0)
					(fill yes)
				)
			)
		)
	)
	(footprint ""
		(layer "F.Cu")
		(at 82.931 -436.118 90)
		(property "Reference" "SR947"
			(at 0 0 90)
			(layer "F.SilkS")
			(hide yes)
			(effects
				(font
					(size 1.27 1.27)
				)
			)
		)
		(property "Value" "4K7R2F-GP"
			(at 0.064008 -3.993896 90)
			(unlocked yes)
			(layer "F.Fab")
			(hide yes)
			(effects
				(font
					(size 1.016 1.016)
					(thickness 0.1524)
				)
			)
		)
		(property "Device Type" "R402H16"
			(at 0.064008 -5.517896 90)
			(unlocked yes)
			(layer "F.Fab")
			(hide yes)
			(effects
				(font
					(size 1.016 1.016)
					(thickness 0.1524)
				)
			)
		)
		(duplicate_pad_numbers_are_jumpers no)
		(fp_line
			(start 0.508 -0.9398)
			(end -0.508 -0.9398)
			(stroke
				(width 0.1524)
				(type default)
			)
			(layer "F.SilkS")
		)
		(fp_line
			(start -0.508 -0.9398)
			(end -0.508 0.9398)
			(stroke
				(width 0.1524)
				(type default)
			)
			(layer "F.SilkS")
		)
		(fp_rect
			(start -0.508 0.9398)
			(end 0.508 -0.9398)
			(stroke
				(width 0)
				(type default)
			)
			(fill no)
			(layer "F.CrtYd")
		)
		(fp_rect
			(start -0.508 0.9398)
			(end 0.508 -0.9398)
			(stroke
				(width 0)
				(type default)
			)
			(fill no)
			(layer "F.Fab")
		)
		(pad "1" smd custom
			(at 0 -0.4445 90)
			(size 0.1397 0.1397)
			(layers "F.Cu" "F.Mask" "F.Paste")
			(net "VDD_DIFF_1")
			(options
				(clearance outline)
				(anchor circle)
			)
			(primitives
				(gr_poly
					(pts
						(arc
							(start -0.1778 -0.2794)
							(mid -0.249642 -0.249642)
							(end -0.2794 -0.1778)
						)
						(arc
							(start -0.2794 0.1778)
							(mid -0.249642 0.249642)
							(end -0.1778 0.2794)
						)
						(arc
							(start 0.1778 0.2794)
							(mid 0.249642 0.249642)
							(end 0.2794 0.1778)
						)
						(arc
							(start 0.2794 -0.1778)
							(mid 0.249642 -0.249642)
							(end 0.1778 -0.2794)
						)
					)
					(width 0)
					(fill yes)
				)
			)
		)
		(pad "2" smd custom
			(at 0 0.4445 90)
			(size 0.1397 0.1397)
			(layers "F.Cu" "F.Mask" "F.Paste")
			(net "CLK_BUF_EU1_HIBW_BYPM_LOBW#")
			(options
				(clearance outline)
				(anchor circle)
			)
			(primitives
				(gr_poly
					(pts
						(arc
							(start -0.1778 -0.2794)
							(mid -0.249642 -0.249642)
							(end -0.2794 -0.1778)
						)
						(arc
							(start -0.2794 0.1778)
							(mid -0.249642 0.249642)
							(end -0.1778 0.2794)
						)
						(arc
							(start 0.1778 0.2794)
							(mid 0.249642 0.249642)
							(end 0.2794 0.1778)
						)
						(arc
							(start 0.2794 -0.1778)
							(mid 0.249642 -0.249642)
							(end 0.1778 -0.2794)
						)
					)
					(width 0)
					(fill yes)
				)
			)
		)
	)
	(footprint ""
		(layer "F.Cu")
		(at 205.867 -46.482)
		(property "Reference" "TP6"
			(at 0 0 0)
			(layer "F.SilkS")
			(hide yes)
			(effects
				(font
					(size 1.27 1.27)
				)
			)
		)
		(property "Value" "TPAD32-GP"
			(at -0.0508 -1.6764 0)
			(unlocked yes)
			(layer "F.Fab")
			(hide yes)
			(effects
				(font
					(size 1.016 1.016)
					(thickness 0.1524)
				)
			)
		)
		(property "Device Type" "TPAD32"
			(at -0.0508 -3.2004 0)
			(unlocked yes)
			(layer "F.Fab")
			(hide yes)
			(effects
				(font
					(size 1.016 1.016)
					(thickness 0.1524)
				)
			)
		)
		(duplicate_pad_numbers_are_jumpers no)
		(fp_poly
			(pts
				(arc
					(start 0.4064 0)
					(mid -0.4064 0)
					(end 0.4064 0)
				)
			)
			(stroke
				(width 0)
				(type default)
			)
			(fill no)
			(layer "F.CrtYd")
		)
		(fp_poly
			(pts
				(arc
					(start 0.7112 0)
					(mid -0.7112 0)
					(end 0.7112 0)
				)
			)
			(stroke
				(width 0)
				(type default)
			)
			(fill no)
			(layer "F.Fab")
		)
		(pad "1" smd circle
			(at 0 0)
			(size 0.8128 0.8128)
			(layers "F.Cu" "F.Mask" "F.Paste")
			(net "I2C_B_TMP3_ALERT")
		)
	)
	(footprint ""
		(layer "F.Cu")
		(at 75.184 -154.178)
		(property "Reference" "SR975"
			(at 0 0 0)
			(layer "F.SilkS")
			(hide yes)
			(effects
				(font
					(size 1.27 1.27)
				)
			)
		)
		(property "Value" "2KR2F-3-GP"
			(at 0.064008 -3.993896 0)
			(unlocked yes)
			(layer "F.Fab")
			(hide yes)
			(effects
				(font
					(size 1.016 1.016)
					(thickness 0.1524)
				)
			)
		)
		(property "Device Type" "R402H16"
			(at 0.064008 -5.517896 0)
			(unlocked yes)
			(layer "F.Fab")
			(hide yes)
			(effects
				(font
					(size 1.016 1.016)
					(thickness 0.1524)
				)
			)
		)
		(duplicate_pad_numbers_are_jumpers no)
		(fp_line
			(start -0.508 -0.9398)
			(end -0.508 0.9398)
			(stroke
				(width 0.1524)
				(type default)
			)
			(layer "F.SilkS")
		)
		(fp_line
			(start 0.508 -0.9398)
			(end -0.508 -0.9398)
			(stroke
				(width 0.1524)
				(type default)
			)
			(layer "F.SilkS")
		)
		(fp_rect
			(start -0.508 0.9398)
			(end 0.508 -0.9398)
			(stroke
				(width 0)
				(type default)
			)
			(fill no)
			(layer "F.CrtYd")
		)
		(fp_rect
			(start -0.508 0.9398)
			(end 0.508 -0.9398)
			(stroke
				(width 0)
				(type default)
			)
			(fill no)
			(layer "F.Fab")
		)
		(pad "1" smd custom
			(at 0 -0.4445)
			(size 0.1397 0.1397)
			(layers "F.Cu" "F.Mask" "F.Paste")
			(net "P3V3")
			(options
				(clearance outline)
				(anchor circle)
			)
			(primitives
				(gr_poly
					(pts
						(arc
							(start -0.1778 -0.2794)
							(mid -0.249642 -0.249642)
							(end -0.2794 -0.1778)
						)
						(arc
							(start -0.2794 0.1778)
							(mid -0.249642 0.249642)
							(end -0.1778 0.2794)
						)
						(arc
							(start 0.1778 0.2794)
							(mid 0.249642 0.249642)
							(end 0.2794 0.1778)
						)
						(arc
							(start 0.2794 -0.1778)
							(mid 0.249642 -0.249642)
							(end 0.1778 -0.2794)
						)
					)
					(width 0)
					(fill yes)
				)
			)
		)
		(pad "2" smd custom
			(at 0 0.4445)
			(size 0.1397 0.1397)
			(layers "F.Cu" "F.Mask" "F.Paste")
			(net "SCL_DR4")
			(options
				(clearance outline)
				(anchor circle)
			)
			(primitives
				(gr_poly
					(pts
						(arc
							(start -0.1778 -0.2794)
							(mid -0.249642 -0.249642)
							(end -0.2794 -0.1778)
						)
						(arc
							(start -0.2794 0.1778)
							(mid -0.249642 0.249642)
							(end -0.1778 0.2794)
						)
						(arc
							(start 0.1778 0.2794)
							(mid 0.249642 0.249642)
							(end 0.2794 0.1778)
						)
						(arc
							(start 0.2794 -0.1778)
							(mid 0.249642 -0.249642)
							(end 0.1778 -0.2794)
						)
					)
					(width 0)
					(fill yes)
				)
			)
		)
	)
	(footprint ""
		(layer "F.Cu")
		(at 30.861 -318.4652)
		(property "Reference" "SR1114"
			(at 0 0 0)
			(layer "F.SilkS")
			(hide yes)
			(effects
				(font
					(size 1.27 1.27)
				)
			)
		)
		(property "Value" "4K7R2F-GP"
			(at 0.064008 -3.993896 0)
			(unlocked yes)
			(layer "F.Fab")
			(hide yes)
			(effects
				(font
					(size 1.016 1.016)
					(thickness 0.1524)
				)
			)
		)
		(property "Device Type" "R402H16"
			(at 0.064008 -5.517896 0)
			(unlocked yes)
			(layer "F.Fab")
			(hide yes)
			(effects
				(font
					(size 1.016 1.016)
					(thickness 0.1524)
				)
			)
		)
		(duplicate_pad_numbers_are_jumpers no)
		(fp_line
			(start -0.508 -0.9398)
			(end -0.508 0.9398)
			(stroke
				(width 0.1524)
				(type default)
			)
			(layer "F.SilkS")
		)
		(fp_line
			(start 0.508 -0.9398)
			(end -0.508 -0.9398)
			(stroke
				(width 0.1524)
				(type default)
			)
			(layer "F.SilkS")
		)
		(fp_rect
			(start -0.508 0.9398)
			(end 0.508 -0.9398)
			(stroke
				(width 0)
				(type default)
			)
			(fill no)
			(layer "F.CrtYd")
		)
		(fp_rect
			(start -0.508 0.9398)
			(end 0.508 -0.9398)
			(stroke
				(width 0)
				(type default)
			)
			(fill no)
			(layer "F.Fab")
		)
		(pad "1" smd custom
			(at 0 -0.4445)
			(size 0.1397 0.1397)
			(layers "F.Cu" "F.Mask" "F.Paste")
			(net "DUALPORTEN#11")
			(options
				(clearance outline)
				(anchor circle)
			)
			(primitives
				(gr_poly
					(pts
						(arc
							(start -0.1778 -0.2794)
							(mid -0.249642 -0.249642)
							(end -0.2794 -0.1778)
						)
						(arc
							(start -0.2794 0.1778)
							(mid -0.249642 0.249642)
							(end -0.1778 0.2794)
						)
						(arc
							(start 0.1778 0.2794)
							(mid 0.249642 0.249642)
							(end 0.2794 0.1778)
						)
						(arc
							(start 0.2794 -0.1778)
							(mid 0.249642 -0.249642)
							(end 0.1778 -0.2794)
						)
					)
					(width 0)
					(fill yes)
				)
			)
		)
		(pad "2" smd custom
			(at 0 0.4445)
			(size 0.1397 0.1397)
			(layers "F.Cu" "F.Mask" "F.Paste")
			(net "GND")
			(options
				(clearance outline)
				(anchor circle)
			)
			(primitives
				(gr_poly
					(pts
						(arc
							(start -0.1778 -0.2794)
							(mid -0.249642 -0.249642)
							(end -0.2794 -0.1778)
						)
						(arc
							(start -0.2794 0.1778)
							(mid -0.249642 0.249642)
							(end -0.1778 0.2794)
						)
						(arc
							(start 0.1778 0.2794)
							(mid 0.249642 0.249642)
							(end 0.2794 0.1778)
						)
						(arc
							(start 0.2794 -0.1778)
							(mid 0.249642 -0.249642)
							(end 0.1778 -0.2794)
						)
					)
					(width 0)
					(fill yes)
				)
			)
		)
	)
	(footprint ""
		(layer "F.Cu")
		(at 79.502 -143.256)
		(property "Reference" "SR1046"
			(at 0 0 0)
			(layer "F.SilkS")
			(hide yes)
			(effects
				(font
					(size 1.27 1.27)
				)
			)
		)
		(property "Value" "4K7R2F-GP"
			(at 0.064008 -3.993896 0)
			(unlocked yes)
			(layer "F.Fab")
			(hide yes)
			(effects
				(font
					(size 1.016 1.016)
					(thickness 0.1524)
				)
			)
		)
		(property "Device Type" "R402H16"
			(at 0.064008 -5.517896 0)
			(unlocked yes)
			(layer "F.Fab")
			(hide yes)
			(effects
				(font
					(size 1.016 1.016)
					(thickness 0.1524)
				)
			)
		)
		(duplicate_pad_numbers_are_jumpers no)
		(fp_line
			(start -0.508 -0.9398)
			(end -0.508 0.9398)
			(stroke
				(width 0.1524)
				(type default)
			)
			(layer "F.SilkS")
		)
		(fp_line
			(start 0.508 -0.9398)
			(end -0.508 -0.9398)
			(stroke
				(width 0.1524)
				(type default)
			)
			(layer "F.SilkS")
		)
		(fp_rect
			(start -0.508 0.9398)
			(end 0.508 -0.9398)
			(stroke
				(width 0)
				(type default)
			)
			(fill no)
			(layer "F.CrtYd")
		)
		(fp_rect
			(start -0.508 0.9398)
			(end 0.508 -0.9398)
			(stroke
				(width 0)
				(type default)
			)
			(fill no)
			(layer "F.Fab")
		)
		(pad "1" smd custom
			(at 0 -0.4445)
			(size 0.1397 0.1397)
			(layers "F.Cu" "F.Mask" "F.Paste")
			(net "I2C_SW_EU16_ADDRESS_A2")
			(options
				(clearance outline)
				(anchor circle)
			)
			(primitives
				(gr_poly
					(pts
						(arc
							(start -0.1778 -0.2794)
							(mid -0.249642 -0.249642)
							(end -0.2794 -0.1778)
						)
						(arc
							(start -0.2794 0.1778)
							(mid -0.249642 0.249642)
							(end -0.1778 0.2794)
						)
						(arc
							(start 0.1778 0.2794)
							(mid 0.249642 0.249642)
							(end 0.2794 0.1778)
						)
						(arc
							(start 0.2794 -0.1778)
							(mid 0.249642 -0.249642)
							(end 0.1778 -0.2794)
						)
					)
					(width 0)
					(fill yes)
				)
			)
		)
		(pad "2" smd custom
			(at 0 0.4445)
			(size 0.1397 0.1397)
			(layers "F.Cu" "F.Mask" "F.Paste")
			(net "GND")
			(options
				(clearance outline)
				(anchor circle)
			)
			(primitives
				(gr_poly
					(pts
						(arc
							(start -0.1778 -0.2794)
							(mid -0.249642 -0.249642)
							(end -0.2794 -0.1778)
						)
						(arc
							(start -0.2794 0.1778)
							(mid -0.249642 0.249642)
							(end -0.1778 0.2794)
						)
						(arc
							(start 0.1778 0.2794)
							(mid 0.249642 0.249642)
							(end 0.2794 0.1778)
						)
						(arc
							(start 0.2794 -0.1778)
							(mid 0.249642 -0.249642)
							(end 0.1778 -0.2794)
						)
					)
					(width 0)
					(fill yes)
				)
			)
		)
	)
	(footprint ""
		(layer "F.Cu")
		(at 36.576 -62.103 180)
		(property "Reference" "PC1199"
			(at 0 0 180)
			(layer "F.SilkS")
			(hide yes)
			(effects
				(font
					(size 1.27 1.27)
				)
			)
		)
		(property "Value" "SCD1U25V3KX-GP"
			(at 0 -2.8194 180)
			(unlocked yes)
			(layer "F.Fab")
			(hide yes)
			(effects
				(font
					(size 1.016 1.016)
					(thickness 0.1524)
				)
			)
		)
		(property "Device Type" "C603H36"
			(at 0 -4.3434 180)
			(unlocked yes)
			(layer "F.Fab")
			(hide yes)
			(effects
				(font
					(size 1.016 1.016)
					(thickness 0.1524)
				)
			)
		)
		(duplicate_pad_numbers_are_jumpers no)
		(fp_line
			(start 0.508 0)
			(end -0.508 0)
			(stroke
				(width 0.2032)
				(type default)
			)
			(layer "F.SilkS")
		)
		(fp_rect
			(start -0.5842 1.3335)
			(end 0.5842 -1.3335)
			(stroke
				(width 0)
				(type default)
			)
			(fill no)
			(layer "F.CrtYd")
		)
		(fp_rect
			(start -0.5842 1.3335)
			(end 0.5842 -1.3335)
			(stroke
				(width 0)
				(type default)
			)
			(fill no)
			(layer "F.Fab")
		)
		(pad "1" smd custom
			(at 0 -0.762 180)
			(size 0.2159 0.2159)
			(layers "F.Cu" "F.Mask" "F.Paste")
			(net "P3V3")
			(options
				(clearance outline)
				(anchor circle)
			)
			(primitives
				(gr_poly
					(pts
						(arc
							(start -0.3302 -0.4318)
							(mid -0.402042 -0.402042)
							(end -0.4318 -0.3302)
						)
						(arc
							(start -0.4318 0.3302)
							(mid -0.402042 0.402042)
							(end -0.3302 0.4318)
						)
						(arc
							(start 0.3302 0.4318)
							(mid 0.402042 0.402042)
							(end 0.4318 0.3302)
						)
						(arc
							(start 0.4318 -0.3302)
							(mid 0.402042 -0.402042)
							(end 0.3302 -0.4318)
						)
					)
					(width 0)
					(fill yes)
				)
			)
		)
		(pad "2" smd custom
			(at 0 0.762 180)
			(size 0.2159 0.2159)
			(layers "F.Cu" "F.Mask" "F.Paste")
			(net "GND")
			(options
				(clearance outline)
				(anchor circle)
			)
			(primitives
				(gr_poly
					(pts
						(arc
							(start -0.3302 -0.4318)
							(mid -0.402042 -0.402042)
							(end -0.4318 -0.3302)
						)
						(arc
							(start -0.4318 0.3302)
							(mid -0.402042 0.402042)
							(end -0.3302 0.4318)
						)
						(arc
							(start 0.3302 0.4318)
							(mid 0.402042 0.402042)
							(end 0.4318 0.3302)
						)
						(arc
							(start 0.4318 -0.3302)
							(mid 0.402042 -0.402042)
							(end 0.3302 -0.4318)
						)
					)
					(width 0)
					(fill yes)
				)
			)
		)
	)
	(footprint ""
		(layer "F.Cu")
		(at 32.131 -288.798 -90)
		(property "Reference" "R402"
			(at 0 0 270)
			(layer "F.SilkS")
			(hide yes)
			(effects
				(font
					(size 1.27 1.27)
				)
			)
		)
		(property "Value" "0R2J-2-GP"
			(at 0.064008 -3.993896 270)
			(unlocked yes)
			(layer "F.Fab")
			(hide yes)
			(effects
				(font
					(size 1.016 1.016)
					(thickness 0.1524)
				)
			)
		)
		(property "Device Type" "R402H16"
			(at 0.064008 -5.517896 270)
			(unlocked yes)
			(layer "F.Fab")
			(hide yes)
			(effects
				(font
					(size 1.016 1.016)
					(thickness 0.1524)
				)
			)
		)
		(duplicate_pad_numbers_are_jumpers no)
		(fp_line
			(start -0.508 -0.9398)
			(end -0.508 0.9398)
			(stroke
				(width 0.1524)
				(type default)
			)
			(layer "F.SilkS")
		)
		(fp_line
			(start 0.508 -0.9398)
			(end -0.508 -0.9398)
			(stroke
				(width 0.1524)
				(type default)
			)
			(layer "F.SilkS")
		)
		(fp_rect
			(start -0.508 0.9398)
			(end 0.508 -0.9398)
			(stroke
				(width 0)
				(type default)
			)
			(fill no)
			(layer "F.CrtYd")
		)
		(fp_rect
			(start -0.508 0.9398)
			(end 0.508 -0.9398)
			(stroke
				(width 0)
				(type default)
			)
			(fill no)
			(layer "F.Fab")
		)
		(pad "1" smd custom
			(at 0 -0.4445 270)
			(size 0.1397 0.1397)
			(layers "F.Cu" "F.Mask" "F.Paste")
			(net "SDA_DR7_R")
			(options
				(clearance outline)
				(anchor circle)
			)
			(primitives
				(gr_poly
					(pts
						(arc
							(start -0.1778 -0.2794)
							(mid -0.249642 -0.249642)
							(end -0.2794 -0.1778)
						)
						(arc
							(start -0.2794 0.1778)
							(mid -0.249642 0.249642)
							(end -0.1778 0.2794)
						)
						(arc
							(start 0.1778 0.2794)
							(mid 0.249642 0.249642)
							(end 0.2794 0.1778)
						)
						(arc
							(start 0.2794 -0.1778)
							(mid 0.249642 -0.249642)
							(end 0.1778 -0.2794)
						)
					)
					(width 0)
					(fill yes)
				)
			)
		)
		(pad "2" smd custom
			(at 0 0.4445 270)
			(size 0.1397 0.1397)
			(layers "F.Cu" "F.Mask" "F.Paste")
			(net "SDA_DR7")
			(options
				(clearance outline)
				(anchor circle)
			)
			(primitives
				(gr_poly
					(pts
						(arc
							(start -0.1778 -0.2794)
							(mid -0.249642 -0.249642)
							(end -0.2794 -0.1778)
						)
						(arc
							(start -0.2794 0.1778)
							(mid -0.249642 0.249642)
							(end -0.1778 0.2794)
						)
						(arc
							(start 0.1778 0.2794)
							(mid 0.249642 0.249642)
							(end 0.2794 0.1778)
						)
						(arc
							(start 0.2794 -0.1778)
							(mid 0.249642 -0.249642)
							(end 0.1778 -0.2794)
						)
					)
					(width 0)
					(fill yes)
				)
			)
		)
	)
	(footprint ""
		(layer "F.Cu")
		(at 234.061 -144.77111 -90)
		(property "Reference" "R9442"
			(at 0 0 270)
			(layer "F.SilkS")
			(hide yes)
			(effects
				(font
					(size 1.27 1.27)
				)
			)
		)
		(property "Value" "330R2F-GP"
			(at 0.064008 -3.993896 270)
			(unlocked yes)
			(layer "F.Fab")
			(hide yes)
			(effects
				(font
					(size 1.016 1.016)
					(thickness 0.1524)
				)
			)
		)
		(property "Device Type" "R402H16"
			(at 0.064008 -5.517896 270)
			(unlocked yes)
			(layer "F.Fab")
			(hide yes)
			(effects
				(font
					(size 1.016 1.016)
					(thickness 0.1524)
				)
			)
		)
		(duplicate_pad_numbers_are_jumpers no)
		(fp_line
			(start -0.508 -0.9398)
			(end -0.508 0.9398)
			(stroke
				(width 0.1524)
				(type default)
			)
			(layer "F.SilkS")
		)
		(fp_line
			(start 0.508 -0.9398)
			(end -0.508 -0.9398)
			(stroke
				(width 0.1524)
				(type default)
			)
			(layer "F.SilkS")
		)
		(fp_rect
			(start -0.508 0.9398)
			(end 0.508 -0.9398)
			(stroke
				(width 0)
				(type default)
			)
			(fill no)
			(layer "F.CrtYd")
		)
		(fp_rect
			(start -0.508 0.9398)
			(end 0.508 -0.9398)
			(stroke
				(width 0)
				(type default)
			)
			(fill no)
			(layer "F.Fab")
		)
		(pad "1" smd custom
			(at 0 -0.4445 270)
			(size 0.1397 0.1397)
			(layers "F.Cu" "F.Mask" "F.Paste")
			(net "P3V3")
			(options
				(clearance outline)
				(anchor circle)
			)
			(primitives
				(gr_poly
					(pts
						(arc
							(start -0.1778 -0.2794)
							(mid -0.249642 -0.249642)
							(end -0.2794 -0.1778)
						)
						(arc
							(start -0.2794 0.1778)
							(mid -0.249642 0.249642)
							(end -0.1778 0.2794)
						)
						(arc
							(start 0.1778 0.2794)
							(mid 0.249642 0.249642)
							(end 0.2794 0.1778)
						)
						(arc
							(start 0.2794 -0.1778)
							(mid 0.249642 -0.249642)
							(end 0.1778 -0.2794)
						)
					)
					(width 0)
					(fill yes)
				)
			)
		)
		(pad "2" smd custom
			(at 0 0.4445 270)
			(size 0.1397 0.1397)
			(layers "F.Cu" "F.Mask" "F.Paste")
			(net "DRV_ATTN_3")
			(options
				(clearance outline)
				(anchor circle)
			)
			(primitives
				(gr_poly
					(pts
						(arc
							(start -0.1778 -0.2794)
							(mid -0.249642 -0.249642)
							(end -0.2794 -0.1778)
						)
						(arc
							(start -0.2794 0.1778)
							(mid -0.249642 0.249642)
							(end -0.1778 0.2794)
						)
						(arc
							(start 0.1778 0.2794)
							(mid 0.249642 0.249642)
							(end 0.2794 0.1778)
						)
						(arc
							(start 0.2794 -0.1778)
							(mid 0.249642 -0.249642)
							(end 0.1778 -0.2794)
						)
					)
					(width 0)
					(fill yes)
				)
			)
		)
	)
	(footprint ""
		(layer "F.Cu")
		(at 82.931 -310.515 90)
		(property "Reference" "SR948"
			(at 0 0 90)
			(layer "F.SilkS")
			(hide yes)
			(effects
				(font
					(size 1.27 1.27)
				)
			)
		)
		(property "Value" "4K7R2F-GP"
			(at 0.064008 -3.993896 90)
			(unlocked yes)
			(layer "F.Fab")
			(hide yes)
			(effects
				(font
					(size 1.016 1.016)
					(thickness 0.1524)
				)
			)
		)
		(property "Device Type" "R402H16"
			(at 0.064008 -5.517896 90)
			(unlocked yes)
			(layer "F.Fab")
			(hide yes)
			(effects
				(font
					(size 1.016 1.016)
					(thickness 0.1524)
				)
			)
		)
		(duplicate_pad_numbers_are_jumpers no)
		(fp_line
			(start 0.508 -0.9398)
			(end -0.508 -0.9398)
			(stroke
				(width 0.1524)
				(type default)
			)
			(layer "F.SilkS")
		)
		(fp_line
			(start -0.508 -0.9398)
			(end -0.508 0.9398)
			(stroke
				(width 0.1524)
				(type default)
			)
			(layer "F.SilkS")
		)
		(fp_rect
			(start -0.508 0.9398)
			(end 0.508 -0.9398)
			(stroke
				(width 0)
				(type default)
			)
			(fill no)
			(layer "F.CrtYd")
		)
		(fp_rect
			(start -0.508 0.9398)
			(end 0.508 -0.9398)
			(stroke
				(width 0)
				(type default)
			)
			(fill no)
			(layer "F.Fab")
		)
		(pad "1" smd custom
			(at 0 -0.4445 90)
			(size 0.1397 0.1397)
			(layers "F.Cu" "F.Mask" "F.Paste")
			(net "VDD_DIFF_2")
			(options
				(clearance outline)
				(anchor circle)
			)
			(primitives
				(gr_poly
					(pts
						(arc
							(start -0.1778 -0.2794)
							(mid -0.249642 -0.249642)
							(end -0.2794 -0.1778)
						)
						(arc
							(start -0.2794 0.1778)
							(mid -0.249642 0.249642)
							(end -0.1778 0.2794)
						)
						(arc
							(start 0.1778 0.2794)
							(mid 0.249642 0.249642)
							(end 0.2794 0.1778)
						)
						(arc
							(start 0.2794 -0.1778)
							(mid 0.249642 -0.249642)
							(end 0.1778 -0.2794)
						)
					)
					(width 0)
					(fill yes)
				)
			)
		)
		(pad "2" smd custom
			(at 0 0.4445 90)
			(size 0.1397 0.1397)
			(layers "F.Cu" "F.Mask" "F.Paste")
			(net "CLK_BUF_EU2_100M_133M#")
			(options
				(clearance outline)
				(anchor circle)
			)
			(primitives
				(gr_poly
					(pts
						(arc
							(start -0.1778 -0.2794)
							(mid -0.249642 -0.249642)
							(end -0.2794 -0.1778)
						)
						(arc
							(start -0.2794 0.1778)
							(mid -0.249642 0.249642)
							(end -0.1778 0.2794)
						)
						(arc
							(start 0.1778 0.2794)
							(mid 0.249642 0.249642)
							(end 0.2794 0.1778)
						)
						(arc
							(start 0.2794 -0.1778)
							(mid 0.249642 -0.249642)
							(end 0.1778 -0.2794)
						)
					)
					(width 0)
					(fill yes)
				)
			)
		)
	)
	(footprint ""
		(layer "F.Cu")
		(at 73.80732 -143.256 180)
		(property "Reference" "SR964"
			(at 0 0 180)
			(layer "F.SilkS")
			(hide yes)
			(effects
				(font
					(size 1.27 1.27)
				)
			)
		)
		(property "Value" "2KR2F-3-GP"
			(at 0.064008 -3.993896 180)
			(unlocked yes)
			(layer "F.Fab")
			(hide yes)
			(effects
				(font
					(size 1.016 1.016)
					(thickness 0.1524)
				)
			)
		)
		(property "Device Type" "R402H16"
			(at 0.064008 -5.517896 180)
			(unlocked yes)
			(layer "F.Fab")
			(hide yes)
			(effects
				(font
					(size 1.016 1.016)
					(thickness 0.1524)
				)
			)
		)
		(duplicate_pad_numbers_are_jumpers no)
		(fp_line
			(start 0.508 -0.9398)
			(end -0.508 -0.9398)
			(stroke
				(width 0.1524)
				(type default)
			)
			(layer "F.SilkS")
		)
		(fp_line
			(start -0.508 -0.9398)
			(end -0.508 0.9398)
			(stroke
				(width 0.1524)
				(type default)
			)
			(layer "F.SilkS")
		)
		(fp_rect
			(start -0.508 0.9398)
			(end 0.508 -0.9398)
			(stroke
				(width 0)
				(type default)
			)
			(fill no)
			(layer "F.CrtYd")
		)
		(fp_rect
			(start -0.508 0.9398)
			(end 0.508 -0.9398)
			(stroke
				(width 0)
				(type default)
			)
			(fill no)
			(layer "F.Fab")
		)
		(pad "1" smd custom
			(at 0 -0.4445 180)
			(size 0.1397 0.1397)
			(layers "F.Cu" "F.Mask" "F.Paste")
			(net "P3V3")
			(options
				(clearance outline)
				(anchor circle)
			)
			(primitives
				(gr_poly
					(pts
						(arc
							(start -0.1778 -0.2794)
							(mid -0.249642 -0.249642)
							(end -0.2794 -0.1778)
						)
						(arc
							(start -0.2794 0.1778)
							(mid -0.249642 0.249642)
							(end -0.1778 0.2794)
						)
						(arc
							(start 0.1778 0.2794)
							(mid 0.249642 0.249642)
							(end 0.2794 0.1778)
						)
						(arc
							(start 0.2794 -0.1778)
							(mid 0.249642 -0.249642)
							(end 0.1778 -0.2794)
						)
					)
					(width 0)
					(fill yes)
				)
			)
		)
		(pad "2" smd custom
			(at 0 0.4445 180)
			(size 0.1397 0.1397)
			(layers "F.Cu" "F.Mask" "F.Paste")
			(net "SDA_DR14")
			(options
				(clearance outline)
				(anchor circle)
			)
			(primitives
				(gr_poly
					(pts
						(arc
							(start -0.1778 -0.2794)
							(mid -0.249642 -0.249642)
							(end -0.2794 -0.1778)
						)
						(arc
							(start -0.2794 0.1778)
							(mid -0.249642 0.249642)
							(end -0.1778 0.2794)
						)
						(arc
							(start 0.1778 0.2794)
							(mid 0.249642 0.249642)
							(end 0.2794 0.1778)
						)
						(arc
							(start 0.2794 -0.1778)
							(mid 0.249642 -0.249642)
							(end 0.1778 -0.2794)
						)
					)
					(width 0)
					(fill yes)
				)
			)
		)
	)
	(footprint ""
		(layer "F.Cu")
		(at 209.804 -294.64 -90)
		(property "Reference" "R139"
			(at 0 0 270)
			(layer "F.SilkS")
			(hide yes)
			(effects
				(font
					(size 1.27 1.27)
				)
			)
		)
		(property "Value" "4K7R2J-2-GP"
			(at 0.064008 -3.993896 270)
			(unlocked yes)
			(layer "F.Fab")
			(hide yes)
			(effects
				(font
					(size 1.016 1.016)
					(thickness 0.1524)
				)
			)
		)
		(property "Device Type" "R402H16"
			(at 0.064008 -5.517896 270)
			(unlocked yes)
			(layer "F.Fab")
			(hide yes)
			(effects
				(font
					(size 1.016 1.016)
					(thickness 0.1524)
				)
			)
		)
		(duplicate_pad_numbers_are_jumpers no)
		(fp_line
			(start -0.508 -0.9398)
			(end -0.508 0.9398)
			(stroke
				(width 0.1524)
				(type default)
			)
			(layer "F.SilkS")
		)
		(fp_line
			(start 0.508 -0.9398)
			(end -0.508 -0.9398)
			(stroke
				(width 0.1524)
				(type default)
			)
			(layer "F.SilkS")
		)
		(fp_rect
			(start -0.508 0.9398)
			(end 0.508 -0.9398)
			(stroke
				(width 0)
				(type default)
			)
			(fill no)
			(layer "F.CrtYd")
		)
		(fp_rect
			(start -0.508 0.9398)
			(end 0.508 -0.9398)
			(stroke
				(width 0)
				(type default)
			)
			(fill no)
			(layer "F.Fab")
		)
		(pad "1" smd custom
			(at 0 -0.4445 270)
			(size 0.1397 0.1397)
			(layers "F.Cu" "F.Mask" "F.Paste")
			(net "P12V")
			(options
				(clearance outline)
				(anchor circle)
			)
			(primitives
				(gr_poly
					(pts
						(arc
							(start -0.1778 -0.2794)
							(mid -0.249642 -0.249642)
							(end -0.2794 -0.1778)
						)
						(arc
							(start -0.2794 0.1778)
							(mid -0.249642 0.249642)
							(end -0.1778 0.2794)
						)
						(arc
							(start 0.1778 0.2794)
							(mid 0.249642 0.249642)
							(end 0.2794 0.1778)
						)
						(arc
							(start 0.2794 -0.1778)
							(mid 0.249642 -0.249642)
							(end 0.1778 -0.2794)
						)
					)
					(width 0)
					(fill yes)
				)
			)
		)
		(pad "2" smd custom
			(at 0 0.4445 270)
			(size 0.1397 0.1397)
			(layers "F.Cu" "F.Mask" "F.Paste")
			(net "SW_SSD2_R")
			(options
				(clearance outline)
				(anchor circle)
			)
			(primitives
				(gr_poly
					(pts
						(arc
							(start -0.1778 -0.2794)
							(mid -0.249642 -0.249642)
							(end -0.2794 -0.1778)
						)
						(arc
							(start -0.2794 0.1778)
							(mid -0.249642 0.249642)
							(end -0.1778 0.2794)
						)
						(arc
							(start 0.1778 0.2794)
							(mid 0.249642 0.249642)
							(end 0.2794 0.1778)
						)
						(arc
							(start 0.2794 -0.1778)
							(mid 0.249642 -0.249642)
							(end 0.1778 -0.2794)
						)
					)
					(width 0)
					(fill yes)
				)
			)
		)
	)
	(footprint ""
		(layer "F.Cu")
		(at 228.499924 -247.10009)
		(property "Reference" "LED2"
			(at 0 0 0)
			(layer "F.SilkS")
			(hide yes)
			(effects
				(font
					(size 1.27 1.27)
				)
			)
		)
		(property "Value" "LED-RB-4-GP"
			(at 5.88899 1.80848 0)
			(unlocked yes)
			(layer "F.Fab")
			(hide yes)
			(effects
				(font
					(size 1.016 1.016)
					(thickness 0.1524)
				)
			)
		)
		(property "Device Type" "LED1613-4PH20"
			(at 5.88899 0.28448 0)
			(unlocked yes)
			(layer "F.Fab")
			(hide yes)
			(effects
				(font
					(size 1.016 1.016)
					(thickness 0.1524)
				)
			)
		)
		(duplicate_pad_numbers_are_jumpers no)
		(fp_line
			(start -1.4478 -0.9652)
			(end 1.4478 -0.9652)
			(stroke
				(width 0.1524)
				(type default)
			)
			(layer "F.SilkS")
		)
		(fp_line
			(start -1.4478 0.9652)
			(end -1.4478 -0.9652)
			(stroke
				(width 0.1524)
				(type default)
			)
			(layer "F.SilkS")
		)
		(fp_line
			(start -1.4478 0.9652)
			(end -1.4478 -0.9652)
			(stroke
				(width 0.508)
				(type default)
			)
			(layer "F.SilkS")
		)
		(fp_line
			(start 1.4478 -0.9652)
			(end 1.4478 0.9652)
			(stroke
				(width 0.1524)
				(type default)
			)
			(layer "F.SilkS")
		)
		(fp_line
			(start 1.4478 0.9652)
			(end -1.4478 0.9652)
			(stroke
				(width 0.1524)
				(type default)
			)
			(layer "F.SilkS")
		)
		(fp_rect
			(start -0.8001 0.6477)
			(end 0.8001 -0.6477)
			(stroke
				(width 0)
				(type default)
			)
			(fill no)
			(layer "F.CrtYd")
		)
		(fp_poly
			(pts
				(xy -1.7018 1.2192) (xy -1.7018 -0.06223) (xy -0.8001 -0.06223) (xy -0.8001 0.6477) (xy 0.8001 0.6477)
				(xy 0.8001 -0.6477) (xy -0.8001 -0.6477) (xy -0.8001 -0.0635) (xy -1.7018 -0.0635) (xy -1.7018 -1.2192)
				(xy 1.7018 -1.2192) (xy 1.7018 1.2192)
			)
			(stroke
				(width 0)
				(type default)
			)
			(fill no)
			(layer "F.CrtYd")
		)
		(fp_rect
			(start -1.7018 1.2192)
			(end 1.7018 -1.2192)
			(stroke
				(width 0)
				(type default)
			)
			(fill no)
			(layer "F.Fab")
		)
		(pad "1" smd rect
			(at -0.73025 0.4064)
			(size 0.9144 0.6096)
			(layers "F.Cu" "F.Mask" "F.Paste")
			(net "SSD_ACT_DR2_MOS_N")
		)
		(pad "2" smd rect
			(at -0.73025 -0.4064)
			(size 0.9144 0.6096)
			(layers "F.Cu" "F.Mask" "F.Paste")
			(net "ATTN_LED_DR2_MOS_N")
		)
		(pad "3" smd rect
			(at 0.73025 -0.4064)
			(size 0.9144 0.6096)
			(layers "F.Cu" "F.Mask" "F.Paste")
			(net "DRV_ATTN_2")
		)
		(pad "4" smd rect
			(at 0.73025 0.4064)
			(size 0.9144 0.6096)
			(layers "F.Cu" "F.Mask" "F.Paste")
			(net "DRV_ACT_2")
		)
	)
	(footprint ""
		(layer "F.Cu")
		(at 87.503 -102.743 180)
		(property "Reference" "C8934"
			(at 0 0 180)
			(layer "F.SilkS")
			(hide yes)
			(effects
				(font
					(size 1.27 1.27)
				)
			)
		)
		(property "Value" "SCD1U16V2KX-3GP"
			(at 1.1811 -2.7051 180)
			(unlocked yes)
			(layer "F.Fab")
			(hide yes)
			(effects
				(font
					(size 1.016 1.016)
					(thickness 0.1524)
				)
			)
		)
		(property "Device Type" "C402H22"
			(at 1.1811 -4.2291 180)
			(unlocked yes)
			(layer "F.Fab")
			(hide yes)
			(effects
				(font
					(size 1.016 1.016)
					(thickness 0.1524)
				)
			)
		)
		(duplicate_pad_numbers_are_jumpers no)
		(fp_rect
			(start -0.4318 0.9525)
			(end 0.4318 -0.9525)
			(stroke
				(width 0)
				(type default)
			)
			(fill no)
			(layer "F.CrtYd")
		)
		(fp_rect
			(start -0.4318 0.9525)
			(end 0.4318 -0.9525)
			(stroke
				(width 0)
				(type default)
			)
			(fill no)
			(layer "F.Fab")
		)
		(pad "1" smd custom
			(at 0 -0.4445 180)
			(size 0.1524 0.1524)
			(layers "F.Cu" "F.Mask" "F.Paste")
			(net "VDDR_4")
			(options
				(clearance outline)
				(anchor circle)
			)
			(primitives
				(gr_poly
					(pts
						(arc
							(start 0.3048 -0.2032)
							(mid 0.275042 -0.275042)
							(end 0.2032 -0.3048)
						)
						(arc
							(start -0.2032 -0.3048)
							(mid -0.275042 -0.275042)
							(end -0.3048 -0.2032)
						)
						(arc
							(start -0.3048 0.2032)
							(mid -0.275042 0.275042)
							(end -0.2032 0.3048)
						)
						(arc
							(start 0.2032 0.3048)
							(mid 0.275042 0.275042)
							(end 0.3048 0.2032)
						)
					)
					(width 0)
					(fill yes)
				)
			)
		)
		(pad "2" smd custom
			(at 0 0.4445 180)
			(size 0.1524 0.1524)
			(layers "F.Cu" "F.Mask" "F.Paste")
			(net "GND")
			(options
				(clearance outline)
				(anchor circle)
			)
			(primitives
				(gr_poly
					(pts
						(arc
							(start 0.3048 -0.2032)
							(mid 0.275042 -0.275042)
							(end 0.2032 -0.3048)
						)
						(arc
							(start -0.2032 -0.3048)
							(mid -0.275042 -0.275042)
							(end -0.3048 -0.2032)
						)
						(arc
							(start -0.3048 0.2032)
							(mid -0.275042 0.275042)
							(end -0.2032 0.3048)
						)
						(arc
							(start 0.2032 0.3048)
							(mid 0.275042 0.275042)
							(end 0.3048 0.2032)
						)
					)
					(width 0)
					(fill yes)
				)
			)
		)
	)
	(footprint ""
		(layer "F.Cu")
		(at 93.599 -312.801 180)
		(property "Reference" "C9425"
			(at 0 0 180)
			(layer "F.SilkS")
			(hide yes)
			(effects
				(font
					(size 1.27 1.27)
				)
			)
		)
		(property "Value" "SCD1U16V2KX-3GP"
			(at 1.1811 -2.7051 180)
			(unlocked yes)
			(layer "F.Fab")
			(hide yes)
			(effects
				(font
					(size 1.016 1.016)
					(thickness 0.1524)
				)
			)
		)
		(property "Device Type" "C402H22"
			(at 1.1811 -4.2291 180)
			(unlocked yes)
			(layer "F.Fab")
			(hide yes)
			(effects
				(font
					(size 1.016 1.016)
					(thickness 0.1524)
				)
			)
		)
		(duplicate_pad_numbers_are_jumpers no)
		(fp_rect
			(start -0.4318 0.9525)
			(end 0.4318 -0.9525)
			(stroke
				(width 0)
				(type default)
			)
			(fill no)
			(layer "F.CrtYd")
		)
		(fp_rect
			(start -0.4318 0.9525)
			(end 0.4318 -0.9525)
			(stroke
				(width 0)
				(type default)
			)
			(fill no)
			(layer "F.Fab")
		)
		(pad "1" smd custom
			(at 0 -0.4445 180)
			(size 0.1524 0.1524)
			(layers "F.Cu" "F.Mask" "F.Paste")
			(net "VDD_DIFF_2")
			(options
				(clearance outline)
				(anchor circle)
			)
			(primitives
				(gr_poly
					(pts
						(arc
							(start 0.3048 -0.2032)
							(mid 0.275042 -0.275042)
							(end 0.2032 -0.3048)
						)
						(arc
							(start -0.2032 -0.3048)
							(mid -0.275042 -0.275042)
							(end -0.3048 -0.2032)
						)
						(arc
							(start -0.3048 0.2032)
							(mid -0.275042 0.275042)
							(end -0.2032 0.3048)
						)
						(arc
							(start 0.2032 0.3048)
							(mid 0.275042 0.275042)
							(end 0.3048 0.2032)
						)
					)
					(width 0)
					(fill yes)
				)
			)
		)
		(pad "2" smd custom
			(at 0 0.4445 180)
			(size 0.1524 0.1524)
			(layers "F.Cu" "F.Mask" "F.Paste")
			(net "GND")
			(options
				(clearance outline)
				(anchor circle)
			)
			(primitives
				(gr_poly
					(pts
						(arc
							(start 0.3048 -0.2032)
							(mid 0.275042 -0.275042)
							(end 0.2032 -0.3048)
						)
						(arc
							(start -0.2032 -0.3048)
							(mid -0.275042 -0.275042)
							(end -0.3048 -0.2032)
						)
						(arc
							(start -0.3048 0.2032)
							(mid -0.275042 0.275042)
							(end -0.2032 0.3048)
						)
						(arc
							(start 0.2032 0.3048)
							(mid 0.275042 0.275042)
							(end 0.3048 0.2032)
						)
					)
					(width 0)
					(fill yes)
				)
			)
		)
	)
	(footprint ""
		(layer "F.Cu")
		(at 35.56 -410.9974 90)
		(property "Reference" "Q76"
			(at 0 0 90)
			(layer "F.SilkS")
			(hide yes)
			(effects
				(font
					(size 1.27 1.27)
				)
			)
		)
		(property "Value" "2N7002A-7-GP"
			(at 0.127 -8.9662 90)
			(unlocked yes)
			(layer "F.Fab")
			(hide yes)
			(effects
				(font
					(size 1.016 1.016)
					(thickness 0.1524)
				)
			)
		)
		(property "Device Type" "SOT23DGS2D4H48"
			(at 0.127 -10.4902 90)
			(unlocked yes)
			(layer "F.Fab")
			(hide yes)
			(effects
				(font
					(size 1.016 1.016)
					(thickness 0.1524)
				)
			)
		)
		(duplicate_pad_numbers_are_jumpers no)
		(fp_line
			(start 1.651 -1.778)
			(end -1.651 -1.778)
			(stroke
				(width 0.1524)
				(type default)
			)
			(layer "F.SilkS")
		)
		(fp_line
			(start -1.651 -1.778)
			(end -1.651 1.778)
			(stroke
				(width 0.1524)
				(type default)
			)
			(layer "F.SilkS")
		)
		(fp_line
			(start 1.651 1.778)
			(end 1.651 -1.778)
			(stroke
				(width 0.1524)
				(type default)
			)
			(layer "F.SilkS")
		)
		(fp_line
			(start -1.651 1.778)
			(end 1.651 1.778)
			(stroke
				(width 0.1524)
				(type default)
			)
			(layer "F.SilkS")
		)
		(fp_poly
			(pts
				(xy -1.778 1.8796) (xy -1.778 -1.8796) (xy 1.778 -1.8796) (xy 1.778 1.8796)
			)
			(stroke
				(width 0)
				(type default)
			)
			(fill no)
			(layer "F.CrtYd")
		)
		(fp_poly
			(pts
				(xy -1.778 1.8796) (xy -1.778 -1.8796) (xy 1.778 -1.8796) (xy 1.778 1.8796)
			)
			(stroke
				(width 0)
				(type default)
			)
			(fill no)
			(layer "F.Fab")
		)
		(pad "D" smd custom
			(at 0 -0.9525 90)
			(size 0.1905 0.1905)
			(layers "F.Cu" "F.Mask" "F.Paste")
			(net "P12V_MOST10_GATE")
			(options
				(clearance outline)
				(anchor circle)
			)
			(primitives
				(gr_poly
					(pts
						(arc
							(start -0.1778 0.5715)
							(mid -0.321484 0.511984)
							(end -0.381 0.3683)
						)
						(arc
							(start -0.381 -0.3683)
							(mid -0.321484 -0.511984)
							(end -0.1778 -0.5715)
						)
						(arc
							(start 0.1778 -0.5715)
							(mid 0.321484 -0.511984)
							(end 0.381 -0.3683)
						)
						(arc
							(start 0.381 0.3683)
							(mid 0.321484 0.511984)
							(end 0.1778 0.5715)
						)
					)
					(width 0)
					(fill yes)
				)
			)
		)
		(pad "G" smd custom
			(at -0.98425 0.9525 90)
			(size 0.1905 0.1905)
			(layers "F.Cu" "F.Mask" "F.Paste")
			(net "SSD10_PWREN_R")
			(options
				(clearance outline)
				(anchor circle)
			)
			(primitives
				(gr_poly
					(pts
						(arc
							(start -0.1778 0.5715)
							(mid -0.321484 0.511984)
							(end -0.381 0.3683)
						)
						(arc
							(start -0.381 -0.3683)
							(mid -0.321484 -0.511984)
							(end -0.1778 -0.5715)
						)
						(arc
							(start 0.1778 -0.5715)
							(mid 0.321484 -0.511984)
							(end 0.381 -0.3683)
						)
						(arc
							(start 0.381 0.3683)
							(mid 0.321484 0.511984)
							(end 0.1778 0.5715)
						)
					)
					(width 0)
					(fill yes)
				)
			)
		)
		(pad "S" smd custom
			(at 0.98425 0.9525 90)
			(size 0.1905 0.1905)
			(layers "F.Cu" "F.Mask" "F.Paste")
			(net "GND")
			(options
				(clearance outline)
				(anchor circle)
			)
			(primitives
				(gr_poly
					(pts
						(arc
							(start -0.1778 0.5715)
							(mid -0.321484 0.511984)
							(end -0.381 0.3683)
						)
						(arc
							(start -0.381 -0.3683)
							(mid -0.321484 -0.511984)
							(end -0.1778 -0.5715)
						)
						(arc
							(start 0.1778 -0.5715)
							(mid 0.321484 -0.511984)
							(end 0.381 -0.3683)
						)
						(arc
							(start 0.381 0.3683)
							(mid 0.321484 0.511984)
							(end 0.1778 0.5715)
						)
					)
					(width 0)
					(fill yes)
				)
			)
		)
	)
	(footprint ""
		(layer "F.Cu")
		(at 27.0002 -213.6394 180)
		(property "Reference" "PC1251"
			(at 0 0 180)
			(layer "F.SilkS")
			(hide yes)
			(effects
				(font
					(size 1.27 1.27)
				)
			)
		)
		(property "Value" "SC22U25V6KX-GP-U"
			(at -2.860802 -5.279644 180)
			(unlocked yes)
			(layer "F.Fab")
			(hide yes)
			(effects
				(font
					(size 1.016 1.016)
					(thickness 0.1524)
				)
			)
		)
		(property "Device Type" "C1206-TO0D3H75"
			(at -2.860802 -6.803644 180)
			(unlocked yes)
			(layer "F.Fab")
			(hide yes)
			(effects
				(font
					(size 1.016 1.016)
					(thickness 0.1524)
				)
			)
		)
		(duplicate_pad_numbers_are_jumpers no)
		(fp_line
			(start 1.3081 2.3749)
			(end -1.3081 2.3749)
			(stroke
				(width 0.1524)
				(type default)
			)
			(layer "F.SilkS")
		)
		(fp_line
			(start 1.3081 -2.3749)
			(end 1.3081 2.3749)
			(stroke
				(width 0.1524)
				(type default)
			)
			(layer "F.SilkS")
		)
		(fp_line
			(start -1.3081 2.3749)
			(end -1.3081 -2.3749)
			(stroke
				(width 0.1524)
				(type default)
			)
			(layer "F.SilkS")
		)
		(fp_line
			(start -1.3081 -2.3749)
			(end 1.3081 -2.3749)
			(stroke
				(width 0.1524)
				(type default)
			)
			(layer "F.SilkS")
		)
		(fp_rect
			(start -0.8001 1.6002)
			(end 0.8001 -1.6002)
			(stroke
				(width 0)
				(type default)
			)
			(fill no)
			(layer "F.CrtYd")
		)
		(fp_poly
			(pts
				(xy -1.5621 2.4511) (xy -1.5621 1.6002) (xy 0.8001 1.6002) (xy 0.8001 -1.6002) (xy -0.8001 -1.6002)
				(xy -0.8001 1.5875) (xy -1.5621 1.5875) (xy -1.5621 -2.4511) (xy 1.5621 -2.4511) (xy 1.5621 2.4511)
			)
			(stroke
				(width 0)
				(type default)
			)
			(fill no)
			(layer "F.CrtYd")
		)
		(fp_rect
			(start -1.5621 2.4511)
			(end 1.5621 -2.4511)
			(stroke
				(width 0)
				(type default)
			)
			(fill no)
			(layer "F.Fab")
		)
		(pad "1" smd rect
			(at 0 -1.392936 180)
			(size 2.1082 1.4478)
			(layers "F.Cu" "F.Mask" "F.Paste")
			(net "P12V_SSD12")
		)
		(pad "2" smd rect
			(at 0 1.392936 180)
			(size 2.1082 1.4478)
			(layers "F.Cu" "F.Mask" "F.Paste")
			(net "GND")
		)
	)
	(footprint ""
		(layer "F.Cu")
		(at 2.999994 -319.14211 90)
		(property "Reference" "J18"
			(at 0 0 90)
			(layer "F.SilkS")
			(hide yes)
			(effects
				(font
					(size 1.27 1.27)
				)
			)
		)
		(property "Value" "PCISLT200-5-GP-U"
			(at -48.7045 -6.7818 90)
			(unlocked yes)
			(layer "F.Fab")
			(hide yes)
			(effects
				(font
					(size 1.016 1.016)
					(thickness 0.1524)
				)
			)
		)
		(property "Device Type" "G639F200221431HR-U"
			(at -48.7045 -8.3058 90)
			(unlocked yes)
			(layer "F.Fab")
			(hide yes)
			(effects
				(font
					(size 1.016 1.016)
					(thickness 0.1524)
				)
			)
		)
		(duplicate_pad_numbers_are_jumpers no)
		(fp_line
			(start 51.7525 -2.999994)
			(end 51.7525 2.9464)
			(stroke
				(width 0.1524)
				(type default)
			)
			(layer "F.SilkS")
		)
		(fp_line
			(start -3.199892 -2.999994)
			(end 51.7525 -2.999994)
			(stroke
				(width 0.1524)
				(type default)
			)
			(layer "F.SilkS")
		)
		(fp_line
			(start -6.400038 -2.999994)
			(end -51.7525 -2.999994)
			(stroke
				(width 0.1524)
				(type default)
			)
			(layer "F.SilkS")
		)
		(fp_line
			(start -51.7525 -2.999994)
			(end -51.7525 2.9464)
			(stroke
				(width 0.1524)
				(type default)
			)
			(layer "F.SilkS")
		)
		(fp_line
			(start -3.700018 -2.499868)
			(end -3.199892 -2.999994)
			(stroke
				(width 0.1524)
				(type default)
			)
			(layer "F.SilkS")
		)
		(fp_line
			(start -5.899912 -2.499868)
			(end -6.400038 -2.999994)
			(stroke
				(width 0.1524)
				(type default)
			)
			(layer "F.SilkS")
		)
		(fp_line
			(start -3.700018 1.400048)
			(end -3.700018 -2.499868)
			(stroke
				(width 0.1524)
				(type default)
			)
			(layer "F.SilkS")
		)
		(fp_line
			(start -5.899912 1.400048)
			(end -5.899912 -2.499868)
			(stroke
				(width 0.1524)
				(type default)
			)
			(layer "F.SilkS")
		)
		(fp_line
			(start 51.7525 2.9464)
			(end -51.7525 2.9464)
			(stroke
				(width 0.1524)
				(type default)
			)
			(layer "F.SilkS")
		)
		(fp_arc
			(start -3.700018 1.400048)
			(mid -4.800092 2.500122)
			(end -5.900166 1.400048)
			(stroke
				(width 0.1524)
				(type default)
			)
			(layer "F.SilkS")
		)
		(fp_poly
			(pts
				(xy -51.4985 2.6924) (xy -51.4985 -5.3086) (xy -46.6979 -5.3086) (xy -46.6979 -18.796) (xy -41.6941 -18.796)
				(xy -41.6941 -10.795) (xy 41.6941 -10.795) (xy 41.6941 -18.796) (xy 46.6979 -18.796) (xy 46.6979 -5.3086)
				(xy 51.4985 -5.3086) (xy 51.4985 2.6924)
			)
			(stroke
				(width 0)
				(type default)
			)
			(fill no)
			(layer "B.CrtYd")
		)
		(fp_poly
			(pts
				(xy -52.0065 3.2004) (xy -52.0065 -5.8166) (xy -47.2059 -5.8166) (xy -47.2059 -19.304) (xy -41.1861 -19.304)
				(xy -41.1861 -11.303) (xy 41.1861 -11.303) (xy 41.1861 -19.304) (xy 47.2059 -19.304) (xy 47.2059 -5.8166)
				(xy 52.0065 -5.8166) (xy 52.0065 -0.00635) (xy 51.4985 -0.00635) (xy 51.4985 -5.3086) (xy 46.6979 -5.3086)
				(xy 46.6979 -18.796) (xy 41.6941 -18.796) (xy 41.6941 -10.795) (xy -41.6941 -10.795) (xy -41.6941 -18.796)
				(xy -46.6979 -18.796) (xy -46.6979 -5.3086) (xy -51.4985 -5.3086) (xy -51.4985 2.6924) (xy 51.4985 2.6924)
				(xy 51.4985 0.00635) (xy 52.0065 0.00635) (xy 52.0065 3.2004)
			)
			(stroke
				(width 0)
				(type default)
			)
			(fill no)
			(layer "B.CrtYd")
		)
		(fp_poly
			(pts
				(xy -51.4985 2.6924) (xy -51.4985 -5.3086) (xy -46.6979 -5.3086) (xy -46.6979 -18.796) (xy -41.6941 -18.796)
				(xy -41.6941 -10.795) (xy 41.6941 -10.795) (xy 41.6941 -18.796) (xy 46.6979 -18.796) (xy 46.6979 -5.3086)
				(xy 51.4985 -5.3086) (xy 51.4985 2.6924)
			)
			(stroke
				(width 0)
				(type default)
			)
			(fill no)
			(layer "F.CrtYd")
		)
		(fp_poly
			(pts
				(xy -52.0065 3.2004) (xy -52.0065 -5.8166) (xy -47.2059 -5.8166) (xy -47.2059 -19.304) (xy -41.1861 -19.304)
				(xy -41.1861 -11.303) (xy 41.1861 -11.303) (xy 41.1861 -19.304) (xy 47.2059 -19.304) (xy 47.2059 -5.8166)
				(xy 52.0065 -5.8166) (xy 52.0065 -0.00635) (xy 51.4985 -0.00635) (xy 51.4985 -5.3086) (xy 46.6979 -5.3086)
				(xy 46.6979 -18.796) (xy 41.6941 -18.796) (xy 41.6941 -10.795) (xy -41.6941 -10.795) (xy -41.6941 -18.796)
				(xy -46.6979 -18.796) (xy -46.6979 -5.3086) (xy -51.4985 -5.3086) (xy -51.4985 2.6924) (xy 51.4985 2.6924)
				(xy 51.4985 0.00635) (xy 52.0065 0.00635) (xy 52.0065 3.2004)
			)
			(stroke
				(width 0)
				(type default)
			)
			(fill no)
			(layer "F.CrtYd")
		)
		(fp_poly
			(pts
				(xy -52.0065 3.2004) (xy -52.0065 -5.8166) (xy -47.2059 -5.8166) (xy -47.2059 -19.304) (xy -41.1861 -19.304)
				(xy -41.1861 -11.303) (xy 41.1861 -11.303) (xy 41.1861 -19.304) (xy 47.2059 -19.304) (xy 47.2059 -5.8166)
				(xy 52.0065 -5.8166) (xy 52.0065 3.2004)
			)
			(stroke
				(width 0)
				(type default)
			)
			(fill no)
			(layer "B.Fab")
		)
		(fp_poly
			(pts
				(xy -52.0065 3.2004) (xy -52.0065 -5.8166) (xy -47.2059 -5.8166) (xy -47.2059 -19.304) (xy -41.1861 -19.304)
				(xy -41.1861 -11.303) (xy 41.1861 -11.303) (xy 41.1861 -19.304) (xy 47.2059 -19.304) (xy 47.2059 -5.8166)
				(xy 52.0065 -5.8166) (xy 52.0065 3.2004)
			)
			(stroke
				(width 0)
				(type default)
			)
			(fill no)
			(layer "F.Fab")
		)
		(fp_text user "Slit"
			(at 10.2108 -6.5786 90)
			(unlocked yes)
			(layer "F.SilkS")
			(effects
				(font
					(size 1.016 1.016)
					(thickness 0.1524)
				)
				(justify left)
			)
		)
		(pad "" np_thru_hole circle
			(at -47.999904 0 90)
			(size 0.254 0.254)
			(drill 2.2098)
			(layers "*.Cu" "*.Mask")
			(clearance 1.3335)
			(thermal_gap 1.3335)
		)
		(pad "" np_thru_hole circle
			(at 47.999904 0 90)
			(size 0.254 0.254)
			(drill 2.2098)
			(layers "*.Cu" "*.Mask")
			(clearance 1.3335)
			(thermal_gap 1.3335)
		)
		(pad "A1" smd rect
			(at -41.20007 -0.750062 90)
			(size 0.508 2.4892)
			(layers "F.Cu" "F.Mask" "F.Paste")
			(net "GND")
		)
		(pad "A2" smd rect
			(at -40.39997 -0.750062 90)
			(size 0.508 2.4892)
			(layers "F.Cu" "F.Mask" "F.Paste")
			(net "PE_TX3_DR4_N")
		)
		(pad "A3" smd rect
			(at -39.600124 -0.750062 90)
			(size 0.508 2.4892)
			(layers "F.Cu" "F.Mask" "F.Paste")
			(net "PE_TX3_DR4_P")
		)
		(pad "A4" smd rect
			(at -38.800024 -0.750062 90)
			(size 0.508 2.4892)
			(layers "F.Cu" "F.Mask" "F.Paste")
			(net "GND")
		)
		(pad "A5" smd rect
			(at -37.999924 -0.750062 90)
			(size 0.508 2.4892)
			(layers "F.Cu" "F.Mask" "F.Paste")
			(net "GND")
		)
		(pad "A6" smd rect
			(at -37.200078 -0.750062 90)
			(size 0.508 2.4892)
			(layers "F.Cu" "F.Mask" "F.Paste")
			(net "PE_TX4_DR4_N")
		)
		(pad "A7" smd rect
			(at -36.399978 -0.750062 90)
			(size 0.508 2.4892)
			(layers "F.Cu" "F.Mask" "F.Paste")
			(net "PE_TX4_DR4_P")
		)
		(pad "A8" smd rect
			(at -35.599878 -0.750062 90)
			(size 0.508 2.4892)
			(layers "F.Cu" "F.Mask" "F.Paste")
			(net "GND")
		)
		(pad "A9" smd rect
			(at -34.800032 -0.750062 90)
			(size 0.508 2.4892)
			(layers "F.Cu" "F.Mask" "F.Paste")
			(net "SSD3_PERST_N")
		)
		(pad "A10" smd rect
			(at -33.999932 -0.750062 90)
			(size 0.508 2.4892)
			(layers "F.Cu" "F.Mask" "F.Paste")
			(net "SSD3_PWREN")
		)
		(pad "A11" smd rect
			(at -33.200086 -0.750062 90)
			(size 0.508 2.4892)
			(layers "F.Cu" "F.Mask" "F.Paste")
			(net "ATTN_LED_DR3_N")
		)
		(pad "A12" smd rect
			(at -32.399986 -0.750062 90)
			(size 0.508 2.4892)
			(layers "F.Cu" "F.Mask" "F.Paste")
			(net "SSD3_CLK0_OE_R_N")
		)
		(pad "A13" smd rect
			(at -31.599886 -0.750062 90)
			(size 0.508 2.4892)
			(layers "F.Cu" "F.Mask" "F.Paste")
			(net "GND")
		)
		(pad "A14" smd rect
			(at -30.80004 -0.750062 90)
			(size 0.508 2.4892)
			(layers "F.Cu" "F.Mask" "F.Paste")
			(net "PE_TX1_DR3_N")
		)
		(pad "A15" smd rect
			(at -29.99994 -0.750062 90)
			(size 0.508 2.4892)
			(layers "F.Cu" "F.Mask" "F.Paste")
			(net "PE_TX1_DR3_P")
		)
		(pad "A16" smd rect
			(at -29.200094 -0.750062 90)
			(size 0.508 2.4892)
			(layers "F.Cu" "F.Mask" "F.Paste")
			(net "GND")
		)
		(pad "A17" smd rect
			(at -28.399994 -0.750062 90)
			(size 0.508 2.4892)
			(layers "F.Cu" "F.Mask" "F.Paste")
			(net "GND")
		)
		(pad "A18" smd rect
			(at -27.599894 -0.750062 90)
			(size 0.508 2.4892)
			(layers "F.Cu" "F.Mask" "F.Paste")
			(net "PE_TX2_DR3_N")
		)
		(pad "A19" smd rect
			(at -26.800048 -0.750062 90)
			(size 0.508 2.4892)
			(layers "F.Cu" "F.Mask" "F.Paste")
			(net "PE_TX2_DR3_P")
		)
		(pad "A20" smd rect
			(at -25.999948 -0.750062 90)
			(size 0.508 2.4892)
			(layers "F.Cu" "F.Mask" "F.Paste")
			(net "GND")
		)
		(pad "A21" smd rect
			(at -25.200102 -0.750062 90)
			(size 0.508 2.4892)
			(layers "F.Cu" "F.Mask" "F.Paste")
			(net "GND")
		)
		(pad "A22" smd rect
			(at -24.400002 -0.750062 90)
			(size 0.508 2.4892)
			(layers "F.Cu" "F.Mask" "F.Paste")
			(net "PE_TX3_DR3_N")
		)
		(pad "A23" smd rect
			(at -23.599902 -0.750062 90)
			(size 0.508 2.4892)
			(layers "F.Cu" "F.Mask" "F.Paste")
			(net "PE_TX3_DR3_P")
		)
		(pad "A24" smd rect
			(at -22.800056 -0.750062 90)
			(size 0.508 2.4892)
			(layers "F.Cu" "F.Mask" "F.Paste")
			(net "GND")
		)
		(pad "A25" smd rect
			(at -21.999956 -0.750062 90)
			(size 0.508 2.4892)
			(layers "F.Cu" "F.Mask" "F.Paste")
			(net "GND")
		)
		(pad "A26" smd rect
			(at -21.20011 -0.750062 90)
			(size 0.508 2.4892)
			(layers "F.Cu" "F.Mask" "F.Paste")
			(net "PE_TX4_DR3_N")
		)
		(pad "A27" smd rect
			(at -20.40001 -0.750062 90)
			(size 0.508 2.4892)
			(layers "F.Cu" "F.Mask" "F.Paste")
			(net "PE_TX4_DR3_P")
		)
		(pad "A28" smd rect
			(at -19.59991 -0.750062 90)
			(size 0.508 2.4892)
			(layers "F.Cu" "F.Mask" "F.Paste")
			(net "GND")
		)
		(pad "A29" smd rect
			(at -18.800064 -0.750062 90)
			(size 0.508 2.4892)
			(layers "F.Cu" "F.Mask" "F.Paste")
			(net "GND")
		)
		(pad "A30" smd rect
			(at -17.999964 -0.750062 90)
			(size 0.508 2.4892)
			(layers "F.Cu" "F.Mask" "F.Paste")
			(net "PE_TX1_DR7_N")
		)
		(pad "A31" smd rect
			(at -17.200118 -0.750062 90)
			(size 0.508 2.4892)
			(layers "F.Cu" "F.Mask" "F.Paste")
			(net "PE_TX1_DR7_P")
		)
		(pad "A32" smd rect
			(at -16.400018 -0.750062 90)
			(size 0.508 2.4892)
			(layers "F.Cu" "F.Mask" "F.Paste")
			(net "GND")
		)
		(pad "A33" smd rect
			(at -15.599918 -0.750062 90)
			(size 0.508 2.4892)
			(layers "F.Cu" "F.Mask" "F.Paste")
			(net "GND")
		)
		(pad "A34" smd rect
			(at -14.800072 -0.750062 90)
			(size 0.508 2.4892)
			(layers "F.Cu" "F.Mask" "F.Paste")
			(net "PE_TX2_DR7_N")
		)
		(pad "A35" smd rect
			(at -13.999972 -0.750062 90)
			(size 0.508 2.4892)
			(layers "F.Cu" "F.Mask" "F.Paste")
			(net "PE_TX2_DR7_P")
		)
		(pad "A36" smd rect
			(at -13.200126 -0.750062 90)
			(size 0.508 2.4892)
			(layers "F.Cu" "F.Mask" "F.Paste")
			(net "GND")
		)
		(pad "A37" smd rect
			(at -12.400026 -0.750062 90)
			(size 0.508 2.4892)
			(layers "F.Cu" "F.Mask" "F.Paste")
			(net "GND")
		)
		(pad "A38" smd rect
			(at -11.599926 -0.750062 90)
			(size 0.508 2.4892)
			(layers "F.Cu" "F.Mask" "F.Paste")
			(net "PE_TX3_DR7_N")
		)
		(pad "A39" smd rect
			(at -10.80008 -0.750062 90)
			(size 0.508 2.4892)
			(layers "F.Cu" "F.Mask" "F.Paste")
			(net "PE_TX3_DR7_P")
		)
		(pad "A40" smd rect
			(at -9.99998 -0.750062 90)
			(size 0.508 2.4892)
			(layers "F.Cu" "F.Mask" "F.Paste")
			(net "GND")
		)
		(pad "A41" smd rect
			(at -9.19988 -0.750062 90)
			(size 0.508 2.4892)
			(layers "F.Cu" "F.Mask" "F.Paste")
			(net "GND")
		)
		(pad "A42" smd rect
			(at -8.400034 -0.750062 90)
			(size 0.508 2.4892)
			(layers "F.Cu" "F.Mask" "F.Paste")
			(net "PE_TX4_DR7_N")
		)
		(pad "A43" smd rect
			(at -7.599934 -0.750062 90)
			(size 0.508 2.4892)
			(layers "F.Cu" "F.Mask" "F.Paste")
			(net "PE_TX4_DR7_P")
		)
		(pad "A44" smd rect
			(at -6.800088 -0.750062 90)
			(size 0.508 2.4892)
			(layers "F.Cu" "F.Mask" "F.Paste")
			(net "GND")
		)
		(pad "A45" smd rect
			(at -2.800096 -0.750062 90)
			(size 0.508 2.4892)
			(layers "F.Cu" "F.Mask" "F.Paste")
			(net "ATTN_LED_DR7_N")
		)
		(pad "A46" smd rect
			(at -1.999996 -0.750062 90)
			(size 0.508 2.4892)
			(layers "F.Cu" "F.Mask" "F.Paste")
			(net "SSD7_CLK0_OE_R_N")
		)
		(pad "A47" smd rect
			(at -1.199896 -0.750062 90)
			(size 0.508 2.4892)
			(layers "F.Cu" "F.Mask" "F.Paste")
			(net "GND")
		)
		(pad "A48" smd rect
			(at -0.40005 -0.750062 90)
			(size 0.508 2.4892)
			(layers "F.Cu" "F.Mask" "F.Paste")
			(net "PE_TX1_DR2_N")
		)
		(pad "A49" smd rect
			(at 0.40005 -0.750062 90)
			(size 0.508 2.4892)
			(layers "F.Cu" "F.Mask" "F.Paste")
			(net "PE_TX1_DR2_P")
		)
		(pad "A50" smd rect
			(at 1.199896 -0.750062 90)
			(size 0.508 2.4892)
			(layers "F.Cu" "F.Mask" "F.Paste")
			(net "GND")
		)
		(pad "A51" smd rect
			(at 1.999996 -0.750062 90)
			(size 0.508 2.4892)
			(layers "F.Cu" "F.Mask" "F.Paste")
			(net "GND")
		)
		(pad "A52" smd rect
			(at 2.800096 -0.750062 90)
			(size 0.508 2.4892)
			(layers "F.Cu" "F.Mask" "F.Paste")
			(net "PE_TX2_DR2_N")
		)
		(pad "A53" smd rect
			(at 3.599942 -0.750062 90)
			(size 0.508 2.4892)
			(layers "F.Cu" "F.Mask" "F.Paste")
			(net "PE_TX2_DR2_P")
		)
		(pad "A54" smd rect
			(at 4.400042 -0.750062 90)
			(size 0.508 2.4892)
			(layers "F.Cu" "F.Mask" "F.Paste")
			(net "GND")
		)
		(pad "A55" smd rect
			(at 5.199888 -0.750062 90)
			(size 0.508 2.4892)
			(layers "F.Cu" "F.Mask" "F.Paste")
			(net "GND")
		)
		(pad "A56" smd rect
			(at 5.999988 -0.750062 90)
			(size 0.508 2.4892)
			(layers "F.Cu" "F.Mask" "F.Paste")
			(net "PE_TX3_DR2_N")
		)
		(pad "A57" smd rect
			(at 6.800088 -0.750062 90)
			(size 0.508 2.4892)
			(layers "F.Cu" "F.Mask" "F.Paste")
			(net "PE_TX3_DR2_P")
		)
		(pad "A58" smd rect
			(at 7.599934 -0.750062 90)
			(size 0.508 2.4892)
			(layers "F.Cu" "F.Mask" "F.Paste")
			(net "GND")
		)
		(pad "A59" smd rect
			(at 8.400034 -0.750062 90)
			(size 0.508 2.4892)
			(layers "F.Cu" "F.Mask" "F.Paste")
			(net "GND")
		)
		(pad "A60" smd rect
			(at 9.19988 -0.750062 90)
			(size 0.508 2.4892)
			(layers "F.Cu" "F.Mask" "F.Paste")
			(net "PE_TX4_DR2_N")
		)
		(pad "A61" smd rect
			(at 9.99998 -0.750062 90)
			(size 0.508 2.4892)
			(layers "F.Cu" "F.Mask" "F.Paste")
			(net "PE_TX4_DR2_P")
		)
		(pad "A62" smd rect
			(at 10.80008 -0.750062 90)
			(size 0.508 2.4892)
			(layers "F.Cu" "F.Mask" "F.Paste")
			(net "GND")
		)
		(pad "A63" smd rect
			(at 11.599926 -0.750062 90)
			(size 0.508 2.4892)
			(layers "F.Cu" "F.Mask" "F.Paste")
			(net "SSD2_PWREN")
		)
		(pad "A64" smd rect
			(at 12.400026 -0.750062 90)
			(size 0.508 2.4892)
			(layers "F.Cu" "F.Mask" "F.Paste")
			(net "ATTN_LED_DR2_N")
		)
		(pad "A65" smd rect
			(at 13.200126 -0.750062 90)
			(size 0.508 2.4892)
			(layers "F.Cu" "F.Mask" "F.Paste")
			(net "SSD2_CLK0_OE_R_N")
		)
		(pad "A66" smd rect
			(at 13.999972 -0.750062 90)
			(size 0.508 2.4892)
			(layers "F.Cu" "F.Mask" "F.Paste")
			(net "GND")
		)
		(pad "A67" smd rect
			(at 14.800072 -0.750062 90)
			(size 0.508 2.4892)
			(layers "F.Cu" "F.Mask" "F.Paste")
			(net "PE_TX1_DR11_N")
		)
		(pad "A68" smd rect
			(at 15.599918 -0.750062 90)
			(size 0.508 2.4892)
			(layers "F.Cu" "F.Mask" "F.Paste")
			(net "PE_TX1_DR11_P")
		)
		(pad "A69" smd rect
			(at 16.400018 -0.750062 90)
			(size 0.508 2.4892)
			(layers "F.Cu" "F.Mask" "F.Paste")
			(net "GND")
		)
		(pad "A70" smd rect
			(at 17.200118 -0.750062 90)
			(size 0.508 2.4892)
			(layers "F.Cu" "F.Mask" "F.Paste")
			(net "GND")
		)
		(pad "A71" smd rect
			(at 17.999964 -0.750062 90)
			(size 0.508 2.4892)
			(layers "F.Cu" "F.Mask" "F.Paste")
			(net "PE_TX2_DR11_N")
		)
		(pad "A72" smd rect
			(at 18.800064 -0.750062 90)
			(size 0.508 2.4892)
			(layers "F.Cu" "F.Mask" "F.Paste")
			(net "PE_TX2_DR11_P")
		)
		(pad "A73" smd rect
			(at 19.59991 -0.750062 90)
			(size 0.508 2.4892)
			(layers "F.Cu" "F.Mask" "F.Paste")
			(net "GND")
		)
		(pad "A74" smd rect
			(at 20.40001 -0.750062 90)
			(size 0.508 2.4892)
			(layers "F.Cu" "F.Mask" "F.Paste")
			(net "GND")
		)
		(pad "A75" smd rect
			(at 21.20011 -0.750062 90)
			(size 0.508 2.4892)
			(layers "F.Cu" "F.Mask" "F.Paste")
			(net "PE_TX3_DR11_N")
		)
		(pad "A76" smd rect
			(at 21.999956 -0.750062 90)
			(size 0.508 2.4892)
			(layers "F.Cu" "F.Mask" "F.Paste")
			(net "PE_TX3_DR11_P")
		)
		(pad "A77" smd rect
			(at 22.800056 -0.750062 90)
			(size 0.508 2.4892)
			(layers "F.Cu" "F.Mask" "F.Paste")
			(net "GND")
		)
		(pad "A78" smd rect
			(at 23.599902 -0.750062 90)
			(size 0.508 2.4892)
			(layers "F.Cu" "F.Mask" "F.Paste")
			(net "GND")
		)
		(pad "A79" smd rect
			(at 24.400002 -0.750062 90)
			(size 0.508 2.4892)
			(layers "F.Cu" "F.Mask" "F.Paste")
			(net "PE_TX4_DR11_N")
		)
		(pad "A80" smd rect
			(at 25.200102 -0.750062 90)
			(size 0.508 2.4892)
			(layers "F.Cu" "F.Mask" "F.Paste")
			(net "PE_TX4_DR11_P")
		)
		(pad "A81" smd rect
			(at 25.999948 -0.750062 90)
			(size 0.508 2.4892)
			(layers "F.Cu" "F.Mask" "F.Paste")
			(net "GND")
		)
		(pad "A82" smd rect
			(at 26.800048 -0.750062 90)
			(size 0.508 2.4892)
			(layers "F.Cu" "F.Mask" "F.Paste")
			(net "GND")
		)
		(pad "A83" smd rect
			(at 27.599894 -0.750062 90)
			(size 0.508 2.4892)
			(layers "F.Cu" "F.Mask" "F.Paste")
			(net "PE_TX1_DR6_N")
		)
		(pad "A84" smd rect
			(at 28.399994 -0.750062 90)
			(size 0.508 2.4892)
			(layers "F.Cu" "F.Mask" "F.Paste")
			(net "PE_TX1_DR6_P")
		)
		(pad "A85" smd rect
			(at 29.200094 -0.750062 90)
			(size 0.508 2.4892)
			(layers "F.Cu" "F.Mask" "F.Paste")
			(net "GND")
		)
		(pad "A86" smd rect
			(at 29.99994 -0.750062 90)
			(size 0.508 2.4892)
			(layers "F.Cu" "F.Mask" "F.Paste")
			(net "GND")
		)
		(pad "A87" smd rect
			(at 30.80004 -0.750062 90)
			(size 0.508 2.4892)
			(layers "F.Cu" "F.Mask" "F.Paste")
			(net "PE_TX2_DR6_N")
		)
		(pad "A88" smd rect
			(at 31.599886 -0.750062 90)
			(size 0.508 2.4892)
			(layers "F.Cu" "F.Mask" "F.Paste")
			(net "PE_TX2_DR6_P")
		)
		(pad "A89" smd rect
			(at 32.399986 -0.750062 90)
			(size 0.508 2.4892)
			(layers "F.Cu" "F.Mask" "F.Paste")
			(net "GND")
		)
		(pad "A90" smd rect
			(at 33.200086 -0.750062 90)
			(size 0.508 2.4892)
			(layers "F.Cu" "F.Mask" "F.Paste")
			(net "GND")
		)
		(pad "A91" smd rect
			(at 33.999932 -0.750062 90)
			(size 0.508 2.4892)
			(layers "F.Cu" "F.Mask" "F.Paste")
			(net "PE_TX3_DR6_N")
		)
		(pad "A92" smd rect
			(at 34.800032 -0.750062 90)
			(size 0.508 2.4892)
			(layers "F.Cu" "F.Mask" "F.Paste")
			(net "PE_TX3_DR6_P")
		)
		(pad "A93" smd rect
			(at 35.599878 -0.750062 90)
			(size 0.508 2.4892)
			(layers "F.Cu" "F.Mask" "F.Paste")
			(net "GND")
		)
		(pad "A94" smd rect
			(at 36.399978 -0.750062 90)
			(size 0.508 2.4892)
			(layers "F.Cu" "F.Mask" "F.Paste")
			(net "GND")
		)
		(pad "A95" smd rect
			(at 37.200078 -0.750062 90)
			(size 0.508 2.4892)
			(layers "F.Cu" "F.Mask" "F.Paste")
			(net "PE_TX4_DR6_N")
		)
		(pad "A96" smd rect
			(at 37.999924 -0.750062 90)
			(size 0.508 2.4892)
			(layers "F.Cu" "F.Mask" "F.Paste")
			(net "PE_TX4_DR6_P")
		)
		(pad "A97" smd rect
			(at 38.800024 -0.750062 90)
			(size 0.508 2.4892)
			(layers "F.Cu" "F.Mask" "F.Paste")
			(net "GND")
		)
		(pad "A98" smd rect
			(at 39.600124 -0.750062 90)
			(size 0.508 2.4892)
			(layers "F.Cu" "F.Mask" "F.Paste")
			(net "SSD6_CLK0_OE_R_N")
		)
		(pad "A99" smd rect
			(at 40.39997 -0.750062 90)
			(size 0.508 2.4892)
			(layers "F.Cu" "F.Mask" "F.Paste")
			(net "ATTN_LED_DR6_N")
		)
		(pad "A100" smd rect
			(at 41.20007 -0.750062 90)
			(size 0.508 2.4892)
			(layers "F.Cu" "F.Mask" "F.Paste")
			(net "SSD6_PWREN")
		)
		(pad "B1" smd rect
			(at -41.20007 -1.131062 90)
			(size 0.508 2.4892)
			(drill
				(offset 0 0.381)
			)
			(layers "F.Cu" "F.Mask" "F.Paste")
			(net "SSD11_PERST_N")
		)
		(pad "B2" smd rect
			(at -40.39997 -1.131062 90)
			(size 0.508 2.4892)
			(drill
				(offset 0 0.381)
			)
			(layers "F.Cu" "F.Mask" "F.Paste")
			(net "SSD2_PERST_N")
		)
		(pad "B3" smd rect
			(at -39.600124 -1.131062 90)
			(size 0.508 2.4892)
			(drill
				(offset 0 0.381)
			)
			(layers "F.Cu" "F.Mask" "F.Paste")
			(net "GND")
		)
		(pad "B4" smd rect
			(at -38.800024 -1.131062 90)
			(size 0.508 2.4892)
			(drill
				(offset 0 0.381)
			)
			(layers "F.Cu" "F.Mask" "F.Paste")
			(net "PE_RX3_DR4_N")
		)
		(pad "B5" smd rect
			(at -37.999924 -1.131062 90)
			(size 0.508 2.4892)
			(drill
				(offset 0 0.381)
			)
			(layers "F.Cu" "F.Mask" "F.Paste")
			(net "PE_RX3_DR4_P")
		)
		(pad "B6" smd rect
			(at -37.200078 -1.131062 90)
			(size 0.508 2.4892)
			(drill
				(offset 0 0.381)
			)
			(layers "F.Cu" "F.Mask" "F.Paste")
			(net "GND")
		)
		(pad "B7" smd rect
			(at -36.399978 -1.131062 90)
			(size 0.508 2.4892)
			(drill
				(offset 0 0.381)
			)
			(layers "F.Cu" "F.Mask" "F.Paste")
			(net "GND")
		)
		(pad "B8" smd rect
			(at -35.599878 -1.131062 90)
			(size 0.508 2.4892)
			(drill
				(offset 0 0.381)
			)
			(layers "F.Cu" "F.Mask" "F.Paste")
			(net "PE_RX4_DR4_N")
		)
		(pad "B9" smd rect
			(at -34.800032 -1.131062 90)
			(size 0.508 2.4892)
			(drill
				(offset 0 0.381)
			)
			(layers "F.Cu" "F.Mask" "F.Paste")
			(net "PE_RX4_DR4_P")
		)
		(pad "B10" smd rect
			(at -33.999932 -1.131062 90)
			(size 0.508 2.4892)
			(drill
				(offset 0 0.381)
			)
			(layers "F.Cu" "F.Mask" "F.Paste")
			(net "GND")
		)
		(pad "B11" smd rect
			(at -33.200086 -1.131062 90)
			(size 0.508 2.4892)
			(drill
				(offset 0 0.381)
			)
			(layers "F.Cu" "F.Mask" "F.Paste")
			(net "SSD12_PERST_N")
		)
		(pad "B12" smd rect
			(at -32.399986 -1.131062 90)
			(size 0.508 2.4892)
			(drill
				(offset 0 0.381)
			)
			(layers "F.Cu" "F.Mask" "F.Paste")
			(net "SSD12_PWREN")
		)
		(pad "B13" smd rect
			(at -31.599886 -1.131062 90)
			(size 0.508 2.4892)
			(drill
				(offset 0 0.381)
			)
			(layers "F.Cu" "F.Mask" "F.Paste")
			(net "ATTN_LED_DR12_N")
		)
		(pad "B14" smd rect
			(at -30.80004 -1.131062 90)
			(size 0.508 2.4892)
			(drill
				(offset 0 0.381)
			)
			(layers "F.Cu" "F.Mask" "F.Paste")
			(net "SSD12_CLK0_OE_R_N")
		)
		(pad "B15" smd rect
			(at -29.99994 -1.131062 90)
			(size 0.508 2.4892)
			(drill
				(offset 0 0.381)
			)
			(layers "F.Cu" "F.Mask" "F.Paste")
			(net "GND")
		)
		(pad "B16" smd rect
			(at -29.200094 -1.131062 90)
			(size 0.508 2.4892)
			(drill
				(offset 0 0.381)
			)
			(layers "F.Cu" "F.Mask" "F.Paste")
			(net "PE_RX1_DR3_N")
		)
		(pad "B17" smd rect
			(at -28.399994 -1.131062 90)
			(size 0.508 2.4892)
			(drill
				(offset 0 0.381)
			)
			(layers "F.Cu" "F.Mask" "F.Paste")
			(net "PE_RX1_DR3_P")
		)
		(pad "B18" smd rect
			(at -27.599894 -1.131062 90)
			(size 0.508 2.4892)
			(drill
				(offset 0 0.381)
			)
			(layers "F.Cu" "F.Mask" "F.Paste")
			(net "GND")
		)
		(pad "B19" smd rect
			(at -26.800048 -1.131062 90)
			(size 0.508 2.4892)
			(drill
				(offset 0 0.381)
			)
			(layers "F.Cu" "F.Mask" "F.Paste")
			(net "GND")
		)
		(pad "B20" smd rect
			(at -25.999948 -1.131062 90)
			(size 0.508 2.4892)
			(drill
				(offset 0 0.381)
			)
			(layers "F.Cu" "F.Mask" "F.Paste")
			(net "PE_RX2_DR3_N")
		)
		(pad "B21" smd rect
			(at -25.200102 -1.131062 90)
			(size 0.508 2.4892)
			(drill
				(offset 0 0.381)
			)
			(layers "F.Cu" "F.Mask" "F.Paste")
			(net "PE_RX2_DR3_P")
		)
		(pad "B22" smd rect
			(at -24.400002 -1.131062 90)
			(size 0.508 2.4892)
			(drill
				(offset 0 0.381)
			)
			(layers "F.Cu" "F.Mask" "F.Paste")
			(net "GND")
		)
		(pad "B23" smd rect
			(at -23.599902 -1.131062 90)
			(size 0.508 2.4892)
			(drill
				(offset 0 0.381)
			)
			(layers "F.Cu" "F.Mask" "F.Paste")
			(net "GND")
		)
		(pad "B24" smd rect
			(at -22.800056 -1.131062 90)
			(size 0.508 2.4892)
			(drill
				(offset 0 0.381)
			)
			(layers "F.Cu" "F.Mask" "F.Paste")
			(net "PE_RX3_DR3_N")
		)
		(pad "B25" smd rect
			(at -21.999956 -1.131062 90)
			(size 0.508 2.4892)
			(drill
				(offset 0 0.381)
			)
			(layers "F.Cu" "F.Mask" "F.Paste")
			(net "PE_RX3_DR3_P")
		)
		(pad "B26" smd rect
			(at -21.20011 -1.131062 90)
			(size 0.508 2.4892)
			(drill
				(offset 0 0.381)
			)
			(layers "F.Cu" "F.Mask" "F.Paste")
			(net "GND")
		)
		(pad "B27" smd rect
			(at -20.40001 -1.131062 90)
			(size 0.508 2.4892)
			(drill
				(offset 0 0.381)
			)
			(layers "F.Cu" "F.Mask" "F.Paste")
			(net "GND")
		)
		(pad "B28" smd rect
			(at -19.59991 -1.131062 90)
			(size 0.508 2.4892)
			(drill
				(offset 0 0.381)
			)
			(layers "F.Cu" "F.Mask" "F.Paste")
			(net "PE_RX4_DR3_N")
		)
		(pad "B29" smd rect
			(at -18.800064 -1.131062 90)
			(size 0.508 2.4892)
			(drill
				(offset 0 0.381)
			)
			(layers "F.Cu" "F.Mask" "F.Paste")
			(net "PE_RX4_DR3_P")
		)
		(pad "B30" smd rect
			(at -17.999964 -1.131062 90)
			(size 0.508 2.4892)
			(drill
				(offset 0 0.381)
			)
			(layers "F.Cu" "F.Mask" "F.Paste")
			(net "GND")
		)
		(pad "B31" smd rect
			(at -17.200118 -1.131062 90)
			(size 0.508 2.4892)
			(drill
				(offset 0 0.381)
			)
			(layers "F.Cu" "F.Mask" "F.Paste")
			(net "GND")
		)
		(pad "B32" smd rect
			(at -16.400018 -1.131062 90)
			(size 0.508 2.4892)
			(drill
				(offset 0 0.381)
			)
			(layers "F.Cu" "F.Mask" "F.Paste")
			(net "PE_RX1_DR7_N")
		)
		(pad "B33" smd rect
			(at -15.599918 -1.131062 90)
			(size 0.508 2.4892)
			(drill
				(offset 0 0.381)
			)
			(layers "F.Cu" "F.Mask" "F.Paste")
			(net "PE_RX1_DR7_P")
		)
		(pad "B34" smd rect
			(at -14.800072 -1.131062 90)
			(size 0.508 2.4892)
			(drill
				(offset 0 0.381)
			)
			(layers "F.Cu" "F.Mask" "F.Paste")
			(net "GND")
		)
		(pad "B35" smd rect
			(at -13.999972 -1.131062 90)
			(size 0.508 2.4892)
			(drill
				(offset 0 0.381)
			)
			(layers "F.Cu" "F.Mask" "F.Paste")
			(net "GND")
		)
		(pad "B36" smd rect
			(at -13.200126 -1.131062 90)
			(size 0.508 2.4892)
			(drill
				(offset 0 0.381)
			)
			(layers "F.Cu" "F.Mask" "F.Paste")
			(net "PE_RX2_DR7_N")
		)
		(pad "B37" smd rect
			(at -12.400026 -1.131062 90)
			(size 0.508 2.4892)
			(drill
				(offset 0 0.381)
			)
			(layers "F.Cu" "F.Mask" "F.Paste")
			(net "PE_RX2_DR7_P")
		)
		(pad "B38" smd rect
			(at -11.599926 -1.131062 90)
			(size 0.508 2.4892)
			(drill
				(offset 0 0.381)
			)
			(layers "F.Cu" "F.Mask" "F.Paste")
			(net "GND")
		)
		(pad "B39" smd rect
			(at -10.80008 -1.131062 90)
			(size 0.508 2.4892)
			(drill
				(offset 0 0.381)
			)
			(layers "F.Cu" "F.Mask" "F.Paste")
			(net "GND")
		)
		(pad "B40" smd rect
			(at -9.99998 -1.131062 90)
			(size 0.508 2.4892)
			(drill
				(offset 0 0.381)
			)
			(layers "F.Cu" "F.Mask" "F.Paste")
			(net "PE_RX3_DR7_N")
		)
		(pad "B41" smd rect
			(at -9.19988 -1.131062 90)
			(size 0.508 2.4892)
			(drill
				(offset 0 0.381)
			)
			(layers "F.Cu" "F.Mask" "F.Paste")
			(net "PE_RX3_DR7_P")
		)
		(pad "B42" smd rect
			(at -8.400034 -1.131062 90)
			(size 0.508 2.4892)
			(drill
				(offset 0 0.381)
			)
			(layers "F.Cu" "F.Mask" "F.Paste")
			(net "GND")
		)
		(pad "B43" smd rect
			(at -7.599934 -1.131062 90)
			(size 0.508 2.4892)
			(drill
				(offset 0 0.381)
			)
			(layers "F.Cu" "F.Mask" "F.Paste")
			(net "SSD7_PERST_N")
		)
		(pad "B44" smd rect
			(at -6.800088 -1.131062 90)
			(size 0.508 2.4892)
			(drill
				(offset 0 0.381)
			)
			(layers "F.Cu" "F.Mask" "F.Paste")
			(net "SSD7_PWREN")
		)
		(pad "B45" smd rect
			(at -2.800096 -1.131062 90)
			(size 0.508 2.4892)
			(drill
				(offset 0 0.381)
			)
			(layers "F.Cu" "F.Mask" "F.Paste")
			(net "GND")
		)
		(pad "B46" smd rect
			(at -1.999996 -1.131062 90)
			(size 0.508 2.4892)
			(drill
				(offset 0 0.381)
			)
			(layers "F.Cu" "F.Mask" "F.Paste")
			(net "PE_RX4_DR7_N")
		)
		(pad "B47" smd rect
			(at -1.199896 -1.131062 90)
			(size 0.508 2.4892)
			(drill
				(offset 0 0.381)
			)
			(layers "F.Cu" "F.Mask" "F.Paste")
			(net "PE_RX4_DR7_P")
		)
		(pad "B48" smd rect
			(at -0.40005 -1.131062 90)
			(size 0.508 2.4892)
			(drill
				(offset 0 0.381)
			)
			(layers "F.Cu" "F.Mask" "F.Paste")
			(net "GND")
		)
		(pad "B49" smd rect
			(at 0.40005 -1.131062 90)
			(size 0.508 2.4892)
			(drill
				(offset 0 0.381)
			)
			(layers "F.Cu" "F.Mask" "F.Paste")
			(net "GND")
		)
		(pad "B50" smd rect
			(at 1.199896 -1.131062 90)
			(size 0.508 2.4892)
			(drill
				(offset 0 0.381)
			)
			(layers "F.Cu" "F.Mask" "F.Paste")
			(net "PE_RX1_DR2_N")
		)
		(pad "B51" smd rect
			(at 1.999996 -1.131062 90)
			(size 0.508 2.4892)
			(drill
				(offset 0 0.381)
			)
			(layers "F.Cu" "F.Mask" "F.Paste")
			(net "PE_RX1_DR2_P")
		)
		(pad "B52" smd rect
			(at 2.800096 -1.131062 90)
			(size 0.508 2.4892)
			(drill
				(offset 0 0.381)
			)
			(layers "F.Cu" "F.Mask" "F.Paste")
			(net "GND")
		)
		(pad "B53" smd rect
			(at 3.599942 -1.131062 90)
			(size 0.508 2.4892)
			(drill
				(offset 0 0.381)
			)
			(layers "F.Cu" "F.Mask" "F.Paste")
			(net "GND")
		)
		(pad "B54" smd rect
			(at 4.400042 -1.131062 90)
			(size 0.508 2.4892)
			(drill
				(offset 0 0.381)
			)
			(layers "F.Cu" "F.Mask" "F.Paste")
			(net "PE_RX2_DR2_N")
		)
		(pad "B55" smd rect
			(at 5.199888 -1.131062 90)
			(size 0.508 2.4892)
			(drill
				(offset 0 0.381)
			)
			(layers "F.Cu" "F.Mask" "F.Paste")
			(net "PE_RX2_DR2_P")
		)
		(pad "B56" smd rect
			(at 5.999988 -1.131062 90)
			(size 0.508 2.4892)
			(drill
				(offset 0 0.381)
			)
			(layers "F.Cu" "F.Mask" "F.Paste")
			(net "GND")
		)
		(pad "B57" smd rect
			(at 6.800088 -1.131062 90)
			(size 0.508 2.4892)
			(drill
				(offset 0 0.381)
			)
			(layers "F.Cu" "F.Mask" "F.Paste")
			(net "GND")
		)
		(pad "B58" smd rect
			(at 7.599934 -1.131062 90)
			(size 0.508 2.4892)
			(drill
				(offset 0 0.381)
			)
			(layers "F.Cu" "F.Mask" "F.Paste")
			(net "PE_RX3_DR2_N")
		)
		(pad "B59" smd rect
			(at 8.400034 -1.131062 90)
			(size 0.508 2.4892)
			(drill
				(offset 0 0.381)
			)
			(layers "F.Cu" "F.Mask" "F.Paste")
			(net "PE_RX3_DR2_P")
		)
		(pad "B60" smd rect
			(at 9.19988 -1.131062 90)
			(size 0.508 2.4892)
			(drill
				(offset 0 0.381)
			)
			(layers "F.Cu" "F.Mask" "F.Paste")
			(net "GND")
		)
		(pad "B61" smd rect
			(at 9.99998 -1.131062 90)
			(size 0.508 2.4892)
			(drill
				(offset 0 0.381)
			)
			(layers "F.Cu" "F.Mask" "F.Paste")
			(net "GND")
		)
		(pad "B62" smd rect
			(at 10.80008 -1.131062 90)
			(size 0.508 2.4892)
			(drill
				(offset 0 0.381)
			)
			(layers "F.Cu" "F.Mask" "F.Paste")
			(net "PE_RX4_DR2_N")
		)
		(pad "B63" smd rect
			(at 11.599926 -1.131062 90)
			(size 0.508 2.4892)
			(drill
				(offset 0 0.381)
			)
			(layers "F.Cu" "F.Mask" "F.Paste")
			(net "PE_RX4_DR2_P")
		)
		(pad "B64" smd rect
			(at 12.400026 -1.131062 90)
			(size 0.508 2.4892)
			(drill
				(offset 0 0.381)
			)
			(layers "F.Cu" "F.Mask" "F.Paste")
			(net "GND")
		)
		(pad "B65" smd rect
			(at 13.200126 -1.131062 90)
			(size 0.508 2.4892)
			(drill
				(offset 0 0.381)
			)
			(layers "F.Cu" "F.Mask" "F.Paste")
			(net "SSD11_PWREN")
		)
		(pad "B66" smd rect
			(at 13.999972 -1.131062 90)
			(size 0.508 2.4892)
			(drill
				(offset 0 0.381)
			)
			(layers "F.Cu" "F.Mask" "F.Paste")
			(net "ATTN_LED_DR11_N")
		)
		(pad "B67" smd rect
			(at 14.800072 -1.131062 90)
			(size 0.508 2.4892)
			(drill
				(offset 0 0.381)
			)
			(layers "F.Cu" "F.Mask" "F.Paste")
			(net "SSD11_CLK0_OE_R_N")
		)
		(pad "B68" smd rect
			(at 15.599918 -1.131062 90)
			(size 0.508 2.4892)
			(drill
				(offset 0 0.381)
			)
			(layers "F.Cu" "F.Mask" "F.Paste")
			(net "GND")
		)
		(pad "B69" smd rect
			(at 16.400018 -1.131062 90)
			(size 0.508 2.4892)
			(drill
				(offset 0 0.381)
			)
			(layers "F.Cu" "F.Mask" "F.Paste")
			(net "PE_RX1_DR11_N")
		)
		(pad "B70" smd rect
			(at 17.200118 -1.131062 90)
			(size 0.508 2.4892)
			(drill
				(offset 0 0.381)
			)
			(layers "F.Cu" "F.Mask" "F.Paste")
			(net "PE_RX1_DR11_P")
		)
		(pad "B71" smd rect
			(at 17.999964 -1.131062 90)
			(size 0.508 2.4892)
			(drill
				(offset 0 0.381)
			)
			(layers "F.Cu" "F.Mask" "F.Paste")
			(net "GND")
		)
		(pad "B72" smd rect
			(at 18.800064 -1.131062 90)
			(size 0.508 2.4892)
			(drill
				(offset 0 0.381)
			)
			(layers "F.Cu" "F.Mask" "F.Paste")
			(net "GND")
		)
		(pad "B73" smd rect
			(at 19.59991 -1.131062 90)
			(size 0.508 2.4892)
			(drill
				(offset 0 0.381)
			)
			(layers "F.Cu" "F.Mask" "F.Paste")
			(net "PE_RX2_DR11_N")
		)
		(pad "B74" smd rect
			(at 20.40001 -1.131062 90)
			(size 0.508 2.4892)
			(drill
				(offset 0 0.381)
			)
			(layers "F.Cu" "F.Mask" "F.Paste")
			(net "PE_RX2_DR11_P")
		)
		(pad "B75" smd rect
			(at 21.20011 -1.131062 90)
			(size 0.508 2.4892)
			(drill
				(offset 0 0.381)
			)
			(layers "F.Cu" "F.Mask" "F.Paste")
			(net "GND")
		)
		(pad "B76" smd rect
			(at 21.999956 -1.131062 90)
			(size 0.508 2.4892)
			(drill
				(offset 0 0.381)
			)
			(layers "F.Cu" "F.Mask" "F.Paste")
			(net "GND")
		)
		(pad "B77" smd rect
			(at 22.800056 -1.131062 90)
			(size 0.508 2.4892)
			(drill
				(offset 0 0.381)
			)
			(layers "F.Cu" "F.Mask" "F.Paste")
			(net "PE_RX3_DR11_N")
		)
		(pad "B78" smd rect
			(at 23.599902 -1.131062 90)
			(size 0.508 2.4892)
			(drill
				(offset 0 0.381)
			)
			(layers "F.Cu" "F.Mask" "F.Paste")
			(net "PE_RX3_DR11_P")
		)
		(pad "B79" smd rect
			(at 24.400002 -1.131062 90)
			(size 0.508 2.4892)
			(drill
				(offset 0 0.381)
			)
			(layers "F.Cu" "F.Mask" "F.Paste")
			(net "GND")
		)
		(pad "B80" smd rect
			(at 25.200102 -1.131062 90)
			(size 0.508 2.4892)
			(drill
				(offset 0 0.381)
			)
			(layers "F.Cu" "F.Mask" "F.Paste")
			(net "GND")
		)
		(pad "B81" smd rect
			(at 25.999948 -1.131062 90)
			(size 0.508 2.4892)
			(drill
				(offset 0 0.381)
			)
			(layers "F.Cu" "F.Mask" "F.Paste")
			(net "PE_RX4_DR11_N")
		)
		(pad "B82" smd rect
			(at 26.800048 -1.131062 90)
			(size 0.508 2.4892)
			(drill
				(offset 0 0.381)
			)
			(layers "F.Cu" "F.Mask" "F.Paste")
			(net "PE_RX4_DR11_P")
		)
		(pad "B83" smd rect
			(at 27.599894 -1.131062 90)
			(size 0.508 2.4892)
			(drill
				(offset 0 0.381)
			)
			(layers "F.Cu" "F.Mask" "F.Paste")
			(net "GND")
		)
		(pad "B84" smd rect
			(at 28.399994 -1.131062 90)
			(size 0.508 2.4892)
			(drill
				(offset 0 0.381)
			)
			(layers "F.Cu" "F.Mask" "F.Paste")
			(net "GND")
		)
		(pad "B85" smd rect
			(at 29.200094 -1.131062 90)
			(size 0.508 2.4892)
			(drill
				(offset 0 0.381)
			)
			(layers "F.Cu" "F.Mask" "F.Paste")
			(net "PE_RX1_DR6_N")
		)
		(pad "B86" smd rect
			(at 29.99994 -1.131062 90)
			(size 0.508 2.4892)
			(drill
				(offset 0 0.381)
			)
			(layers "F.Cu" "F.Mask" "F.Paste")
			(net "PE_RX1_DR6_P")
		)
		(pad "B87" smd rect
			(at 30.80004 -1.131062 90)
			(size 0.508 2.4892)
			(drill
				(offset 0 0.381)
			)
			(layers "F.Cu" "F.Mask" "F.Paste")
			(net "GND")
		)
		(pad "B88" smd rect
			(at 31.599886 -1.131062 90)
			(size 0.508 2.4892)
			(drill
				(offset 0 0.381)
			)
			(layers "F.Cu" "F.Mask" "F.Paste")
			(net "GND")
		)
		(pad "B89" smd rect
			(at 32.399986 -1.131062 90)
			(size 0.508 2.4892)
			(drill
				(offset 0 0.381)
			)
			(layers "F.Cu" "F.Mask" "F.Paste")
			(net "PE_RX2_DR6_N")
		)
		(pad "B90" smd rect
			(at 33.200086 -1.131062 90)
			(size 0.508 2.4892)
			(drill
				(offset 0 0.381)
			)
			(layers "F.Cu" "F.Mask" "F.Paste")
			(net "PE_RX2_DR6_P")
		)
		(pad "B91" smd rect
			(at 33.999932 -1.131062 90)
			(size 0.508 2.4892)
			(drill
				(offset 0 0.381)
			)
			(layers "F.Cu" "F.Mask" "F.Paste")
			(net "GND")
		)
		(pad "B92" smd rect
			(at 34.800032 -1.131062 90)
			(size 0.508 2.4892)
			(drill
				(offset 0 0.381)
			)
			(layers "F.Cu" "F.Mask" "F.Paste")
			(net "GND")
		)
		(pad "B93" smd rect
			(at 35.599878 -1.131062 90)
			(size 0.508 2.4892)
			(drill
				(offset 0 0.381)
			)
			(layers "F.Cu" "F.Mask" "F.Paste")
			(net "PE_RX3_DR6_N")
		)
		(pad "B94" smd rect
			(at 36.399978 -1.131062 90)
			(size 0.508 2.4892)
			(drill
				(offset 0 0.381)
			)
			(layers "F.Cu" "F.Mask" "F.Paste")
			(net "PE_RX3_DR6_P")
		)
		(pad "B95" smd rect
			(at 37.200078 -1.131062 90)
			(size 0.508 2.4892)
			(drill
				(offset 0 0.381)
			)
			(layers "F.Cu" "F.Mask" "F.Paste")
			(net "GND")
		)
		(pad "B96" smd rect
			(at 37.999924 -1.131062 90)
			(size 0.508 2.4892)
			(drill
				(offset 0 0.381)
			)
			(layers "F.Cu" "F.Mask" "F.Paste")
			(net "GND")
		)
		(pad "B97" smd rect
			(at 38.800024 -1.131062 90)
			(size 0.508 2.4892)
			(drill
				(offset 0 0.381)
			)
			(layers "F.Cu" "F.Mask" "F.Paste")
			(net "PE_RX4_DR6_N")
		)
		(pad "B98" smd rect
			(at 39.600124 -1.131062 90)
			(size 0.508 2.4892)
			(drill
				(offset 0 0.381)
			)
			(layers "F.Cu" "F.Mask" "F.Paste")
			(net "PE_RX4_DR6_P")
		)
		(pad "B99" smd rect
			(at 40.39997 -1.131062 90)
			(size 0.508 2.4892)
			(drill
				(offset 0 0.381)
			)
			(layers "F.Cu" "F.Mask" "F.Paste")
			(net "GND")
		)
		(pad "B100" smd rect
			(at 41.20007 -1.131062 90)
			(size 0.508 2.4892)
			(drill
				(offset 0 0.381)
			)
			(layers "F.Cu" "F.Mask" "F.Paste")
			(net "SSD6_PERST_N")
		)
		(zone
			(layers "F.Cu" "B.Cu" "In1.Cu" "In2.Cu" "In3.Cu" "In4.Cu" "In5.Cu" "In6.Cu")
			(hatch none 0.5)
			(connect_pads
				(clearance 0)
			)
			(min_thickness 0.25)
			(keepout
				(tracks not_allowed)
				(vias allowed)
				(pads allowed)
				(copperpour not_allowed)
				(footprints allowed)
			)
			(placement
				(enabled no)
				(sheetname "")
			)
			(fill
				(thermal_gap 0.5)
				(thermal_bridge_width 0.5)
				(island_removal_mode 0)
			)
			(polygon
				(pts
					(arc
						(start 4.409694 -367.142014)
						(mid 1.590294 -367.142014)
						(end 4.409694 -367.142014)
					)
				)
			)
		)
		(zone
			(layers "F.Cu" "B.Cu" "In1.Cu" "In2.Cu" "In3.Cu" "In4.Cu" "In5.Cu" "In6.Cu")
			(hatch none 0.5)
			(connect_pads
				(clearance 0)
			)
			(min_thickness 0.25)
			(keepout
				(tracks not_allowed)
				(vias allowed)
				(pads allowed)
				(copperpour not_allowed)
				(footprints allowed)
			)
			(placement
				(enabled no)
				(sheetname "")
			)
			(fill
				(thermal_gap 0.5)
				(thermal_bridge_width 0.5)
				(island_removal_mode 0)
			)
			(polygon
				(pts
					(arc
						(start 4.409694 -271.142206)
						(mid 1.590294 -271.142206)
						(end 4.409694 -271.142206)
					)
				)
			)
		)
	)
	(footprint ""
		(layer "F.Cu")
		(at 81.661 -362.1278 -90)
		(property "Reference" "SR991"
			(at 0 0 270)
			(layer "F.SilkS")
			(hide yes)
			(effects
				(font
					(size 1.27 1.27)
				)
			)
		)
		(property "Value" "2KR2F-3-GP"
			(at 0.064008 -3.993896 270)
			(unlocked yes)
			(layer "F.Fab")
			(hide yes)
			(effects
				(font
					(size 1.016 1.016)
					(thickness 0.1524)
				)
			)
		)
		(property "Device Type" "R402H16"
			(at 0.064008 -5.517896 270)
			(unlocked yes)
			(layer "F.Fab")
			(hide yes)
			(effects
				(font
					(size 1.016 1.016)
					(thickness 0.1524)
				)
			)
		)
		(duplicate_pad_numbers_are_jumpers no)
		(fp_line
			(start -0.508 -0.9398)
			(end -0.508 0.9398)
			(stroke
				(width 0.1524)
				(type default)
			)
			(layer "F.SilkS")
		)
		(fp_line
			(start 0.508 -0.9398)
			(end -0.508 -0.9398)
			(stroke
				(width 0.1524)
				(type default)
			)
			(layer "F.SilkS")
		)
		(fp_rect
			(start -0.508 0.9398)
			(end 0.508 -0.9398)
			(stroke
				(width 0)
				(type default)
			)
			(fill no)
			(layer "F.CrtYd")
		)
		(fp_rect
			(start -0.508 0.9398)
			(end 0.508 -0.9398)
			(stroke
				(width 0)
				(type default)
			)
			(fill no)
			(layer "F.Fab")
		)
		(pad "1" smd custom
			(at 0 -0.4445 270)
			(size 0.1397 0.1397)
			(layers "F.Cu" "F.Mask" "F.Paste")
			(net "P3V3")
			(options
				(clearance outline)
				(anchor circle)
			)
			(primitives
				(gr_poly
					(pts
						(arc
							(start -0.1778 -0.2794)
							(mid -0.249642 -0.249642)
							(end -0.2794 -0.1778)
						)
						(arc
							(start -0.2794 0.1778)
							(mid -0.249642 0.249642)
							(end -0.1778 0.2794)
						)
						(arc
							(start 0.1778 0.2794)
							(mid 0.249642 0.249642)
							(end 0.2794 0.1778)
						)
						(arc
							(start 0.2794 -0.1778)
							(mid 0.249642 -0.249642)
							(end 0.1778 -0.2794)
						)
					)
					(width 0)
					(fill yes)
				)
			)
		)
		(pad "2" smd custom
			(at 0 0.4445 270)
			(size 0.1397 0.1397)
			(layers "F.Cu" "F.Mask" "F.Paste")
			(net "SCL_DR1")
			(options
				(clearance outline)
				(anchor circle)
			)
			(primitives
				(gr_poly
					(pts
						(arc
							(start -0.1778 -0.2794)
							(mid -0.249642 -0.249642)
							(end -0.2794 -0.1778)
						)
						(arc
							(start -0.2794 0.1778)
							(mid -0.249642 0.249642)
							(end -0.1778 0.2794)
						)
						(arc
							(start 0.1778 0.2794)
							(mid 0.249642 0.249642)
							(end 0.2794 0.1778)
						)
						(arc
							(start 0.2794 -0.1778)
							(mid 0.249642 -0.249642)
							(end 0.1778 -0.2794)
						)
					)
					(width 0)
					(fill yes)
				)
			)
		)
	)
	(footprint ""
		(layer "F.Cu")
		(at 46.609 -133.858 -90)
		(property "Reference" "R321"
			(at 0 0 270)
			(layer "F.SilkS")
			(hide yes)
			(effects
				(font
					(size 1.27 1.27)
				)
			)
		)
		(property "Value" "0R2J-2-GP"
			(at 0.064008 -3.993896 270)
			(unlocked yes)
			(layer "F.Fab")
			(hide yes)
			(effects
				(font
					(size 1.016 1.016)
					(thickness 0.1524)
				)
			)
		)
		(property "Device Type" "R402H16"
			(at 0.064008 -5.517896 270)
			(unlocked yes)
			(layer "F.Fab")
			(hide yes)
			(effects
				(font
					(size 1.016 1.016)
					(thickness 0.1524)
				)
			)
		)
		(duplicate_pad_numbers_are_jumpers no)
		(fp_line
			(start -0.508 -0.9398)
			(end -0.508 0.9398)
			(stroke
				(width 0.1524)
				(type default)
			)
			(layer "F.SilkS")
		)
		(fp_line
			(start 0.508 -0.9398)
			(end -0.508 -0.9398)
			(stroke
				(width 0.1524)
				(type default)
			)
			(layer "F.SilkS")
		)
		(fp_rect
			(start -0.508 0.9398)
			(end 0.508 -0.9398)
			(stroke
				(width 0)
				(type default)
			)
			(fill no)
			(layer "F.CrtYd")
		)
		(fp_rect
			(start -0.508 0.9398)
			(end 0.508 -0.9398)
			(stroke
				(width 0)
				(type default)
			)
			(fill no)
			(layer "F.Fab")
		)
		(pad "1" smd custom
			(at 0 -0.4445 270)
			(size 0.1397 0.1397)
			(layers "F.Cu" "F.Mask" "F.Paste")
			(net "I2C_B_SCL")
			(options
				(clearance outline)
				(anchor circle)
			)
			(primitives
				(gr_poly
					(pts
						(arc
							(start -0.1778 -0.2794)
							(mid -0.249642 -0.249642)
							(end -0.2794 -0.1778)
						)
						(arc
							(start -0.2794 0.1778)
							(mid -0.249642 0.249642)
							(end -0.1778 0.2794)
						)
						(arc
							(start 0.1778 0.2794)
							(mid 0.249642 0.249642)
							(end 0.2794 0.1778)
						)
						(arc
							(start 0.2794 -0.1778)
							(mid 0.249642 -0.249642)
							(end 0.1778 -0.2794)
						)
					)
					(width 0)
					(fill yes)
				)
			)
		)
		(pad "2" smd custom
			(at 0 0.4445 270)
			(size 0.1397 0.1397)
			(layers "F.Cu" "F.Mask" "F.Paste")
			(net "TMP1_SCL")
			(options
				(clearance outline)
				(anchor circle)
			)
			(primitives
				(gr_poly
					(pts
						(arc
							(start -0.1778 -0.2794)
							(mid -0.249642 -0.249642)
							(end -0.2794 -0.1778)
						)
						(arc
							(start -0.2794 0.1778)
							(mid -0.249642 0.249642)
							(end -0.1778 0.2794)
						)
						(arc
							(start 0.1778 0.2794)
							(mid 0.249642 0.249642)
							(end 0.2794 0.1778)
						)
						(arc
							(start 0.2794 -0.1778)
							(mid 0.249642 -0.249642)
							(end 0.1778 -0.2794)
						)
					)
					(width 0)
					(fill yes)
				)
			)
		)
	)
	(footprint ""
		(layer "F.Cu")
		(at 96.647 -291.719 180)
		(property "Reference" "R9592"
			(at 0 0 180)
			(layer "F.SilkS")
			(hide yes)
			(effects
				(font
					(size 1.27 1.27)
				)
			)
		)
		(property "Value" "10R2F-L-GP"
			(at 0.064008 -3.993896 180)
			(unlocked yes)
			(layer "F.Fab")
			(hide yes)
			(effects
				(font
					(size 1.016 1.016)
					(thickness 0.1524)
				)
			)
		)
		(property "Device Type" "R402H14"
			(at 0.064008 -5.517896 180)
			(unlocked yes)
			(layer "F.Fab")
			(hide yes)
			(effects
				(font
					(size 1.016 1.016)
					(thickness 0.1524)
				)
			)
		)
		(duplicate_pad_numbers_are_jumpers no)
		(fp_line
			(start 0.508 -0.9398)
			(end -0.508 -0.9398)
			(stroke
				(width 0.1524)
				(type default)
			)
			(layer "F.SilkS")
		)
		(fp_line
			(start -0.508 -0.9398)
			(end -0.508 0.9398)
			(stroke
				(width 0.1524)
				(type default)
			)
			(layer "F.SilkS")
		)
		(fp_rect
			(start -0.508 0.9398)
			(end 0.508 -0.9398)
			(stroke
				(width 0)
				(type default)
			)
			(fill no)
			(layer "F.CrtYd")
		)
		(fp_rect
			(start -0.508 0.9398)
			(end 0.508 -0.9398)
			(stroke
				(width 0)
				(type default)
			)
			(fill no)
			(layer "F.Fab")
		)
		(pad "1" smd custom
			(at 0 -0.4445 180)
			(size 0.1397 0.1397)
			(layers "F.Cu" "F.Mask" "F.Paste")
			(net "SSD_PRSNT_NET2")
			(options
				(clearance outline)
				(anchor circle)
			)
			(primitives
				(gr_poly
					(pts
						(arc
							(start -0.1778 -0.2794)
							(mid -0.249642 -0.249642)
							(end -0.2794 -0.1778)
						)
						(arc
							(start -0.2794 0.1778)
							(mid -0.249642 0.249642)
							(end -0.1778 0.2794)
						)
						(arc
							(start 0.1778 0.2794)
							(mid 0.249642 0.249642)
							(end 0.2794 0.1778)
						)
						(arc
							(start 0.2794 -0.1778)
							(mid 0.249642 -0.249642)
							(end 0.1778 -0.2794)
						)
					)
					(width 0)
					(fill yes)
				)
			)
		)
		(pad "2" smd custom
			(at 0 0.4445 180)
			(size 0.1397 0.1397)
			(layers "F.Cu" "F.Mask" "F.Paste")
			(net "SSD_PRSNT2")
			(options
				(clearance outline)
				(anchor circle)
			)
			(primitives
				(gr_poly
					(pts
						(arc
							(start -0.1778 -0.2794)
							(mid -0.249642 -0.249642)
							(end -0.2794 -0.1778)
						)
						(arc
							(start -0.2794 0.1778)
							(mid -0.249642 0.249642)
							(end -0.1778 0.2794)
						)
						(arc
							(start 0.1778 0.2794)
							(mid 0.249642 0.249642)
							(end 0.2794 0.1778)
						)
						(arc
							(start 0.2794 -0.1778)
							(mid 0.249642 -0.249642)
							(end 0.1778 -0.2794)
						)
					)
					(width 0)
					(fill yes)
				)
			)
		)
	)
	(footprint ""
		(layer "F.Cu")
		(at 228.499924 -144.100042)
		(property "Reference" "LED3"
			(at 0 0 0)
			(layer "F.SilkS")
			(hide yes)
			(effects
				(font
					(size 1.27 1.27)
				)
			)
		)
		(property "Value" "LED-RB-4-GP"
			(at 5.88899 1.80848 0)
			(unlocked yes)
			(layer "F.Fab")
			(hide yes)
			(effects
				(font
					(size 1.016 1.016)
					(thickness 0.1524)
				)
			)
		)
		(property "Device Type" "LED1613-4PH20"
			(at 5.88899 0.28448 0)
			(unlocked yes)
			(layer "F.Fab")
			(hide yes)
			(effects
				(font
					(size 1.016 1.016)
					(thickness 0.1524)
				)
			)
		)
		(duplicate_pad_numbers_are_jumpers no)
		(fp_line
			(start -1.4478 -0.9652)
			(end 1.4478 -0.9652)
			(stroke
				(width 0.1524)
				(type default)
			)
			(layer "F.SilkS")
		)
		(fp_line
			(start -1.4478 0.9652)
			(end -1.4478 -0.9652)
			(stroke
				(width 0.1524)
				(type default)
			)
			(layer "F.SilkS")
		)
		(fp_line
			(start -1.4478 0.9652)
			(end -1.4478 -0.9652)
			(stroke
				(width 0.508)
				(type default)
			)
			(layer "F.SilkS")
		)
		(fp_line
			(start 1.4478 -0.9652)
			(end 1.4478 0.9652)
			(stroke
				(width 0.1524)
				(type default)
			)
			(layer "F.SilkS")
		)
		(fp_line
			(start 1.4478 0.9652)
			(end -1.4478 0.9652)
			(stroke
				(width 0.1524)
				(type default)
			)
			(layer "F.SilkS")
		)
		(fp_rect
			(start -0.8001 0.6477)
			(end 0.8001 -0.6477)
			(stroke
				(width 0)
				(type default)
			)
			(fill no)
			(layer "F.CrtYd")
		)
		(fp_poly
			(pts
				(xy -1.7018 1.2192) (xy -1.7018 -0.06223) (xy -0.8001 -0.06223) (xy -0.8001 0.6477) (xy 0.8001 0.6477)
				(xy 0.8001 -0.6477) (xy -0.8001 -0.6477) (xy -0.8001 -0.0635) (xy -1.7018 -0.0635) (xy -1.7018 -1.2192)
				(xy 1.7018 -1.2192) (xy 1.7018 1.2192)
			)
			(stroke
				(width 0)
				(type default)
			)
			(fill no)
			(layer "F.CrtYd")
		)
		(fp_rect
			(start -1.7018 1.2192)
			(end 1.7018 -1.2192)
			(stroke
				(width 0)
				(type default)
			)
			(fill no)
			(layer "F.Fab")
		)
		(pad "1" smd rect
			(at -0.73025 0.4064)
			(size 0.9144 0.6096)
			(layers "F.Cu" "F.Mask" "F.Paste")
			(net "SSD_ACT_DR3_MOS_N")
		)
		(pad "2" smd rect
			(at -0.73025 -0.4064)
			(size 0.9144 0.6096)
			(layers "F.Cu" "F.Mask" "F.Paste")
			(net "ATTN_LED_DR3_MOS_N")
		)
		(pad "3" smd rect
			(at 0.73025 -0.4064)
			(size 0.9144 0.6096)
			(layers "F.Cu" "F.Mask" "F.Paste")
			(net "DRV_ATTN_3")
		)
		(pad "4" smd rect
			(at 0.73025 0.4064)
			(size 0.9144 0.6096)
			(layers "F.Cu" "F.Mask" "F.Paste")
			(net "DRV_ACT_3")
		)
	)
	(footprint ""
		(layer "F.Cu")
		(at 221.615 -371.348 180)
		(property "Reference" "PC1239"
			(at 0 0 180)
			(layer "F.SilkS")
			(hide yes)
			(effects
				(font
					(size 1.27 1.27)
				)
			)
		)
		(property "Value" "SCD1U25V3KX-GP"
			(at 0 -2.8194 180)
			(unlocked yes)
			(layer "F.Fab")
			(hide yes)
			(effects
				(font
					(size 1.016 1.016)
					(thickness 0.1524)
				)
			)
		)
		(property "Device Type" "C603H36"
			(at 0 -4.3434 180)
			(unlocked yes)
			(layer "F.Fab")
			(hide yes)
			(effects
				(font
					(size 1.016 1.016)
					(thickness 0.1524)
				)
			)
		)
		(duplicate_pad_numbers_are_jumpers no)
		(fp_line
			(start 0.508 0)
			(end -0.508 0)
			(stroke
				(width 0.2032)
				(type default)
			)
			(layer "F.SilkS")
		)
		(fp_rect
			(start -0.5842 1.3335)
			(end 0.5842 -1.3335)
			(stroke
				(width 0)
				(type default)
			)
			(fill no)
			(layer "F.CrtYd")
		)
		(fp_rect
			(start -0.5842 1.3335)
			(end 0.5842 -1.3335)
			(stroke
				(width 0)
				(type default)
			)
			(fill no)
			(layer "F.Fab")
		)
		(pad "1" smd custom
			(at 0 -0.762 180)
			(size 0.2159 0.2159)
			(layers "F.Cu" "F.Mask" "F.Paste")
			(net "P3V3")
			(options
				(clearance outline)
				(anchor circle)
			)
			(primitives
				(gr_poly
					(pts
						(arc
							(start -0.3302 -0.4318)
							(mid -0.402042 -0.402042)
							(end -0.4318 -0.3302)
						)
						(arc
							(start -0.4318 0.3302)
							(mid -0.402042 0.402042)
							(end -0.3302 0.4318)
						)
						(arc
							(start 0.3302 0.4318)
							(mid 0.402042 0.402042)
							(end 0.4318 0.3302)
						)
						(arc
							(start 0.4318 -0.3302)
							(mid 0.402042 -0.402042)
							(end 0.3302 -0.4318)
						)
					)
					(width 0)
					(fill yes)
				)
			)
		)
		(pad "2" smd custom
			(at 0 0.762 180)
			(size 0.2159 0.2159)
			(layers "F.Cu" "F.Mask" "F.Paste")
			(net "GND")
			(options
				(clearance outline)
				(anchor circle)
			)
			(primitives
				(gr_poly
					(pts
						(arc
							(start -0.3302 -0.4318)
							(mid -0.402042 -0.402042)
							(end -0.4318 -0.3302)
						)
						(arc
							(start -0.4318 0.3302)
							(mid -0.402042 0.402042)
							(end -0.3302 0.4318)
						)
						(arc
							(start 0.3302 0.4318)
							(mid 0.402042 0.402042)
							(end 0.4318 0.3302)
						)
						(arc
							(start 0.4318 -0.3302)
							(mid 0.402042 -0.402042)
							(end 0.3302 -0.4318)
						)
					)
					(width 0)
					(fill yes)
				)
			)
		)
	)
	(footprint ""
		(layer "F.Cu")
		(at 70.231 -440.182)
		(property "Reference" "R352"
			(at 0 0 0)
			(layer "F.SilkS")
			(hide yes)
			(effects
				(font
					(size 1.27 1.27)
				)
			)
		)
		(property "Value" "0R2J-2-GP"
			(at 0.064008 -3.993896 0)
			(unlocked yes)
			(layer "F.Fab")
			(hide yes)
			(effects
				(font
					(size 1.016 1.016)
					(thickness 0.1524)
				)
			)
		)
		(property "Device Type" "R402H16"
			(at 0.064008 -5.517896 0)
			(unlocked yes)
			(layer "F.Fab")
			(hide yes)
			(effects
				(font
					(size 1.016 1.016)
					(thickness 0.1524)
				)
			)
		)
		(duplicate_pad_numbers_are_jumpers no)
		(fp_line
			(start -0.508 -0.9398)
			(end -0.508 0.9398)
			(stroke
				(width 0.1524)
				(type default)
			)
			(layer "F.SilkS")
		)
		(fp_line
			(start 0.508 -0.9398)
			(end -0.508 -0.9398)
			(stroke
				(width 0.1524)
				(type default)
			)
			(layer "F.SilkS")
		)
		(fp_rect
			(start -0.508 0.9398)
			(end 0.508 -0.9398)
			(stroke
				(width 0)
				(type default)
			)
			(fill no)
			(layer "F.CrtYd")
		)
		(fp_rect
			(start -0.508 0.9398)
			(end 0.508 -0.9398)
			(stroke
				(width 0)
				(type default)
			)
			(fill no)
			(layer "F.Fab")
		)
		(pad "1" smd custom
			(at 0 -0.4445)
			(size 0.1397 0.1397)
			(layers "F.Cu" "F.Mask" "F.Paste")
			(net "EEPROM_SCL")
			(options
				(clearance outline)
				(anchor circle)
			)
			(primitives
				(gr_poly
					(pts
						(arc
							(start -0.1778 -0.2794)
							(mid -0.249642 -0.249642)
							(end -0.2794 -0.1778)
						)
						(arc
							(start -0.2794 0.1778)
							(mid -0.249642 0.249642)
							(end -0.1778 0.2794)
						)
						(arc
							(start 0.1778 0.2794)
							(mid 0.249642 0.249642)
							(end 0.2794 0.1778)
						)
						(arc
							(start 0.2794 -0.1778)
							(mid 0.249642 -0.249642)
							(end 0.1778 -0.2794)
						)
					)
					(width 0)
					(fill yes)
				)
			)
		)
		(pad "2" smd custom
			(at 0 0.4445)
			(size 0.1397 0.1397)
			(layers "F.Cu" "F.Mask" "F.Paste")
			(net "I2C_B_SCL")
			(options
				(clearance outline)
				(anchor circle)
			)
			(primitives
				(gr_poly
					(pts
						(arc
							(start -0.1778 -0.2794)
							(mid -0.249642 -0.249642)
							(end -0.2794 -0.1778)
						)
						(arc
							(start -0.2794 0.1778)
							(mid -0.249642 0.249642)
							(end -0.1778 0.2794)
						)
						(arc
							(start 0.1778 0.2794)
							(mid 0.249642 0.249642)
							(end 0.2794 0.1778)
						)
						(arc
							(start 0.2794 -0.1778)
							(mid 0.249642 -0.249642)
							(end 0.1778 -0.2794)
						)
					)
					(width 0)
					(fill yes)
				)
			)
		)
	)
	(footprint ""
		(layer "F.Cu")
		(at 16.72336 -360.14914 90)
		(property "Reference" "R9950"
			(at 0 0 90)
			(layer "F.SilkS")
			(hide yes)
			(effects
				(font
					(size 1.27 1.27)
				)
			)
		)
		(property "Value" "4K7R2J-2-GP"
			(at 0.064008 -3.993896 90)
			(unlocked yes)
			(layer "F.Fab")
			(hide yes)
			(effects
				(font
					(size 1.016 1.016)
					(thickness 0.1524)
				)
			)
		)
		(property "Device Type" "R402H16"
			(at 0.064008 -5.517896 90)
			(unlocked yes)
			(layer "F.Fab")
			(hide yes)
			(effects
				(font
					(size 1.016 1.016)
					(thickness 0.1524)
				)
			)
		)
		(duplicate_pad_numbers_are_jumpers no)
		(fp_line
			(start 0.508 -0.9398)
			(end -0.508 -0.9398)
			(stroke
				(width 0.1524)
				(type default)
			)
			(layer "F.SilkS")
		)
		(fp_line
			(start -0.508 -0.9398)
			(end -0.508 0.9398)
			(stroke
				(width 0.1524)
				(type default)
			)
			(layer "F.SilkS")
		)
		(fp_rect
			(start -0.508 0.9398)
			(end 0.508 -0.9398)
			(stroke
				(width 0)
				(type default)
			)
			(fill no)
			(layer "F.CrtYd")
		)
		(fp_rect
			(start -0.508 0.9398)
			(end 0.508 -0.9398)
			(stroke
				(width 0)
				(type default)
			)
			(fill no)
			(layer "F.Fab")
		)
		(pad "1" smd custom
			(at 0 -0.4445 90)
			(size 0.1397 0.1397)
			(layers "F.Cu" "F.Mask" "F.Paste")
			(net "P3V3")
			(options
				(clearance outline)
				(anchor circle)
			)
			(primitives
				(gr_poly
					(pts
						(arc
							(start -0.1778 -0.2794)
							(mid -0.249642 -0.249642)
							(end -0.2794 -0.1778)
						)
						(arc
							(start -0.2794 0.1778)
							(mid -0.249642 0.249642)
							(end -0.1778 0.2794)
						)
						(arc
							(start 0.1778 0.2794)
							(mid 0.249642 0.249642)
							(end 0.2794 0.1778)
						)
						(arc
							(start 0.2794 -0.1778)
							(mid 0.249642 -0.249642)
							(end 0.1778 -0.2794)
						)
					)
					(width 0)
					(fill yes)
				)
			)
		)
		(pad "2" smd custom
			(at 0 0.4445 90)
			(size 0.1397 0.1397)
			(layers "F.Cu" "F.Mask" "F.Paste")
			(net "SSD_ACT_DR11_MOS_N")
			(options
				(clearance outline)
				(anchor circle)
			)
			(primitives
				(gr_poly
					(pts
						(arc
							(start -0.1778 -0.2794)
							(mid -0.249642 -0.249642)
							(end -0.2794 -0.1778)
						)
						(arc
							(start -0.2794 0.1778)
							(mid -0.249642 0.249642)
							(end -0.1778 0.2794)
						)
						(arc
							(start 0.1778 0.2794)
							(mid 0.249642 0.249642)
							(end 0.2794 0.1778)
						)
						(arc
							(start 0.2794 -0.1778)
							(mid 0.249642 -0.249642)
							(end 0.1778 -0.2794)
						)
					)
					(width 0)
					(fill yes)
				)
			)
		)
	)
	(footprint ""
		(layer "F.Cu")
		(at 85.8012 -101.2444 180)
		(property "Reference" "R9974"
			(at 0 0 180)
			(layer "F.SilkS")
			(hide yes)
			(effects
				(font
					(size 1.27 1.27)
				)
			)
		)
		(property "Value" "100R1F-GP"
			(at -3.3274 -1.3335 180)
			(unlocked yes)
			(layer "F.Fab")
			(hide yes)
			(effects
				(font
					(size 1.016 1.016)
					(thickness 0.1524)
				)
			)
		)
		(property "Device Type" "R0201H12"
			(at -3.3274 -2.8575 180)
			(unlocked yes)
			(layer "F.Fab")
			(hide yes)
			(effects
				(font
					(size 1.016 1.016)
					(thickness 0.1524)
				)
			)
		)
		(duplicate_pad_numbers_are_jumpers no)
		(fp_rect
			(start -0.2794 0.6477)
			(end 0.2794 -0.6477)
			(stroke
				(width 0)
				(type default)
			)
			(fill no)
			(layer "F.CrtYd")
		)
		(fp_rect
			(start -0.2794 0.6477)
			(end 0.2794 -0.6477)
			(stroke
				(width 0)
				(type default)
			)
			(fill no)
			(layer "F.Fab")
		)
		(pad "1" smd custom
			(at 0 -0.2794 180)
			(size 0.0762 0.0762)
			(layers "F.Cu" "F.Mask" "F.Paste")
			(net "PE_100M_CLK1_N")
			(options
				(clearance outline)
				(anchor circle)
			)
			(primitives
				(gr_poly
					(pts
						(arc
							(start 0.1524 -0.127)
							(mid 0.137521 -0.162921)
							(end 0.1016 -0.1778)
						)
						(arc
							(start -0.1016 -0.1778)
							(mid -0.137521 -0.162921)
							(end -0.1524 -0.127)
						)
						(arc
							(start -0.1524 0.127)
							(mid -0.137521 0.162921)
							(end -0.1016 0.1778)
						)
						(arc
							(start 0.1016 0.1778)
							(mid 0.137521 0.162921)
							(end 0.1524 0.127)
						)
					)
					(width 0)
					(fill yes)
				)
			)
		)
		(pad "2" smd custom
			(at 0 0.2794 180)
			(size 0.0762 0.0762)
			(layers "F.Cu" "F.Mask" "F.Paste")
			(net "PE_100M_CLK1_P")
			(options
				(clearance outline)
				(anchor circle)
			)
			(primitives
				(gr_poly
					(pts
						(arc
							(start 0.1524 -0.127)
							(mid 0.137521 -0.162921)
							(end 0.1016 -0.1778)
						)
						(arc
							(start -0.1016 -0.1778)
							(mid -0.137521 -0.162921)
							(end -0.1524 -0.127)
						)
						(arc
							(start -0.1524 0.127)
							(mid -0.137521 0.162921)
							(end -0.1016 0.1778)
						)
						(arc
							(start 0.1016 0.1778)
							(mid 0.137521 0.162921)
							(end 0.1524 0.127)
						)
					)
					(width 0)
					(fill yes)
				)
			)
		)
	)
	(footprint ""
		(layer "F.Cu")
		(at 38.354 -38.735 180)
		(property "Reference" "Q74"
			(at 0 0 180)
			(layer "F.SilkS")
			(hide yes)
			(effects
				(font
					(size 1.27 1.27)
				)
			)
		)
		(property "Value" "2N7002A-7-GP"
			(at 0.127 -8.9662 180)
			(unlocked yes)
			(layer "F.Fab")
			(hide yes)
			(effects
				(font
					(size 1.016 1.016)
					(thickness 0.1524)
				)
			)
		)
		(property "Device Type" "SOT23DGS2D4H48"
			(at 0.127 -10.4902 180)
			(unlocked yes)
			(layer "F.Fab")
			(hide yes)
			(effects
				(font
					(size 1.016 1.016)
					(thickness 0.1524)
				)
			)
		)
		(duplicate_pad_numbers_are_jumpers no)
		(fp_line
			(start 1.651 1.778)
			(end 1.651 -1.778)
			(stroke
				(width 0.1524)
				(type default)
			)
			(layer "F.SilkS")
		)
		(fp_line
			(start 1.651 -1.778)
			(end -1.651 -1.778)
			(stroke
				(width 0.1524)
				(type default)
			)
			(layer "F.SilkS")
		)
		(fp_line
			(start -1.651 1.778)
			(end 1.651 1.778)
			(stroke
				(width 0.1524)
				(type default)
			)
			(layer "F.SilkS")
		)
		(fp_line
			(start -1.651 -1.778)
			(end -1.651 1.778)
			(stroke
				(width 0.1524)
				(type default)
			)
			(layer "F.SilkS")
		)
		(fp_poly
			(pts
				(xy -1.778 1.8796) (xy -1.778 -1.8796) (xy 1.778 -1.8796) (xy 1.778 1.8796)
			)
			(stroke
				(width 0)
				(type default)
			)
			(fill no)
			(layer "F.CrtYd")
		)
		(fp_poly
			(pts
				(xy -1.778 1.8796) (xy -1.778 -1.8796) (xy 1.778 -1.8796) (xy 1.778 1.8796)
			)
			(stroke
				(width 0)
				(type default)
			)
			(fill no)
			(layer "F.Fab")
		)
		(pad "D" smd custom
			(at 0 -0.9525 180)
			(size 0.1905 0.1905)
			(layers "F.Cu" "F.Mask" "F.Paste")
			(net "SSD9_CLK0_OE_MOS_N")
			(options
				(clearance outline)
				(anchor circle)
			)
			(primitives
				(gr_poly
					(pts
						(arc
							(start -0.1778 0.5715)
							(mid -0.321484 0.511984)
							(end -0.381 0.3683)
						)
						(arc
							(start -0.381 -0.3683)
							(mid -0.321484 -0.511984)
							(end -0.1778 -0.5715)
						)
						(arc
							(start 0.1778 -0.5715)
							(mid 0.321484 -0.511984)
							(end 0.381 -0.3683)
						)
						(arc
							(start 0.381 0.3683)
							(mid 0.321484 0.511984)
							(end 0.1778 0.5715)
						)
					)
					(width 0)
					(fill yes)
				)
			)
		)
		(pad "G" smd custom
			(at -0.98425 0.9525 180)
			(size 0.1905 0.1905)
			(layers "F.Cu" "F.Mask" "F.Paste")
			(net "SSD9_CLK0_OE_R_N")
			(options
				(clearance outline)
				(anchor circle)
			)
			(primitives
				(gr_poly
					(pts
						(arc
							(start -0.1778 0.5715)
							(mid -0.321484 0.511984)
							(end -0.381 0.3683)
						)
						(arc
							(start -0.381 -0.3683)
							(mid -0.321484 -0.511984)
							(end -0.1778 -0.5715)
						)
						(arc
							(start 0.1778 -0.5715)
							(mid 0.321484 -0.511984)
							(end 0.381 -0.3683)
						)
						(arc
							(start 0.381 0.3683)
							(mid 0.321484 0.511984)
							(end 0.1778 0.5715)
						)
					)
					(width 0)
					(fill yes)
				)
			)
		)
		(pad "S" smd custom
			(at 0.98425 0.9525 180)
			(size 0.1905 0.1905)
			(layers "F.Cu" "F.Mask" "F.Paste")
			(net "GND")
			(options
				(clearance outline)
				(anchor circle)
			)
			(primitives
				(gr_poly
					(pts
						(arc
							(start -0.1778 0.5715)
							(mid -0.321484 0.511984)
							(end -0.381 0.3683)
						)
						(arc
							(start -0.381 -0.3683)
							(mid -0.321484 -0.511984)
							(end -0.1778 -0.5715)
						)
						(arc
							(start 0.1778 -0.5715)
							(mid 0.321484 -0.511984)
							(end 0.381 -0.3683)
						)
						(arc
							(start 0.381 0.3683)
							(mid 0.321484 0.511984)
							(end 0.1778 0.5715)
						)
					)
					(width 0)
					(fill yes)
				)
			)
		)
	)
	(footprint ""
		(layer "F.Cu")
		(at 225.552 -40.894 90)
		(property "Reference" "R9916"
			(at 0 0 90)
			(layer "F.SilkS")
			(hide yes)
			(effects
				(font
					(size 1.27 1.27)
				)
			)
		)
		(property "Value" "47KR2J-2-GP"
			(at 0.064008 -3.993896 90)
			(unlocked yes)
			(layer "F.Fab")
			(hide yes)
			(effects
				(font
					(size 1.016 1.016)
					(thickness 0.1524)
				)
			)
		)
		(property "Device Type" "R402H16"
			(at 0.064008 -5.517896 90)
			(unlocked yes)
			(layer "F.Fab")
			(hide yes)
			(effects
				(font
					(size 1.016 1.016)
					(thickness 0.1524)
				)
			)
		)
		(duplicate_pad_numbers_are_jumpers no)
		(fp_line
			(start 0.508 -0.9398)
			(end -0.508 -0.9398)
			(stroke
				(width 0.1524)
				(type default)
			)
			(layer "F.SilkS")
		)
		(fp_line
			(start -0.508 -0.9398)
			(end -0.508 0.9398)
			(stroke
				(width 0.1524)
				(type default)
			)
			(layer "F.SilkS")
		)
		(fp_rect
			(start -0.508 0.9398)
			(end 0.508 -0.9398)
			(stroke
				(width 0)
				(type default)
			)
			(fill no)
			(layer "F.CrtYd")
		)
		(fp_rect
			(start -0.508 0.9398)
			(end 0.508 -0.9398)
			(stroke
				(width 0)
				(type default)
			)
			(fill no)
			(layer "F.Fab")
		)
		(pad "1" smd custom
			(at 0 -0.4445 90)
			(size 0.1397 0.1397)
			(layers "F.Cu" "F.Mask" "F.Paste")
			(net "P3V3")
			(options
				(clearance outline)
				(anchor circle)
			)
			(primitives
				(gr_poly
					(pts
						(arc
							(start -0.1778 -0.2794)
							(mid -0.249642 -0.249642)
							(end -0.2794 -0.1778)
						)
						(arc
							(start -0.2794 0.1778)
							(mid -0.249642 0.249642)
							(end -0.1778 0.2794)
						)
						(arc
							(start 0.1778 0.2794)
							(mid 0.249642 0.249642)
							(end 0.2794 0.1778)
						)
						(arc
							(start 0.2794 -0.1778)
							(mid 0.249642 -0.249642)
							(end 0.1778 -0.2794)
						)
					)
					(width 0)
					(fill yes)
				)
			)
		)
		(pad "2" smd custom
			(at 0 0.4445 90)
			(size 0.1397 0.1397)
			(layers "F.Cu" "F.Mask" "F.Paste")
			(net "ATTN_LED_DR4_N")
			(options
				(clearance outline)
				(anchor circle)
			)
			(primitives
				(gr_poly
					(pts
						(arc
							(start -0.1778 -0.2794)
							(mid -0.249642 -0.249642)
							(end -0.2794 -0.1778)
						)
						(arc
							(start -0.2794 0.1778)
							(mid -0.249642 0.249642)
							(end -0.1778 0.2794)
						)
						(arc
							(start 0.1778 0.2794)
							(mid 0.249642 0.249642)
							(end 0.2794 0.1778)
						)
						(arc
							(start 0.2794 -0.1778)
							(mid 0.249642 -0.249642)
							(end 0.1778 -0.2794)
						)
					)
					(width 0)
					(fill yes)
				)
			)
		)
	)
	(footprint ""
		(layer "F.Cu")
		(at 99.949 -310.769)
		(property "Reference" "C8852"
			(at 0 0 0)
			(layer "F.SilkS")
			(hide yes)
			(effects
				(font
					(size 1.27 1.27)
				)
			)
		)
		(property "Value" "SCD1U16V2KX-3GP"
			(at 1.1811 -2.7051 0)
			(unlocked yes)
			(layer "F.Fab")
			(hide yes)
			(effects
				(font
					(size 1.016 1.016)
					(thickness 0.1524)
				)
			)
		)
		(property "Device Type" "C402H22"
			(at 1.1811 -4.2291 0)
			(unlocked yes)
			(layer "F.Fab")
			(hide yes)
			(effects
				(font
					(size 1.016 1.016)
					(thickness 0.1524)
				)
			)
		)
		(duplicate_pad_numbers_are_jumpers no)
		(fp_rect
			(start -0.4318 0.9525)
			(end 0.4318 -0.9525)
			(stroke
				(width 0)
				(type default)
			)
			(fill no)
			(layer "F.CrtYd")
		)
		(fp_rect
			(start -0.4318 0.9525)
			(end 0.4318 -0.9525)
			(stroke
				(width 0)
				(type default)
			)
			(fill no)
			(layer "F.Fab")
		)
		(pad "1" smd custom
			(at 0 -0.4445)
			(size 0.1524 0.1524)
			(layers "F.Cu" "F.Mask" "F.Paste")
			(net "VDD_IO_2")
			(options
				(clearance outline)
				(anchor circle)
			)
			(primitives
				(gr_poly
					(pts
						(arc
							(start 0.3048 -0.2032)
							(mid 0.275042 -0.275042)
							(end 0.2032 -0.3048)
						)
						(arc
							(start -0.2032 -0.3048)
							(mid -0.275042 -0.275042)
							(end -0.3048 -0.2032)
						)
						(arc
							(start -0.3048 0.2032)
							(mid -0.275042 0.275042)
							(end -0.2032 0.3048)
						)
						(arc
							(start 0.2032 0.3048)
							(mid 0.275042 0.275042)
							(end 0.3048 0.2032)
						)
					)
					(width 0)
					(fill yes)
				)
			)
		)
		(pad "2" smd custom
			(at 0 0.4445)
			(size 0.1524 0.1524)
			(layers "F.Cu" "F.Mask" "F.Paste")
			(net "GND")
			(options
				(clearance outline)
				(anchor circle)
			)
			(primitives
				(gr_poly
					(pts
						(arc
							(start 0.3048 -0.2032)
							(mid 0.275042 -0.275042)
							(end 0.2032 -0.3048)
						)
						(arc
							(start -0.2032 -0.3048)
							(mid -0.275042 -0.275042)
							(end -0.3048 -0.2032)
						)
						(arc
							(start -0.3048 0.2032)
							(mid -0.275042 0.275042)
							(end -0.2032 0.3048)
						)
						(arc
							(start 0.2032 0.3048)
							(mid 0.275042 0.275042)
							(end 0.3048 0.2032)
						)
					)
					(width 0)
					(fill yes)
				)
			)
		)
	)
	(footprint ""
		(layer "F.Cu")
		(at 81.788 -145.415 -90)
		(property "Reference" "R427"
			(at 0 0 270)
			(layer "F.SilkS")
			(hide yes)
			(effects
				(font
					(size 1.27 1.27)
				)
			)
		)
		(property "Value" "0R2J-2-GP"
			(at 0.064008 -3.993896 270)
			(unlocked yes)
			(layer "F.Fab")
			(hide yes)
			(effects
				(font
					(size 1.016 1.016)
					(thickness 0.1524)
				)
			)
		)
		(property "Device Type" "R402H16"
			(at 0.064008 -5.517896 270)
			(unlocked yes)
			(layer "F.Fab")
			(hide yes)
			(effects
				(font
					(size 1.016 1.016)
					(thickness 0.1524)
				)
			)
		)
		(duplicate_pad_numbers_are_jumpers no)
		(fp_line
			(start -0.508 -0.9398)
			(end -0.508 0.9398)
			(stroke
				(width 0.1524)
				(type default)
			)
			(layer "F.SilkS")
		)
		(fp_line
			(start 0.508 -0.9398)
			(end -0.508 -0.9398)
			(stroke
				(width 0.1524)
				(type default)
			)
			(layer "F.SilkS")
		)
		(fp_rect
			(start -0.508 0.9398)
			(end 0.508 -0.9398)
			(stroke
				(width 0)
				(type default)
			)
			(fill no)
			(layer "F.CrtYd")
		)
		(fp_rect
			(start -0.508 0.9398)
			(end 0.508 -0.9398)
			(stroke
				(width 0)
				(type default)
			)
			(fill no)
			(layer "F.Fab")
		)
		(pad "1" smd custom
			(at 0 -0.4445 270)
			(size 0.1397 0.1397)
			(layers "F.Cu" "F.Mask" "F.Paste")
			(net "BMC_I2C_SCL_BUF_8")
			(options
				(clearance outline)
				(anchor circle)
			)
			(primitives
				(gr_poly
					(pts
						(arc
							(start -0.1778 -0.2794)
							(mid -0.249642 -0.249642)
							(end -0.2794 -0.1778)
						)
						(arc
							(start -0.2794 0.1778)
							(mid -0.249642 0.249642)
							(end -0.1778 0.2794)
						)
						(arc
							(start 0.1778 0.2794)
							(mid 0.249642 0.249642)
							(end 0.2794 0.1778)
						)
						(arc
							(start 0.2794 -0.1778)
							(mid 0.249642 -0.249642)
							(end 0.1778 -0.2794)
						)
					)
					(width 0)
					(fill yes)
				)
			)
		)
		(pad "2" smd custom
			(at 0 0.4445 270)
			(size 0.1397 0.1397)
			(layers "F.Cu" "F.Mask" "F.Paste")
			(net "I2C8_SCL_R_SW_EU16")
			(options
				(clearance outline)
				(anchor circle)
			)
			(primitives
				(gr_poly
					(pts
						(arc
							(start -0.1778 -0.2794)
							(mid -0.249642 -0.249642)
							(end -0.2794 -0.1778)
						)
						(arc
							(start -0.2794 0.1778)
							(mid -0.249642 0.249642)
							(end -0.1778 0.2794)
						)
						(arc
							(start 0.1778 0.2794)
							(mid 0.249642 0.249642)
							(end 0.2794 0.1778)
						)
						(arc
							(start 0.2794 -0.1778)
							(mid 0.249642 -0.249642)
							(end 0.1778 -0.2794)
						)
					)
					(width 0)
					(fill yes)
				)
			)
		)
	)
	(footprint ""
		(layer "F.Cu")
		(at 85.471 -302.387 90)
		(property "Reference" "PR9038"
			(at 0 0 90)
			(layer "F.SilkS")
			(hide yes)
			(effects
				(font
					(size 1.27 1.27)
				)
			)
		)
		(property "Value" "4K7R2F-GP"
			(at 0.064008 -3.993896 90)
			(unlocked yes)
			(layer "F.Fab")
			(hide yes)
			(effects
				(font
					(size 1.016 1.016)
					(thickness 0.1524)
				)
			)
		)
		(property "Device Type" "R402H16"
			(at 0.064008 -5.517896 90)
			(unlocked yes)
			(layer "F.Fab")
			(hide yes)
			(effects
				(font
					(size 1.016 1.016)
					(thickness 0.1524)
				)
			)
		)
		(duplicate_pad_numbers_are_jumpers no)
		(fp_line
			(start 0.508 -0.9398)
			(end -0.508 -0.9398)
			(stroke
				(width 0.1524)
				(type default)
			)
			(layer "F.SilkS")
		)
		(fp_line
			(start -0.508 -0.9398)
			(end -0.508 0.9398)
			(stroke
				(width 0.1524)
				(type default)
			)
			(layer "F.SilkS")
		)
		(fp_rect
			(start -0.508 0.9398)
			(end 0.508 -0.9398)
			(stroke
				(width 0)
				(type default)
			)
			(fill no)
			(layer "F.CrtYd")
		)
		(fp_rect
			(start -0.508 0.9398)
			(end 0.508 -0.9398)
			(stroke
				(width 0)
				(type default)
			)
			(fill no)
			(layer "F.Fab")
		)
		(pad "1" smd custom
			(at 0 -0.4445 90)
			(size 0.1397 0.1397)
			(layers "F.Cu" "F.Mask" "F.Paste")
			(net "VDD_DIFF_2")
			(options
				(clearance outline)
				(anchor circle)
			)
			(primitives
				(gr_poly
					(pts
						(arc
							(start -0.1778 -0.2794)
							(mid -0.249642 -0.249642)
							(end -0.2794 -0.1778)
						)
						(arc
							(start -0.2794 0.1778)
							(mid -0.249642 0.249642)
							(end -0.1778 0.2794)
						)
						(arc
							(start 0.1778 0.2794)
							(mid 0.249642 0.249642)
							(end 0.2794 0.1778)
						)
						(arc
							(start 0.2794 -0.1778)
							(mid 0.249642 -0.249642)
							(end 0.1778 -0.2794)
						)
					)
					(width 0)
					(fill yes)
				)
			)
		)
		(pad "2" smd custom
			(at 0 0.4445 90)
			(size 0.1397 0.1397)
			(layers "F.Cu" "F.Mask" "F.Paste")
			(net "CLK_BUF_EU2_SMB_A0_TRI")
			(options
				(clearance outline)
				(anchor circle)
			)
			(primitives
				(gr_poly
					(pts
						(arc
							(start -0.1778 -0.2794)
							(mid -0.249642 -0.249642)
							(end -0.2794 -0.1778)
						)
						(arc
							(start -0.2794 0.1778)
							(mid -0.249642 0.249642)
							(end -0.1778 0.2794)
						)
						(arc
							(start 0.1778 0.2794)
							(mid 0.249642 0.249642)
							(end 0.2794 0.1778)
						)
						(arc
							(start 0.2794 -0.1778)
							(mid 0.249642 -0.249642)
							(end 0.1778 -0.2794)
						)
					)
					(width 0)
					(fill yes)
				)
			)
		)
	)
	(footprint ""
		(layer "F.Cu")
		(at 234.061 -40.64 -90)
		(property "Reference" "R9408"
			(at 0 0 270)
			(layer "F.SilkS")
			(hide yes)
			(effects
				(font
					(size 1.27 1.27)
				)
			)
		)
		(property "Value" "100R2J-2-GP"
			(at 0.064008 -3.993896 270)
			(unlocked yes)
			(layer "F.Fab")
			(hide yes)
			(effects
				(font
					(size 1.016 1.016)
					(thickness 0.1524)
				)
			)
		)
		(property "Device Type" "R402H14"
			(at 0.064008 -5.517896 270)
			(unlocked yes)
			(layer "F.Fab")
			(hide yes)
			(effects
				(font
					(size 1.016 1.016)
					(thickness 0.1524)
				)
			)
		)
		(duplicate_pad_numbers_are_jumpers no)
		(fp_line
			(start -0.508 -0.9398)
			(end -0.508 0.9398)
			(stroke
				(width 0.1524)
				(type default)
			)
			(layer "F.SilkS")
		)
		(fp_line
			(start 0.508 -0.9398)
			(end -0.508 -0.9398)
			(stroke
				(width 0.1524)
				(type default)
			)
			(layer "F.SilkS")
		)
		(fp_rect
			(start -0.508 0.9398)
			(end 0.508 -0.9398)
			(stroke
				(width 0)
				(type default)
			)
			(fill no)
			(layer "F.CrtYd")
		)
		(fp_rect
			(start -0.508 0.9398)
			(end 0.508 -0.9398)
			(stroke
				(width 0)
				(type default)
			)
			(fill no)
			(layer "F.Fab")
		)
		(pad "1" smd custom
			(at 0 -0.4445 270)
			(size 0.1397 0.1397)
			(layers "F.Cu" "F.Mask" "F.Paste")
			(net "P3V3")
			(options
				(clearance outline)
				(anchor circle)
			)
			(primitives
				(gr_poly
					(pts
						(arc
							(start -0.1778 -0.2794)
							(mid -0.249642 -0.249642)
							(end -0.2794 -0.1778)
						)
						(arc
							(start -0.2794 0.1778)
							(mid -0.249642 0.249642)
							(end -0.1778 0.2794)
						)
						(arc
							(start 0.1778 0.2794)
							(mid 0.249642 0.249642)
							(end 0.2794 0.1778)
						)
						(arc
							(start 0.2794 -0.1778)
							(mid 0.249642 -0.249642)
							(end 0.1778 -0.2794)
						)
					)
					(width 0)
					(fill yes)
				)
			)
		)
		(pad "2" smd custom
			(at 0 0.4445 270)
			(size 0.1397 0.1397)
			(layers "F.Cu" "F.Mask" "F.Paste")
			(net "DRV_ACT_4")
			(options
				(clearance outline)
				(anchor circle)
			)
			(primitives
				(gr_poly
					(pts
						(arc
							(start -0.1778 -0.2794)
							(mid -0.249642 -0.249642)
							(end -0.2794 -0.1778)
						)
						(arc
							(start -0.2794 0.1778)
							(mid -0.249642 0.249642)
							(end -0.1778 0.2794)
						)
						(arc
							(start 0.1778 0.2794)
							(mid 0.249642 0.249642)
							(end 0.2794 0.1778)
						)
						(arc
							(start 0.2794 -0.1778)
							(mid 0.249642 -0.249642)
							(end 0.1778 -0.2794)
						)
					)
					(width 0)
					(fill yes)
				)
			)
		)
	)
	(footprint ""
		(layer "F.Cu")
		(at 29.7688 -88.9 -90)
		(property "Reference" "U18"
			(at 0 0 270)
			(layer "F.SilkS")
			(hide yes)
			(effects
				(font
					(size 1.27 1.27)
				)
			)
		)
		(property "Value" "P2003EVG-GP"
			(at 0 -11.1252 270)
			(unlocked yes)
			(layer "F.Fab")
			(hide yes)
			(effects
				(font
					(size 1.016 1.016)
					(thickness 0.1524)
				)
			)
		)
		(property "Device Type" "SOIC8H79"
			(at 0 -12.6492 270)
			(unlocked yes)
			(layer "F.Fab")
			(hide yes)
			(effects
				(font
					(size 1.016 1.016)
					(thickness 0.1524)
				)
			)
		)
		(duplicate_pad_numbers_are_jumpers no)
		(fp_line
			(start -2.6162 3.429)
			(end -2.6162 1.4732)
			(stroke
				(width 0.4064)
				(type default)
			)
			(layer "F.SilkS")
		)
		(fp_line
			(start -2.7432 1.4224)
			(end 2.1336 1.4224)
			(stroke
				(width 0.1524)
				(type default)
			)
			(layer "F.SilkS")
		)
		(fp_line
			(start 2.1336 1.4224)
			(end 2.1336 -1.4224)
			(stroke
				(width 0.1524)
				(type default)
			)
			(layer "F.SilkS")
		)
		(fp_line
			(start -2.2352 0)
			(end -2.7432 0.508)
			(stroke
				(width 0.1524)
				(type default)
			)
			(layer "F.SilkS")
		)
		(fp_line
			(start -2.7432 -0.508)
			(end -2.2352 0)
			(stroke
				(width 0.1524)
				(type default)
			)
			(layer "F.SilkS")
		)
		(fp_line
			(start -2.7432 -1.4224)
			(end -2.7432 1.4224)
			(stroke
				(width 0.1524)
				(type default)
			)
			(layer "F.SilkS")
		)
		(fp_line
			(start 2.1336 -1.4224)
			(end -2.7432 -1.4224)
			(stroke
				(width 0.1524)
				(type default)
			)
			(layer "F.SilkS")
		)
		(fp_poly
			(pts
				(xy 2.2098 -1.4224) (xy 2.2098 1.4224) (xy -2.2225 1.4224) (xy -2.2225 -1.4224)
			)
			(stroke
				(width 0)
				(type default)
			)
			(fill yes)
			(layer "F.SilkS")
		)
		(fp_rect
			(start -2.4511 2.9972)
			(end 2.4511 -2.9972)
			(stroke
				(width 0)
				(type default)
			)
			(fill no)
			(layer "F.CrtYd")
		)
		(fp_poly
			(pts
				(xy -2.8194 3.6322) (xy -2.8194 -3.6322) (xy 2.8194 -3.6322) (xy 2.8194 -2.2987) (xy 2.4511 -2.2987)
				(xy 2.4511 -2.9972) (xy -2.4511 -2.9972) (xy -2.4511 2.9972) (xy 2.4511 2.9972) (xy 2.4511 -2.286)
				(xy 2.8194 -2.286) (xy 2.8194 3.6322)
			)
			(stroke
				(width 0)
				(type default)
			)
			(fill no)
			(layer "F.CrtYd")
		)
		(fp_rect
			(start -2.8194 3.6322)
			(end 2.8194 -3.6322)
			(stroke
				(width 0)
				(type default)
			)
			(fill no)
			(layer "F.Fab")
		)
		(pad "1" smd rect
			(at -1.905 2.54 270)
			(size 0.635 1.651)
			(layers "F.Cu" "F.Mask" "F.Paste")
			(net "P12V")
		)
		(pad "2" smd rect
			(at -0.635 2.54 270)
			(size 0.635 1.651)
			(layers "F.Cu" "F.Mask" "F.Paste")
			(net "P12V")
		)
		(pad "3" smd rect
			(at 0.635 2.54 270)
			(size 0.635 1.651)
			(layers "F.Cu" "F.Mask" "F.Paste")
			(net "P12V")
		)
		(pad "4" smd rect
			(at 1.905 2.54 270)
			(size 0.635 1.651)
			(layers "F.Cu" "F.Mask" "F.Paste")
			(net "SW_SSD9_N")
		)
		(pad "5" smd rect
			(at 1.905 -2.54 270)
			(size 0.635 1.651)
			(layers "F.Cu" "F.Mask" "F.Paste")
			(net "P12V_SSD9")
		)
		(pad "6" smd rect
			(at 0.635 -2.54 270)
			(size 0.635 1.651)
			(layers "F.Cu" "F.Mask" "F.Paste")
			(net "P12V_SSD9")
		)
		(pad "7" smd rect
			(at -0.635 -2.54 270)
			(size 0.635 1.651)
			(layers "F.Cu" "F.Mask" "F.Paste")
			(net "P12V_SSD9")
		)
		(pad "8" smd rect
			(at -1.905 -2.54 270)
			(size 0.635 1.651)
			(layers "F.Cu" "F.Mask" "F.Paste")
			(net "P12V_SSD9")
		)
	)
	(footprint ""
		(layer "F.Cu")
		(at 210.312 -87.122)
		(property "Reference" "C386"
			(at 0 0 0)
			(layer "F.SilkS")
			(hide yes)
			(effects
				(font
					(size 1.27 1.27)
				)
			)
		)
		(property "Value" "SCD1U25V2KX-2-GP"
			(at 1.1811 -2.7051 0)
			(unlocked yes)
			(layer "F.Fab")
			(hide yes)
			(effects
				(font
					(size 1.016 1.016)
					(thickness 0.1524)
				)
			)
		)
		(property "Device Type" "C402H22"
			(at 1.1811 -4.2291 0)
			(unlocked yes)
			(layer "F.Fab")
			(hide yes)
			(effects
				(font
					(size 1.016 1.016)
					(thickness 0.1524)
				)
			)
		)
		(duplicate_pad_numbers_are_jumpers no)
		(fp_rect
			(start -0.4318 0.9525)
			(end 0.4318 -0.9525)
			(stroke
				(width 0)
				(type default)
			)
			(fill no)
			(layer "F.CrtYd")
		)
		(fp_rect
			(start -0.4318 0.9525)
			(end 0.4318 -0.9525)
			(stroke
				(width 0)
				(type default)
			)
			(fill no)
			(layer "F.Fab")
		)
		(pad "1" smd custom
			(at 0 -0.4445)
			(size 0.1524 0.1524)
			(layers "F.Cu" "F.Mask" "F.Paste")
			(net "P12V")
			(options
				(clearance outline)
				(anchor circle)
			)
			(primitives
				(gr_poly
					(pts
						(arc
							(start 0.3048 -0.2032)
							(mid 0.275042 -0.275042)
							(end 0.2032 -0.3048)
						)
						(arc
							(start -0.2032 -0.3048)
							(mid -0.275042 -0.275042)
							(end -0.3048 -0.2032)
						)
						(arc
							(start -0.3048 0.2032)
							(mid -0.275042 0.275042)
							(end -0.2032 0.3048)
						)
						(arc
							(start 0.2032 0.3048)
							(mid 0.275042 0.275042)
							(end 0.3048 0.2032)
						)
					)
					(width 0)
					(fill yes)
				)
			)
		)
		(pad "2" smd custom
			(at 0 0.4445)
			(size 0.1524 0.1524)
			(layers "F.Cu" "F.Mask" "F.Paste")
			(net "SW_SSD4_N")
			(options
				(clearance outline)
				(anchor circle)
			)
			(primitives
				(gr_poly
					(pts
						(arc
							(start 0.3048 -0.2032)
							(mid 0.275042 -0.275042)
							(end 0.2032 -0.3048)
						)
						(arc
							(start -0.2032 -0.3048)
							(mid -0.275042 -0.275042)
							(end -0.3048 -0.2032)
						)
						(arc
							(start -0.3048 0.2032)
							(mid -0.275042 0.275042)
							(end -0.2032 0.3048)
						)
						(arc
							(start 0.2032 0.3048)
							(mid 0.275042 0.275042)
							(end 0.3048 0.2032)
						)
					)
					(width 0)
					(fill yes)
				)
			)
		)
	)
	(footprint ""
		(layer "F.Cu")
		(at 86.487 -92.964)
		(property "Reference" "R9124"
			(at 0 0 0)
			(layer "F.SilkS")
			(hide yes)
			(effects
				(font
					(size 1.27 1.27)
				)
			)
		)
		(property "Value" "27R2F-GP"
			(at 0.064008 -3.993896 0)
			(unlocked yes)
			(layer "F.Fab")
			(hide yes)
			(effects
				(font
					(size 1.016 1.016)
					(thickness 0.1524)
				)
			)
		)
		(property "Device Type" "R402H16"
			(at 0.064008 -5.517896 0)
			(unlocked yes)
			(layer "F.Fab")
			(hide yes)
			(effects
				(font
					(size 1.016 1.016)
					(thickness 0.1524)
				)
			)
		)
		(duplicate_pad_numbers_are_jumpers no)
		(fp_line
			(start -0.508 -0.9398)
			(end -0.508 0.9398)
			(stroke
				(width 0.1524)
				(type default)
			)
			(layer "F.SilkS")
		)
		(fp_line
			(start 0.508 -0.9398)
			(end -0.508 -0.9398)
			(stroke
				(width 0.1524)
				(type default)
			)
			(layer "F.SilkS")
		)
		(fp_rect
			(start -0.508 0.9398)
			(end 0.508 -0.9398)
			(stroke
				(width 0)
				(type default)
			)
			(fill no)
			(layer "F.CrtYd")
		)
		(fp_rect
			(start -0.508 0.9398)
			(end 0.508 -0.9398)
			(stroke
				(width 0)
				(type default)
			)
			(fill no)
			(layer "F.Fab")
		)
		(pad "1" smd custom
			(at 0 -0.4445)
			(size 0.1397 0.1397)
			(layers "F.Cu" "F.Mask" "F.Paste")
			(net "PE_CLK_100M_DR9_2_R_P")
			(options
				(clearance outline)
				(anchor circle)
			)
			(primitives
				(gr_poly
					(pts
						(arc
							(start -0.1778 -0.2794)
							(mid -0.249642 -0.249642)
							(end -0.2794 -0.1778)
						)
						(arc
							(start -0.2794 0.1778)
							(mid -0.249642 0.249642)
							(end -0.1778 0.2794)
						)
						(arc
							(start 0.1778 0.2794)
							(mid 0.249642 0.249642)
							(end 0.2794 0.1778)
						)
						(arc
							(start 0.2794 -0.1778)
							(mid 0.249642 -0.249642)
							(end 0.1778 -0.2794)
						)
					)
					(width 0)
					(fill yes)
				)
			)
		)
		(pad "2" smd custom
			(at 0 0.4445)
			(size 0.1397 0.1397)
			(layers "F.Cu" "F.Mask" "F.Paste")
			(net "PE_CLK100M_DR9_2_P")
			(options
				(clearance outline)
				(anchor circle)
			)
			(primitives
				(gr_poly
					(pts
						(arc
							(start -0.1778 -0.2794)
							(mid -0.249642 -0.249642)
							(end -0.2794 -0.1778)
						)
						(arc
							(start -0.2794 0.1778)
							(mid -0.249642 0.249642)
							(end -0.1778 0.2794)
						)
						(arc
							(start 0.1778 0.2794)
							(mid 0.249642 0.249642)
							(end 0.2794 0.1778)
						)
						(arc
							(start 0.2794 -0.1778)
							(mid 0.249642 -0.249642)
							(end 0.1778 -0.2794)
						)
					)
					(width 0)
					(fill yes)
				)
			)
		)
	)
	(footprint ""
		(layer "F.Cu")
		(at 97.028 -197.358 180)
		(property "Reference" "R9597"
			(at 0 0 180)
			(layer "F.SilkS")
			(hide yes)
			(effects
				(font
					(size 1.27 1.27)
				)
			)
		)
		(property "Value" "10R2F-L-GP"
			(at 0.064008 -3.993896 180)
			(unlocked yes)
			(layer "F.Fab")
			(hide yes)
			(effects
				(font
					(size 1.016 1.016)
					(thickness 0.1524)
				)
			)
		)
		(property "Device Type" "R402H14"
			(at 0.064008 -5.517896 180)
			(unlocked yes)
			(layer "F.Fab")
			(hide yes)
			(effects
				(font
					(size 1.016 1.016)
					(thickness 0.1524)
				)
			)
		)
		(duplicate_pad_numbers_are_jumpers no)
		(fp_line
			(start 0.508 -0.9398)
			(end -0.508 -0.9398)
			(stroke
				(width 0.1524)
				(type default)
			)
			(layer "F.SilkS")
		)
		(fp_line
			(start -0.508 -0.9398)
			(end -0.508 0.9398)
			(stroke
				(width 0.1524)
				(type default)
			)
			(layer "F.SilkS")
		)
		(fp_rect
			(start -0.508 0.9398)
			(end 0.508 -0.9398)
			(stroke
				(width 0)
				(type default)
			)
			(fill no)
			(layer "F.CrtYd")
		)
		(fp_rect
			(start -0.508 0.9398)
			(end 0.508 -0.9398)
			(stroke
				(width 0)
				(type default)
			)
			(fill no)
			(layer "F.Fab")
		)
		(pad "1" smd custom
			(at 0 -0.4445 180)
			(size 0.1397 0.1397)
			(layers "F.Cu" "F.Mask" "F.Paste")
			(net "SSD4_CLK0_OE_N")
			(options
				(clearance outline)
				(anchor circle)
			)
			(primitives
				(gr_poly
					(pts
						(arc
							(start -0.1778 -0.2794)
							(mid -0.249642 -0.249642)
							(end -0.2794 -0.1778)
						)
						(arc
							(start -0.2794 0.1778)
							(mid -0.249642 0.249642)
							(end -0.1778 0.2794)
						)
						(arc
							(start 0.1778 0.2794)
							(mid 0.249642 0.249642)
							(end 0.2794 0.1778)
						)
						(arc
							(start 0.2794 -0.1778)
							(mid 0.249642 -0.249642)
							(end 0.1778 -0.2794)
						)
					)
					(width 0)
					(fill yes)
				)
			)
		)
		(pad "2" smd custom
			(at 0 0.4445 180)
			(size 0.1397 0.1397)
			(layers "F.Cu" "F.Mask" "F.Paste")
			(net "SSD4_CLK0_OE_R_N")
			(options
				(clearance outline)
				(anchor circle)
			)
			(primitives
				(gr_poly
					(pts
						(arc
							(start -0.1778 -0.2794)
							(mid -0.249642 -0.249642)
							(end -0.2794 -0.1778)
						)
						(arc
							(start -0.2794 0.1778)
							(mid -0.249642 0.249642)
							(end -0.1778 0.2794)
						)
						(arc
							(start 0.1778 0.2794)
							(mid 0.249642 0.249642)
							(end 0.2794 0.1778)
						)
						(arc
							(start 0.2794 -0.1778)
							(mid 0.249642 -0.249642)
							(end 0.1778 -0.2794)
						)
					)
					(width 0)
					(fill yes)
				)
			)
		)
	)
	(footprint ""
		(layer "F.Cu")
		(at 79.1464 -366.522)
		(property "Reference" "SR986"
			(at 0 0 0)
			(layer "F.SilkS")
			(hide yes)
			(effects
				(font
					(size 1.27 1.27)
				)
			)
		)
		(property "Value" "2KR2F-3-GP"
			(at 0.064008 -3.993896 0)
			(unlocked yes)
			(layer "F.Fab")
			(hide yes)
			(effects
				(font
					(size 1.016 1.016)
					(thickness 0.1524)
				)
			)
		)
		(property "Device Type" "R402H16"
			(at 0.064008 -5.517896 0)
			(unlocked yes)
			(layer "F.Fab")
			(hide yes)
			(effects
				(font
					(size 1.016 1.016)
					(thickness 0.1524)
				)
			)
		)
		(duplicate_pad_numbers_are_jumpers no)
		(fp_line
			(start -0.508 -0.9398)
			(end -0.508 0.9398)
			(stroke
				(width 0.1524)
				(type default)
			)
			(layer "F.SilkS")
		)
		(fp_line
			(start 0.508 -0.9398)
			(end -0.508 -0.9398)
			(stroke
				(width 0.1524)
				(type default)
			)
			(layer "F.SilkS")
		)
		(fp_rect
			(start -0.508 0.9398)
			(end 0.508 -0.9398)
			(stroke
				(width 0)
				(type default)
			)
			(fill no)
			(layer "F.CrtYd")
		)
		(fp_rect
			(start -0.508 0.9398)
			(end 0.508 -0.9398)
			(stroke
				(width 0)
				(type default)
			)
			(fill no)
			(layer "F.Fab")
		)
		(pad "1" smd custom
			(at 0 -0.4445)
			(size 0.1397 0.1397)
			(layers "F.Cu" "F.Mask" "F.Paste")
			(net "P3V3")
			(options
				(clearance outline)
				(anchor circle)
			)
			(primitives
				(gr_poly
					(pts
						(arc
							(start -0.1778 -0.2794)
							(mid -0.249642 -0.249642)
							(end -0.2794 -0.1778)
						)
						(arc
							(start -0.2794 0.1778)
							(mid -0.249642 0.249642)
							(end -0.1778 0.2794)
						)
						(arc
							(start 0.1778 0.2794)
							(mid 0.249642 0.249642)
							(end 0.2794 0.1778)
						)
						(arc
							(start 0.2794 -0.1778)
							(mid 0.249642 -0.249642)
							(end 0.1778 -0.2794)
						)
					)
					(width 0)
					(fill yes)
				)
			)
		)
		(pad "2" smd custom
			(at 0 0.4445)
			(size 0.1397 0.1397)
			(layers "F.Cu" "F.Mask" "F.Paste")
			(net "SDA_DR5")
			(options
				(clearance outline)
				(anchor circle)
			)
			(primitives
				(gr_poly
					(pts
						(arc
							(start -0.1778 -0.2794)
							(mid -0.249642 -0.249642)
							(end -0.2794 -0.1778)
						)
						(arc
							(start -0.2794 0.1778)
							(mid -0.249642 0.249642)
							(end -0.1778 0.2794)
						)
						(arc
							(start 0.1778 0.2794)
							(mid 0.249642 0.249642)
							(end 0.2794 0.1778)
						)
						(arc
							(start 0.2794 -0.1778)
							(mid 0.249642 -0.249642)
							(end 0.1778 -0.2794)
						)
					)
					(width 0)
					(fill yes)
				)
			)
		)
	)
	(footprint ""
		(layer "F.Cu")
		(at 93.726 -439.293 180)
		(property "Reference" "C9418"
			(at 0 0 180)
			(layer "F.SilkS")
			(hide yes)
			(effects
				(font
					(size 1.27 1.27)
				)
			)
		)
		(property "Value" "SCD1U16V2KX-3GP"
			(at 1.1811 -2.7051 180)
			(unlocked yes)
			(layer "F.Fab")
			(hide yes)
			(effects
				(font
					(size 1.016 1.016)
					(thickness 0.1524)
				)
			)
		)
		(property "Device Type" "C402H22"
			(at 1.1811 -4.2291 180)
			(unlocked yes)
			(layer "F.Fab")
			(hide yes)
			(effects
				(font
					(size 1.016 1.016)
					(thickness 0.1524)
				)
			)
		)
		(duplicate_pad_numbers_are_jumpers no)
		(fp_rect
			(start -0.4318 0.9525)
			(end 0.4318 -0.9525)
			(stroke
				(width 0)
				(type default)
			)
			(fill no)
			(layer "F.CrtYd")
		)
		(fp_rect
			(start -0.4318 0.9525)
			(end 0.4318 -0.9525)
			(stroke
				(width 0)
				(type default)
			)
			(fill no)
			(layer "F.Fab")
		)
		(pad "1" smd custom
			(at 0 -0.4445 180)
			(size 0.1524 0.1524)
			(layers "F.Cu" "F.Mask" "F.Paste")
			(net "VDD_DIFF_1")
			(options
				(clearance outline)
				(anchor circle)
			)
			(primitives
				(gr_poly
					(pts
						(arc
							(start 0.3048 -0.2032)
							(mid 0.275042 -0.275042)
							(end 0.2032 -0.3048)
						)
						(arc
							(start -0.2032 -0.3048)
							(mid -0.275042 -0.275042)
							(end -0.3048 -0.2032)
						)
						(arc
							(start -0.3048 0.2032)
							(mid -0.275042 0.275042)
							(end -0.2032 0.3048)
						)
						(arc
							(start 0.2032 0.3048)
							(mid 0.275042 0.275042)
							(end 0.3048 0.2032)
						)
					)
					(width 0)
					(fill yes)
				)
			)
		)
		(pad "2" smd custom
			(at 0 0.4445 180)
			(size 0.1524 0.1524)
			(layers "F.Cu" "F.Mask" "F.Paste")
			(net "GND")
			(options
				(clearance outline)
				(anchor circle)
			)
			(primitives
				(gr_poly
					(pts
						(arc
							(start 0.3048 -0.2032)
							(mid 0.275042 -0.275042)
							(end 0.2032 -0.3048)
						)
						(arc
							(start -0.2032 -0.3048)
							(mid -0.275042 -0.275042)
							(end -0.3048 -0.2032)
						)
						(arc
							(start -0.3048 0.2032)
							(mid -0.275042 0.275042)
							(end -0.2032 0.3048)
						)
						(arc
							(start 0.2032 0.3048)
							(mid 0.275042 0.275042)
							(end 0.3048 0.2032)
						)
					)
					(width 0)
					(fill yes)
				)
			)
		)
	)
	(footprint ""
		(layer "F.Cu")
		(at 28.956 -374.65)
		(property "Reference" "R341"
			(at 0 0 0)
			(layer "F.SilkS")
			(hide yes)
			(effects
				(font
					(size 1.27 1.27)
				)
			)
		)
		(property "Value" "4K7R2F-GP"
			(at 0.064008 -3.993896 0)
			(unlocked yes)
			(layer "F.Fab")
			(hide yes)
			(effects
				(font
					(size 1.016 1.016)
					(thickness 0.1524)
				)
			)
		)
		(property "Device Type" "R402H16"
			(at 0.064008 -5.517896 0)
			(unlocked yes)
			(layer "F.Fab")
			(hide yes)
			(effects
				(font
					(size 1.016 1.016)
					(thickness 0.1524)
				)
			)
		)
		(duplicate_pad_numbers_are_jumpers no)
		(fp_line
			(start -0.508 -0.9398)
			(end -0.508 0.9398)
			(stroke
				(width 0.1524)
				(type default)
			)
			(layer "F.SilkS")
		)
		(fp_line
			(start 0.508 -0.9398)
			(end -0.508 -0.9398)
			(stroke
				(width 0.1524)
				(type default)
			)
			(layer "F.SilkS")
		)
		(fp_rect
			(start -0.508 0.9398)
			(end 0.508 -0.9398)
			(stroke
				(width 0)
				(type default)
			)
			(fill no)
			(layer "F.CrtYd")
		)
		(fp_rect
			(start -0.508 0.9398)
			(end 0.508 -0.9398)
			(stroke
				(width 0)
				(type default)
			)
			(fill no)
			(layer "F.Fab")
		)
		(pad "1" smd custom
			(at 0 -0.4445)
			(size 0.1397 0.1397)
			(layers "F.Cu" "F.Mask" "F.Paste")
			(net "I2C_B_TMP4_A0")
			(options
				(clearance outline)
				(anchor circle)
			)
			(primitives
				(gr_poly
					(pts
						(arc
							(start -0.1778 -0.2794)
							(mid -0.249642 -0.249642)
							(end -0.2794 -0.1778)
						)
						(arc
							(start -0.2794 0.1778)
							(mid -0.249642 0.249642)
							(end -0.1778 0.2794)
						)
						(arc
							(start 0.1778 0.2794)
							(mid 0.249642 0.249642)
							(end 0.2794 0.1778)
						)
						(arc
							(start 0.2794 -0.1778)
							(mid 0.249642 -0.249642)
							(end 0.1778 -0.2794)
						)
					)
					(width 0)
					(fill yes)
				)
			)
		)
		(pad "2" smd custom
			(at 0 0.4445)
			(size 0.1397 0.1397)
			(layers "F.Cu" "F.Mask" "F.Paste")
			(net "GND")
			(options
				(clearance outline)
				(anchor circle)
			)
			(primitives
				(gr_poly
					(pts
						(arc
							(start -0.1778 -0.2794)
							(mid -0.249642 -0.249642)
							(end -0.2794 -0.1778)
						)
						(arc
							(start -0.2794 0.1778)
							(mid -0.249642 0.249642)
							(end -0.1778 0.2794)
						)
						(arc
							(start 0.1778 0.2794)
							(mid 0.249642 0.249642)
							(end 0.2794 0.1778)
						)
						(arc
							(start 0.2794 -0.1778)
							(mid 0.249642 -0.249642)
							(end 0.1778 -0.2794)
						)
					)
					(width 0)
					(fill yes)
				)
			)
		)
	)
	(footprint ""
		(layer "F.Cu")
		(at 24.003 -363.474 -90)
		(property "Reference" "SR1143"
			(at 0 0 270)
			(layer "F.SilkS")
			(hide yes)
			(effects
				(font
					(size 1.27 1.27)
				)
			)
		)
		(property "Value" "4K7R2F-GP"
			(at 0.064008 -3.993896 270)
			(unlocked yes)
			(layer "F.Fab")
			(hide yes)
			(effects
				(font
					(size 1.016 1.016)
					(thickness 0.1524)
				)
			)
		)
		(property "Device Type" "R402H16"
			(at 0.064008 -5.517896 270)
			(unlocked yes)
			(layer "F.Fab")
			(hide yes)
			(effects
				(font
					(size 1.016 1.016)
					(thickness 0.1524)
				)
			)
		)
		(duplicate_pad_numbers_are_jumpers no)
		(fp_line
			(start -0.508 -0.9398)
			(end -0.508 0.9398)
			(stroke
				(width 0.1524)
				(type default)
			)
			(layer "F.SilkS")
		)
		(fp_line
			(start 0.508 -0.9398)
			(end -0.508 -0.9398)
			(stroke
				(width 0.1524)
				(type default)
			)
			(layer "F.SilkS")
		)
		(fp_rect
			(start -0.508 0.9398)
			(end 0.508 -0.9398)
			(stroke
				(width 0)
				(type default)
			)
			(fill no)
			(layer "F.CrtYd")
		)
		(fp_rect
			(start -0.508 0.9398)
			(end 0.508 -0.9398)
			(stroke
				(width 0)
				(type default)
			)
			(fill no)
			(layer "F.Fab")
		)
		(pad "1" smd custom
			(at 0 -0.4445 270)
			(size 0.1397 0.1397)
			(layers "F.Cu" "F.Mask" "F.Paste")
			(net "P3V3")
			(options
				(clearance outline)
				(anchor circle)
			)
			(primitives
				(gr_poly
					(pts
						(arc
							(start -0.1778 -0.2794)
							(mid -0.249642 -0.249642)
							(end -0.2794 -0.1778)
						)
						(arc
							(start -0.2794 0.1778)
							(mid -0.249642 0.249642)
							(end -0.1778 0.2794)
						)
						(arc
							(start 0.1778 0.2794)
							(mid 0.249642 0.249642)
							(end 0.2794 0.1778)
						)
						(arc
							(start 0.2794 -0.1778)
							(mid 0.249642 -0.249642)
							(end 0.1778 -0.2794)
						)
					)
					(width 0)
					(fill yes)
				)
			)
		)
		(pad "2" smd custom
			(at 0 0.4445 270)
			(size 0.1397 0.1397)
			(layers "F.Cu" "F.Mask" "F.Paste")
			(net "SSD11_CLK0_OE_MOS_N")
			(options
				(clearance outline)
				(anchor circle)
			)
			(primitives
				(gr_poly
					(pts
						(arc
							(start -0.1778 -0.2794)
							(mid -0.249642 -0.249642)
							(end -0.2794 -0.1778)
						)
						(arc
							(start -0.2794 0.1778)
							(mid -0.249642 0.249642)
							(end -0.1778 0.2794)
						)
						(arc
							(start 0.1778 0.2794)
							(mid 0.249642 0.249642)
							(end 0.2794 0.1778)
						)
						(arc
							(start 0.2794 -0.1778)
							(mid 0.249642 -0.249642)
							(end 0.1778 -0.2794)
						)
					)
					(width 0)
					(fill yes)
				)
			)
		)
	)
	(footprint ""
		(layer "F.Cu")
		(at 24.3078 -293.2176 180)
		(property "Reference" "R573"
			(at 0 0 180)
			(layer "F.SilkS")
			(hide yes)
			(effects
				(font
					(size 1.27 1.27)
				)
			)
		)
		(property "Value" "300KR2F-GP"
			(at 0.064008 -3.993896 180)
			(unlocked yes)
			(layer "F.Fab")
			(hide yes)
			(effects
				(font
					(size 1.016 1.016)
					(thickness 0.1524)
				)
			)
		)
		(property "Device Type" "R402H16"
			(at 0.064008 -5.517896 180)
			(unlocked yes)
			(layer "F.Fab")
			(hide yes)
			(effects
				(font
					(size 1.016 1.016)
					(thickness 0.1524)
				)
			)
		)
		(duplicate_pad_numbers_are_jumpers no)
		(fp_line
			(start 0.508 -0.9398)
			(end -0.508 -0.9398)
			(stroke
				(width 0.1524)
				(type default)
			)
			(layer "F.SilkS")
		)
		(fp_line
			(start -0.508 -0.9398)
			(end -0.508 0.9398)
			(stroke
				(width 0.1524)
				(type default)
			)
			(layer "F.SilkS")
		)
		(fp_rect
			(start -0.508 0.9398)
			(end 0.508 -0.9398)
			(stroke
				(width 0)
				(type default)
			)
			(fill no)
			(layer "F.CrtYd")
		)
		(fp_rect
			(start -0.508 0.9398)
			(end 0.508 -0.9398)
			(stroke
				(width 0)
				(type default)
			)
			(fill no)
			(layer "F.Fab")
		)
		(pad "1" smd custom
			(at 0 -0.4445 180)
			(size 0.1397 0.1397)
			(layers "F.Cu" "F.Mask" "F.Paste")
			(net "SW_SSD7_N")
			(options
				(clearance outline)
				(anchor circle)
			)
			(primitives
				(gr_poly
					(pts
						(arc
							(start -0.1778 -0.2794)
							(mid -0.249642 -0.249642)
							(end -0.2794 -0.1778)
						)
						(arc
							(start -0.2794 0.1778)
							(mid -0.249642 0.249642)
							(end -0.1778 0.2794)
						)
						(arc
							(start 0.1778 0.2794)
							(mid 0.249642 0.249642)
							(end 0.2794 0.1778)
						)
						(arc
							(start 0.2794 -0.1778)
							(mid 0.249642 -0.249642)
							(end 0.1778 -0.2794)
						)
					)
					(width 0)
					(fill yes)
				)
			)
		)
		(pad "2" smd custom
			(at 0 0.4445 180)
			(size 0.1397 0.1397)
			(layers "F.Cu" "F.Mask" "F.Paste")
			(net "P12V")
			(options
				(clearance outline)
				(anchor circle)
			)
			(primitives
				(gr_poly
					(pts
						(arc
							(start -0.1778 -0.2794)
							(mid -0.249642 -0.249642)
							(end -0.2794 -0.1778)
						)
						(arc
							(start -0.2794 0.1778)
							(mid -0.249642 0.249642)
							(end -0.1778 0.2794)
						)
						(arc
							(start 0.1778 0.2794)
							(mid 0.249642 0.249642)
							(end 0.2794 0.1778)
						)
						(arc
							(start 0.2794 -0.1778)
							(mid 0.249642 -0.249642)
							(end 0.1778 -0.2794)
						)
					)
					(width 0)
					(fill yes)
				)
			)
		)
	)
	(footprint ""
		(layer "F.Cu")
		(at 10.6172 -498.4242)
		(property "Reference" "R9765"
			(at 0 0 0)
			(layer "F.SilkS")
			(hide yes)
			(effects
				(font
					(size 1.27 1.27)
				)
			)
		)
		(property "Value" "4K7R2J-2-GP"
			(at 0.064008 -3.993896 0)
			(unlocked yes)
			(layer "F.Fab")
			(hide yes)
			(effects
				(font
					(size 1.016 1.016)
					(thickness 0.1524)
				)
			)
		)
		(property "Device Type" "R402H16"
			(at 0.064008 -5.517896 0)
			(unlocked yes)
			(layer "F.Fab")
			(hide yes)
			(effects
				(font
					(size 1.016 1.016)
					(thickness 0.1524)
				)
			)
		)
		(duplicate_pad_numbers_are_jumpers no)
		(fp_line
			(start -0.508 -0.9398)
			(end -0.508 0.9398)
			(stroke
				(width 0.1524)
				(type default)
			)
			(layer "F.SilkS")
		)
		(fp_line
			(start 0.508 -0.9398)
			(end -0.508 -0.9398)
			(stroke
				(width 0.1524)
				(type default)
			)
			(layer "F.SilkS")
		)
		(fp_rect
			(start -0.508 0.9398)
			(end 0.508 -0.9398)
			(stroke
				(width 0)
				(type default)
			)
			(fill no)
			(layer "F.CrtYd")
		)
		(fp_rect
			(start -0.508 0.9398)
			(end 0.508 -0.9398)
			(stroke
				(width 0)
				(type default)
			)
			(fill no)
			(layer "F.Fab")
		)
		(pad "1" smd custom
			(at 0 -0.4445)
			(size 0.1397 0.1397)
			(layers "F.Cu" "F.Mask" "F.Paste")
			(net "SSD5_PWREN")
			(options
				(clearance outline)
				(anchor circle)
			)
			(primitives
				(gr_poly
					(pts
						(arc
							(start -0.1778 -0.2794)
							(mid -0.249642 -0.249642)
							(end -0.2794 -0.1778)
						)
						(arc
							(start -0.2794 0.1778)
							(mid -0.249642 0.249642)
							(end -0.1778 0.2794)
						)
						(arc
							(start 0.1778 0.2794)
							(mid 0.249642 0.249642)
							(end 0.2794 0.1778)
						)
						(arc
							(start 0.2794 -0.1778)
							(mid 0.249642 -0.249642)
							(end 0.1778 -0.2794)
						)
					)
					(width 0)
					(fill yes)
				)
			)
		)
		(pad "2" smd custom
			(at 0 0.4445)
			(size 0.1397 0.1397)
			(layers "F.Cu" "F.Mask" "F.Paste")
			(net "GND")
			(options
				(clearance outline)
				(anchor circle)
			)
			(primitives
				(gr_poly
					(pts
						(arc
							(start -0.1778 -0.2794)
							(mid -0.249642 -0.249642)
							(end -0.2794 -0.1778)
						)
						(arc
							(start -0.2794 0.1778)
							(mid -0.249642 0.249642)
							(end -0.1778 0.2794)
						)
						(arc
							(start 0.1778 0.2794)
							(mid 0.249642 0.249642)
							(end 0.2794 0.1778)
						)
						(arc
							(start 0.2794 -0.1778)
							(mid 0.249642 -0.249642)
							(end 0.1778 -0.2794)
						)
					)
					(width 0)
					(fill yes)
				)
			)
		)
	)
	(footprint ""
		(layer "F.Cu")
		(at 98.552 -440.055)
		(property "Reference" "R9582"
			(at 0 0 0)
			(layer "F.SilkS")
			(hide yes)
			(effects
				(font
					(size 1.27 1.27)
				)
			)
		)
		(property "Value" "0R5J-L1-GP"
			(at 0 -8.9535 0)
			(unlocked yes)
			(layer "F.Fab")
			(hide yes)
			(effects
				(font
					(size 1.27 1.016)
					(thickness 0.1524)
				)
			)
		)
		(property "Device Type" "R805H24"
			(at 0 -10.6299 0)
			(unlocked yes)
			(layer "F.Fab")
			(hide yes)
			(effects
				(font
					(size 1.27 1.016)
					(thickness 0.1524)
				)
			)
		)
		(duplicate_pad_numbers_are_jumpers no)
		(fp_line
			(start -0.889 -1.7018)
			(end -0.889 0.2794)
			(stroke
				(width 0.1524)
				(type default)
			)
			(layer "F.SilkS")
		)
		(fp_line
			(start -0.889 0.0762)
			(end -0.889 1.7018)
			(stroke
				(width 0.1524)
				(type default)
			)
			(layer "F.SilkS")
		)
		(fp_line
			(start -0.889 1.7018)
			(end 0.889 1.7018)
			(stroke
				(width 0.1524)
				(type default)
			)
			(layer "F.SilkS")
		)
		(fp_line
			(start 0.889 -1.7018)
			(end -0.889 -1.7018)
			(stroke
				(width 0.1524)
				(type default)
			)
			(layer "F.SilkS")
		)
		(fp_line
			(start 0.889 -1.7018)
			(end 0.889 -0.381)
			(stroke
				(width 0.1524)
				(type default)
			)
			(layer "F.SilkS")
		)
		(fp_line
			(start 0.889 1.7018)
			(end 0.889 -0.508)
			(stroke
				(width 0.1524)
				(type default)
			)
			(layer "F.SilkS")
		)
		(fp_poly
			(pts
				(xy 0.9652 -1.778) (xy 0.9652 1.778) (xy -0.9652 1.778) (xy -0.9652 -1.778)
			)
			(stroke
				(width 0)
				(type default)
			)
			(fill no)
			(layer "F.CrtYd")
		)
		(fp_rect
			(start -0.9652 1.778)
			(end 0.9652 -1.778)
			(stroke
				(width 0)
				(type default)
			)
			(fill no)
			(layer "F.Fab")
		)
		(pad "1" smd rect
			(at 0 -0.9652)
			(size 1.397 1.143)
			(layers "F.Cu" "F.Mask" "F.Paste")
			(net "P3V3")
		)
		(pad "2" smd rect
			(at 0 0.9652)
			(size 1.397 1.143)
			(layers "F.Cu" "F.Mask" "F.Paste")
			(net "VDD_IO_1")
		)
	)
	(footprint ""
		(layer "F.Cu")
		(at 253.499874 -483.497636)
		(property "Reference" "H12"
			(at 0 0 0)
			(layer "F.SilkS")
			(hide yes)
			(effects
				(font
					(size 1.27 1.27)
				)
			)
		)
		(property "Value" "GEN276X162R197X296-6-F-A-GP"
			(at -6.7183 4.1402 0)
			(unlocked yes)
			(layer "F.Fab")
			(hide yes)
			(effects
				(font
					(size 1.016 1.016)
					(thickness 0.1524)
				)
			)
		)
		(property "Device Type" "GEN276X162R197X296-6-F-A"
			(at -6.7183 2.6162 0)
			(unlocked yes)
			(layer "F.Fab")
			(hide yes)
			(effects
				(font
					(size 1.016 1.016)
					(thickness 0.1524)
				)
			)
		)
		(duplicate_pad_numbers_are_jumpers no)
		(fp_poly
			(pts
				(arc
					(start 2.723642 4.777232)
					(mid -0.000169 6.508462)
					(end -2.723896 4.776978)
				)
				(arc
					(start -2.723896 4.776978)
					(mid 0.000173 -5.499012)
					(end 2.723642 4.777232)
				)
			)
			(stroke
				(width 0)
				(type default)
			)
			(fill no)
			(layer "B.CrtYd")
		)
		(fp_poly
			(pts
				(arc
					(start 2.723642 4.777232)
					(mid -0.000169 6.508462)
					(end -2.723896 4.776978)
				)
				(arc
					(start -2.723896 4.776978)
					(mid 0.000173 -5.499012)
					(end 2.723642 4.777232)
				)
			)
			(stroke
				(width 0)
				(type default)
			)
			(fill no)
			(layer "F.CrtYd")
		)
		(fp_poly
			(pts
				(arc
					(start 2.723642 4.777232)
					(mid -0.000169 6.508462)
					(end -2.723896 4.776978)
				)
				(arc
					(start -2.723896 4.776978)
					(mid 0.000173 -5.499012)
					(end 2.723642 4.777232)
				)
			)
			(stroke
				(width 0)
				(type default)
			)
			(fill no)
			(layer "B.Fab")
		)
		(fp_poly
			(pts
				(arc
					(start 2.723642 4.777232)
					(mid -0.000169 6.508462)
					(end -2.723896 4.776978)
				)
				(arc
					(start -2.723896 4.776978)
					(mid 0.000173 -5.499012)
					(end 2.723642 4.777232)
				)
			)
			(stroke
				(width 0)
				(type default)
			)
			(fill no)
			(layer "F.Fab")
		)
		(pad "" np_thru_hole circle
			(at 0 0)
			(size 0.254 0.254)
			(drill 0.0254)
			(layers "*.Cu" "*.Mask")
			(clearance 3.135376)
			(thermal_gap 3.135376)
		)
		(pad "1" thru_hole circle
			(at 2.549906 0)
			(size 0.8636 0.8636)
			(drill 0.508)
			(layers "*.Cu" "*.Mask")
			(remove_unused_layers no)
			(net "GND")
			(clearance 0.8255)
			(thermal_gap 0.8255)
		)
		(pad "2" thru_hole circle
			(at 2.210054 -1.27)
			(size 0.8636 0.8636)
			(drill 0.508)
			(layers "*.Cu" "*.Mask")
			(remove_unused_layers no)
			(net "GND")
			(clearance 0.8255)
			(thermal_gap 0.8255)
		)
		(pad "3" thru_hole circle
			(at 1.27 -2.210054)
			(size 0.8636 0.8636)
			(drill 0.508)
			(layers "*.Cu" "*.Mask")
			(remove_unused_layers no)
			(net "GND")
			(clearance 0.8255)
			(thermal_gap 0.8255)
		)
		(pad "4" thru_hole circle
			(at -1.279906 -2.210054)
			(size 0.8636 0.8636)
			(drill 0.508)
			(layers "*.Cu" "*.Mask")
			(remove_unused_layers no)
			(net "GND")
			(clearance 0.8255)
			(thermal_gap 0.8255)
		)
		(pad "5" thru_hole circle
			(at -2.210054 -1.27)
			(size 0.8636 0.8636)
			(drill 0.508)
			(layers "*.Cu" "*.Mask")
			(remove_unused_layers no)
			(net "GND")
			(clearance 0.8255)
			(thermal_gap 0.8255)
		)
		(pad "6" thru_hole circle
			(at -2.549906 0)
			(size 0.8636 0.8636)
			(drill 0.508)
			(layers "*.Cu" "*.Mask")
			(remove_unused_layers no)
			(net "GND")
			(clearance 0.8255)
			(thermal_gap 0.8255)
		)
		(zone
			(layers "F.Cu" "B.Cu" "In1.Cu" "In2.Cu" "In3.Cu" "In4.Cu" "In5.Cu" "In6.Cu")
			(hatch none 0.5)
			(connect_pads
				(clearance 0)
			)
			(min_thickness 0.25)
			(keepout
				(tracks allowed)
				(vias not_allowed)
				(pads allowed)
				(copperpour not_allowed)
				(footprints allowed)
			)
			(placement
				(enabled no)
				(sheetname "")
			)
			(fill
				(thermal_gap 0.5)
				(thermal_bridge_width 0.5)
				(island_removal_mode 0)
			)
			(polygon
				(pts
					(arc
						(start 257.817874 -483.500684)
						(mid 249.181874 -483.500684)
						(end 257.817874 -483.500684)
					)
				)
			)
		)
		(zone
			(layers "F.Cu" "B.Cu" "In1.Cu" "In2.Cu" "In3.Cu" "In4.Cu" "In5.Cu" "In6.Cu")
			(hatch none 0.5)
			(connect_pads
				(clearance 0)
			)
			(min_thickness 0.25)
			(keepout
				(tracks not_allowed)
				(vias allowed)
				(pads allowed)
				(copperpour not_allowed)
				(footprints allowed)
			)
			(placement
				(enabled no)
				(sheetname "")
			)
			(fill
				(thermal_gap 0.5)
				(thermal_bridge_width 0.5)
				(island_removal_mode 0)
			)
			(polygon
				(pts
					(arc
						(start 255.839214 -481.888292)
						(mid 253.499954 -476.989189)
						(end 251.16028 -481.888292)
					)
					(arc
						(start 251.16028 -481.888292)
						(mid 251.406247 -482.328658)
						(end 251.491496 -482.825806)
					)
					(arc
						(start 251.491496 -483.497636)
						(mid 253.499874 -485.506014)
						(end 255.507998 -483.497636)
					)
					(arc
						(start 255.507998 -482.825806)
						(mid 255.593233 -482.328652)
						(end 255.839214 -481.888292)
					)
				)
			)
		)
	)
	(footprint ""
		(layer "F.Cu")
		(at 207.01 -454.66 180)
		(property "Reference" "R317"
			(at 0 0 180)
			(layer "F.SilkS")
			(hide yes)
			(effects
				(font
					(size 1.27 1.27)
				)
			)
		)
		(property "Value" "4K7R2J-2-GP"
			(at 0.064008 -3.993896 180)
			(unlocked yes)
			(layer "F.Fab")
			(hide yes)
			(effects
				(font
					(size 1.016 1.016)
					(thickness 0.1524)
				)
			)
		)
		(property "Device Type" "R402H16"
			(at 0.064008 -5.517896 180)
			(unlocked yes)
			(layer "F.Fab")
			(hide yes)
			(effects
				(font
					(size 1.016 1.016)
					(thickness 0.1524)
				)
			)
		)
		(duplicate_pad_numbers_are_jumpers no)
		(fp_line
			(start 0.508 -0.9398)
			(end -0.508 -0.9398)
			(stroke
				(width 0.1524)
				(type default)
			)
			(layer "F.SilkS")
		)
		(fp_line
			(start -0.508 -0.9398)
			(end -0.508 0.9398)
			(stroke
				(width 0.1524)
				(type default)
			)
			(layer "F.SilkS")
		)
		(fp_rect
			(start -0.508 0.9398)
			(end 0.508 -0.9398)
			(stroke
				(width 0)
				(type default)
			)
			(fill no)
			(layer "F.CrtYd")
		)
		(fp_rect
			(start -0.508 0.9398)
			(end 0.508 -0.9398)
			(stroke
				(width 0)
				(type default)
			)
			(fill no)
			(layer "F.Fab")
		)
		(pad "1" smd custom
			(at 0 -0.4445 180)
			(size 0.1397 0.1397)
			(layers "F.Cu" "F.Mask" "F.Paste")
			(net "P3V3")
			(options
				(clearance outline)
				(anchor circle)
			)
			(primitives
				(gr_poly
					(pts
						(arc
							(start -0.1778 -0.2794)
							(mid -0.249642 -0.249642)
							(end -0.2794 -0.1778)
						)
						(arc
							(start -0.2794 0.1778)
							(mid -0.249642 0.249642)
							(end -0.1778 0.2794)
						)
						(arc
							(start 0.1778 0.2794)
							(mid 0.249642 0.249642)
							(end 0.2794 0.1778)
						)
						(arc
							(start 0.2794 -0.1778)
							(mid 0.249642 -0.249642)
							(end 0.1778 -0.2794)
						)
					)
					(width 0)
					(fill yes)
				)
			)
		)
		(pad "2" smd custom
			(at 0 0.4445 180)
			(size 0.1397 0.1397)
			(layers "F.Cu" "F.Mask" "F.Paste")
			(net "I2C_B_TMP2_A0")
			(options
				(clearance outline)
				(anchor circle)
			)
			(primitives
				(gr_poly
					(pts
						(arc
							(start -0.1778 -0.2794)
							(mid -0.249642 -0.249642)
							(end -0.2794 -0.1778)
						)
						(arc
							(start -0.2794 0.1778)
							(mid -0.249642 0.249642)
							(end -0.1778 0.2794)
						)
						(arc
							(start 0.1778 0.2794)
							(mid 0.249642 0.249642)
							(end 0.2794 0.1778)
						)
						(arc
							(start 0.2794 -0.1778)
							(mid 0.249642 -0.249642)
							(end 0.1778 -0.2794)
						)
					)
					(width 0)
					(fill yes)
				)
			)
		)
	)
	(footprint ""
		(layer "F.Cu")
		(at 107.442 -205.613 -90)
		(property "Reference" "R9594"
			(at 0 0 270)
			(layer "F.SilkS")
			(hide yes)
			(effects
				(font
					(size 1.27 1.27)
				)
			)
		)
		(property "Value" "10R2F-L-GP"
			(at 0.064008 -3.993896 270)
			(unlocked yes)
			(layer "F.Fab")
			(hide yes)
			(effects
				(font
					(size 1.016 1.016)
					(thickness 0.1524)
				)
			)
		)
		(property "Device Type" "R402H14"
			(at 0.064008 -5.517896 270)
			(unlocked yes)
			(layer "F.Fab")
			(hide yes)
			(effects
				(font
					(size 1.016 1.016)
					(thickness 0.1524)
				)
			)
		)
		(duplicate_pad_numbers_are_jumpers no)
		(fp_line
			(start -0.508 -0.9398)
			(end -0.508 0.9398)
			(stroke
				(width 0.1524)
				(type default)
			)
			(layer "F.SilkS")
		)
		(fp_line
			(start 0.508 -0.9398)
			(end -0.508 -0.9398)
			(stroke
				(width 0.1524)
				(type default)
			)
			(layer "F.SilkS")
		)
		(fp_rect
			(start -0.508 0.9398)
			(end 0.508 -0.9398)
			(stroke
				(width 0)
				(type default)
			)
			(fill no)
			(layer "F.CrtYd")
		)
		(fp_rect
			(start -0.508 0.9398)
			(end 0.508 -0.9398)
			(stroke
				(width 0)
				(type default)
			)
			(fill no)
			(layer "F.Fab")
		)
		(pad "1" smd custom
			(at 0 -0.4445 270)
			(size 0.1397 0.1397)
			(layers "F.Cu" "F.Mask" "F.Paste")
			(net "SSD_PRSNT_NET3")
			(options
				(clearance outline)
				(anchor circle)
			)
			(primitives
				(gr_poly
					(pts
						(arc
							(start -0.1778 -0.2794)
							(mid -0.249642 -0.249642)
							(end -0.2794 -0.1778)
						)
						(arc
							(start -0.2794 0.1778)
							(mid -0.249642 0.249642)
							(end -0.1778 0.2794)
						)
						(arc
							(start 0.1778 0.2794)
							(mid 0.249642 0.249642)
							(end 0.2794 0.1778)
						)
						(arc
							(start 0.2794 -0.1778)
							(mid 0.249642 -0.249642)
							(end 0.1778 -0.2794)
						)
					)
					(width 0)
					(fill yes)
				)
			)
		)
		(pad "2" smd custom
			(at 0 0.4445 270)
			(size 0.1397 0.1397)
			(layers "F.Cu" "F.Mask" "F.Paste")
			(net "SSD_PRSNT3")
			(options
				(clearance outline)
				(anchor circle)
			)
			(primitives
				(gr_poly
					(pts
						(arc
							(start -0.1778 -0.2794)
							(mid -0.249642 -0.249642)
							(end -0.2794 -0.1778)
						)
						(arc
							(start -0.2794 0.1778)
							(mid -0.249642 0.249642)
							(end -0.1778 0.2794)
						)
						(arc
							(start 0.1778 0.2794)
							(mid 0.249642 0.249642)
							(end 0.2794 0.1778)
						)
						(arc
							(start 0.2794 -0.1778)
							(mid 0.249642 -0.249642)
							(end 0.1778 -0.2794)
						)
					)
					(width 0)
					(fill yes)
				)
			)
		)
	)
	(footprint ""
		(layer "F.Cu")
		(at 35.56 -205.0034 90)
		(property "Reference" "Q87"
			(at 0 0 90)
			(layer "F.SilkS")
			(hide yes)
			(effects
				(font
					(size 1.27 1.27)
				)
			)
		)
		(property "Value" "2N7002A-7-GP"
			(at 0.127 -8.9662 90)
			(unlocked yes)
			(layer "F.Fab")
			(hide yes)
			(effects
				(font
					(size 1.016 1.016)
					(thickness 0.1524)
				)
			)
		)
		(property "Device Type" "SOT23DGS2D4H48"
			(at 0.127 -10.4902 90)
			(unlocked yes)
			(layer "F.Fab")
			(hide yes)
			(effects
				(font
					(size 1.016 1.016)
					(thickness 0.1524)
				)
			)
		)
		(duplicate_pad_numbers_are_jumpers no)
		(fp_line
			(start 1.651 -1.778)
			(end -1.651 -1.778)
			(stroke
				(width 0.1524)
				(type default)
			)
			(layer "F.SilkS")
		)
		(fp_line
			(start -1.651 -1.778)
			(end -1.651 1.778)
			(stroke
				(width 0.1524)
				(type default)
			)
			(layer "F.SilkS")
		)
		(fp_line
			(start 1.651 1.778)
			(end 1.651 -1.778)
			(stroke
				(width 0.1524)
				(type default)
			)
			(layer "F.SilkS")
		)
		(fp_line
			(start -1.651 1.778)
			(end 1.651 1.778)
			(stroke
				(width 0.1524)
				(type default)
			)
			(layer "F.SilkS")
		)
		(fp_poly
			(pts
				(xy -1.778 1.8796) (xy -1.778 -1.8796) (xy 1.778 -1.8796) (xy 1.778 1.8796)
			)
			(stroke
				(width 0)
				(type default)
			)
			(fill no)
			(layer "F.CrtYd")
		)
		(fp_poly
			(pts
				(xy -1.778 1.8796) (xy -1.778 -1.8796) (xy 1.778 -1.8796) (xy 1.778 1.8796)
			)
			(stroke
				(width 0)
				(type default)
			)
			(fill no)
			(layer "F.Fab")
		)
		(pad "D" smd custom
			(at 0 -0.9525 90)
			(size 0.1905 0.1905)
			(layers "F.Cu" "F.Mask" "F.Paste")
			(net "P12V_MOST12_GATE")
			(options
				(clearance outline)
				(anchor circle)
			)
			(primitives
				(gr_poly
					(pts
						(arc
							(start -0.1778 0.5715)
							(mid -0.321484 0.511984)
							(end -0.381 0.3683)
						)
						(arc
							(start -0.381 -0.3683)
							(mid -0.321484 -0.511984)
							(end -0.1778 -0.5715)
						)
						(arc
							(start 0.1778 -0.5715)
							(mid 0.321484 -0.511984)
							(end 0.381 -0.3683)
						)
						(arc
							(start 0.381 0.3683)
							(mid 0.321484 0.511984)
							(end 0.1778 0.5715)
						)
					)
					(width 0)
					(fill yes)
				)
			)
		)
		(pad "G" smd custom
			(at -0.98425 0.9525 90)
			(size 0.1905 0.1905)
			(layers "F.Cu" "F.Mask" "F.Paste")
			(net "SSD12_PWREN_R")
			(options
				(clearance outline)
				(anchor circle)
			)
			(primitives
				(gr_poly
					(pts
						(arc
							(start -0.1778 0.5715)
							(mid -0.321484 0.511984)
							(end -0.381 0.3683)
						)
						(arc
							(start -0.381 -0.3683)
							(mid -0.321484 -0.511984)
							(end -0.1778 -0.5715)
						)
						(arc
							(start 0.1778 -0.5715)
							(mid 0.321484 -0.511984)
							(end 0.381 -0.3683)
						)
						(arc
							(start 0.381 0.3683)
							(mid 0.321484 0.511984)
							(end 0.1778 0.5715)
						)
					)
					(width 0)
					(fill yes)
				)
			)
		)
		(pad "S" smd custom
			(at 0.98425 0.9525 90)
			(size 0.1905 0.1905)
			(layers "F.Cu" "F.Mask" "F.Paste")
			(net "GND")
			(options
				(clearance outline)
				(anchor circle)
			)
			(primitives
				(gr_poly
					(pts
						(arc
							(start -0.1778 0.5715)
							(mid -0.321484 0.511984)
							(end -0.381 0.3683)
						)
						(arc
							(start -0.381 -0.3683)
							(mid -0.321484 -0.511984)
							(end -0.1778 -0.5715)
						)
						(arc
							(start 0.1778 -0.5715)
							(mid 0.321484 -0.511984)
							(end 0.381 -0.3683)
						)
						(arc
							(start 0.381 0.3683)
							(mid 0.321484 0.511984)
							(end 0.1778 0.5715)
						)
					)
					(width 0)
					(fill yes)
				)
			)
		)
	)
	(footprint ""
		(layer "F.Cu")
		(at 209.296 -396.113 180)
		(property "Reference" "R567"
			(at 0 0 180)
			(layer "F.SilkS")
			(hide yes)
			(effects
				(font
					(size 1.27 1.27)
				)
			)
		)
		(property "Value" "300KR2F-GP"
			(at 0.064008 -3.993896 180)
			(unlocked yes)
			(layer "F.Fab")
			(hide yes)
			(effects
				(font
					(size 1.016 1.016)
					(thickness 0.1524)
				)
			)
		)
		(property "Device Type" "R402H16"
			(at 0.064008 -5.517896 180)
			(unlocked yes)
			(layer "F.Fab")
			(hide yes)
			(effects
				(font
					(size 1.016 1.016)
					(thickness 0.1524)
				)
			)
		)
		(duplicate_pad_numbers_are_jumpers no)
		(fp_line
			(start 0.508 -0.9398)
			(end -0.508 -0.9398)
			(stroke
				(width 0.1524)
				(type default)
			)
			(layer "F.SilkS")
		)
		(fp_line
			(start -0.508 -0.9398)
			(end -0.508 0.9398)
			(stroke
				(width 0.1524)
				(type default)
			)
			(layer "F.SilkS")
		)
		(fp_rect
			(start -0.508 0.9398)
			(end 0.508 -0.9398)
			(stroke
				(width 0)
				(type default)
			)
			(fill no)
			(layer "F.CrtYd")
		)
		(fp_rect
			(start -0.508 0.9398)
			(end 0.508 -0.9398)
			(stroke
				(width 0)
				(type default)
			)
			(fill no)
			(layer "F.Fab")
		)
		(pad "1" smd custom
			(at 0 -0.4445 180)
			(size 0.1397 0.1397)
			(layers "F.Cu" "F.Mask" "F.Paste")
			(net "SW_SSD1_N")
			(options
				(clearance outline)
				(anchor circle)
			)
			(primitives
				(gr_poly
					(pts
						(arc
							(start -0.1778 -0.2794)
							(mid -0.249642 -0.249642)
							(end -0.2794 -0.1778)
						)
						(arc
							(start -0.2794 0.1778)
							(mid -0.249642 0.249642)
							(end -0.1778 0.2794)
						)
						(arc
							(start 0.1778 0.2794)
							(mid 0.249642 0.249642)
							(end 0.2794 0.1778)
						)
						(arc
							(start 0.2794 -0.1778)
							(mid 0.249642 -0.249642)
							(end 0.1778 -0.2794)
						)
					)
					(width 0)
					(fill yes)
				)
			)
		)
		(pad "2" smd custom
			(at 0 0.4445 180)
			(size 0.1397 0.1397)
			(layers "F.Cu" "F.Mask" "F.Paste")
			(net "P12V")
			(options
				(clearance outline)
				(anchor circle)
			)
			(primitives
				(gr_poly
					(pts
						(arc
							(start -0.1778 -0.2794)
							(mid -0.249642 -0.249642)
							(end -0.2794 -0.1778)
						)
						(arc
							(start -0.2794 0.1778)
							(mid -0.249642 0.249642)
							(end -0.1778 0.2794)
						)
						(arc
							(start 0.1778 0.2794)
							(mid 0.249642 0.249642)
							(end 0.2794 0.1778)
						)
						(arc
							(start 0.2794 -0.1778)
							(mid 0.249642 -0.249642)
							(end 0.1778 -0.2794)
						)
					)
					(width 0)
					(fill yes)
				)
			)
		)
	)
	(footprint ""
		(layer "F.Cu")
		(at 79.1718 -216.6874 90)
		(property "Reference" "FB9"
			(at 0 0 90)
			(layer "F.SilkS")
			(hide yes)
			(effects
				(font
					(size 1.27 1.27)
				)
			)
		)
		(property "Value" "BLM21PG331SN1D-2-GP"
			(at 0 -4.2418 90)
			(unlocked yes)
			(layer "F.Fab")
			(hide yes)
			(effects
				(font
					(size 1.016 1.016)
					(thickness 0.1524)
				)
			)
		)
		(property "Device Type" "L805H42"
			(at 0 -5.7912 90)
			(unlocked yes)
			(layer "F.Fab")
			(hide yes)
			(effects
				(font
					(size 1.016 1.016)
					(thickness 0.1524)
				)
			)
		)
		(duplicate_pad_numbers_are_jumpers no)
		(fp_line
			(start 0.889 -1.7018)
			(end 0.889 1.7018)
			(stroke
				(width 0.1524)
				(type default)
			)
			(layer "F.SilkS")
		)
		(fp_line
			(start -0.889 -1.7018)
			(end 0.889 -1.7018)
			(stroke
				(width 0.1524)
				(type default)
			)
			(layer "F.SilkS")
		)
		(fp_line
			(start 0.889 1.7018)
			(end -0.889 1.7018)
			(stroke
				(width 0.1524)
				(type default)
			)
			(layer "F.SilkS")
		)
		(fp_line
			(start -0.889 1.7018)
			(end -0.889 -1.7018)
			(stroke
				(width 0.1524)
				(type default)
			)
			(layer "F.SilkS")
		)
		(fp_rect
			(start -0.9652 1.778)
			(end 0.9652 -1.778)
			(stroke
				(width 0)
				(type default)
			)
			(fill no)
			(layer "F.CrtYd")
		)
		(fp_rect
			(start -0.9652 1.778)
			(end 0.9652 -1.778)
			(stroke
				(width 0)
				(type default)
			)
			(fill no)
			(layer "F.Fab")
		)
		(pad "1" smd rect
			(at 0 -0.9652 90)
			(size 1.397 1.143)
			(layers "F.Cu" "F.Mask" "F.Paste")
			(net "P3V3")
		)
		(pad "2" smd rect
			(at 0 0.9652 90)
			(size 1.397 1.143)
			(layers "F.Cu" "F.Mask" "F.Paste")
			(net "VDD_DIFF_3")
		)
	)
	(footprint ""
		(layer "F.Cu")
		(at 227.203 -137.91311 90)
		(property "Reference" "U200"
			(at 0 0 90)
			(layer "F.SilkS")
			(hide yes)
			(effects
				(font
					(size 1.27 1.27)
				)
			)
		)
		(property "Value" "SN74LVC1G08DCKR-GP"
			(at -2.3368 -8.6868 90)
			(unlocked yes)
			(layer "F.Fab")
			(hide yes)
			(effects
				(font
					(size 1.016 1.016)
					(thickness 0.1524)
				)
			)
		)
		(property "Device Type" "SC70-5H44"
			(at -2.3114 -10.414 90)
			(unlocked yes)
			(layer "F.Fab")
			(hide yes)
			(effects
				(font
					(size 1.016 1.016)
					(thickness 0.1524)
				)
			)
		)
		(duplicate_pad_numbers_are_jumpers no)
		(fp_line
			(start 1.3843 -1.8034)
			(end 1.3843 -1.1176)
			(stroke
				(width 0.3302)
				(type default)
			)
			(layer "F.SilkS")
		)
		(fp_line
			(start 0.6604 -1.8034)
			(end 1.3843 -1.8034)
			(stroke
				(width 0.3302)
				(type default)
			)
			(layer "F.SilkS")
		)
		(fp_line
			(start 1.27 -1.7018)
			(end 1.27 1.7018)
			(stroke
				(width 0.1524)
				(type default)
			)
			(layer "F.SilkS")
		)
		(fp_line
			(start -1.27 -1.7018)
			(end 1.27 -1.7018)
			(stroke
				(width 0.1524)
				(type default)
			)
			(layer "F.SilkS")
		)
		(fp_line
			(start 1.27 1.7018)
			(end -1.27 1.7018)
			(stroke
				(width 0.1524)
				(type default)
			)
			(layer "F.SilkS")
		)
		(fp_line
			(start -1.27 1.7018)
			(end -1.27 -1.7018)
			(stroke
				(width 0.1524)
				(type default)
			)
			(layer "F.SilkS")
		)
		(fp_rect
			(start -1.524 1.9558)
			(end 1.524 -1.9558)
			(stroke
				(width 0)
				(type default)
			)
			(fill no)
			(layer "F.CrtYd")
		)
		(fp_poly
			(pts
				(xy -1.524 -1.9558) (xy 1.524 -1.9558) (xy 1.524 1.9558) (xy -1.524 1.9558)
			)
			(stroke
				(width 0)
				(type default)
			)
			(fill no)
			(layer "F.Fab")
		)
		(pad "1" smd rect
			(at 0.65024 -0.8255 90)
			(size 0.4064 1.2192)
			(layers "F.Cu" "F.Mask" "F.Paste")
			(net "SSD3_CLK0_OE_MOS_N")
		)
		(pad "2" smd rect
			(at 0 -0.8255 90)
			(size 0.4064 1.2192)
			(layers "F.Cu" "F.Mask" "F.Paste")
			(net "ATTN_LED_DR3_N")
		)
		(pad "3" smd rect
			(at -0.65024 -0.8255 90)
			(size 0.4064 1.2192)
			(layers "F.Cu" "F.Mask" "F.Paste")
			(net "GND")
		)
		(pad "4" smd rect
			(at -0.65024 0.8255 90)
			(size 0.4064 1.2192)
			(layers "F.Cu" "F.Mask" "F.Paste")
			(net "ATTN_LED_DR3_AND")
		)
		(pad "5" smd rect
			(at 0.65024 0.8255 90)
			(size 0.4064 1.2192)
			(layers "F.Cu" "F.Mask" "F.Paste")
			(net "P3V3")
		)
	)
	(footprint ""
		(layer "F.Cu")
		(at 29.845 -424.434 90)
		(property "Reference" "R408"
			(at 0 0 90)
			(layer "F.SilkS")
			(hide yes)
			(effects
				(font
					(size 1.27 1.27)
				)
			)
		)
		(property "Value" "0R2J-2-GP"
			(at 0.064008 -3.993896 90)
			(unlocked yes)
			(layer "F.Fab")
			(hide yes)
			(effects
				(font
					(size 1.016 1.016)
					(thickness 0.1524)
				)
			)
		)
		(property "Device Type" "R402H16"
			(at 0.064008 -5.517896 90)
			(unlocked yes)
			(layer "F.Fab")
			(hide yes)
			(effects
				(font
					(size 1.016 1.016)
					(thickness 0.1524)
				)
			)
		)
		(duplicate_pad_numbers_are_jumpers no)
		(fp_line
			(start 0.508 -0.9398)
			(end -0.508 -0.9398)
			(stroke
				(width 0.1524)
				(type default)
			)
			(layer "F.SilkS")
		)
		(fp_line
			(start -0.508 -0.9398)
			(end -0.508 0.9398)
			(stroke
				(width 0.1524)
				(type default)
			)
			(layer "F.SilkS")
		)
		(fp_rect
			(start -0.508 0.9398)
			(end 0.508 -0.9398)
			(stroke
				(width 0)
				(type default)
			)
			(fill no)
			(layer "F.CrtYd")
		)
		(fp_rect
			(start -0.508 0.9398)
			(end 0.508 -0.9398)
			(stroke
				(width 0)
				(type default)
			)
			(fill no)
			(layer "F.Fab")
		)
		(pad "1" smd custom
			(at 0 -0.4445 90)
			(size 0.1397 0.1397)
			(layers "F.Cu" "F.Mask" "F.Paste")
			(net "SCL_DR10_R")
			(options
				(clearance outline)
				(anchor circle)
			)
			(primitives
				(gr_poly
					(pts
						(arc
							(start -0.1778 -0.2794)
							(mid -0.249642 -0.249642)
							(end -0.2794 -0.1778)
						)
						(arc
							(start -0.2794 0.1778)
							(mid -0.249642 0.249642)
							(end -0.1778 0.2794)
						)
						(arc
							(start 0.1778 0.2794)
							(mid 0.249642 0.249642)
							(end 0.2794 0.1778)
						)
						(arc
							(start 0.2794 -0.1778)
							(mid 0.249642 -0.249642)
							(end 0.1778 -0.2794)
						)
					)
					(width 0)
					(fill yes)
				)
			)
		)
		(pad "2" smd custom
			(at 0 0.4445 90)
			(size 0.1397 0.1397)
			(layers "F.Cu" "F.Mask" "F.Paste")
			(net "SCL_DR10")
			(options
				(clearance outline)
				(anchor circle)
			)
			(primitives
				(gr_poly
					(pts
						(arc
							(start -0.1778 -0.2794)
							(mid -0.249642 -0.249642)
							(end -0.2794 -0.1778)
						)
						(arc
							(start -0.2794 0.1778)
							(mid -0.249642 0.249642)
							(end -0.1778 0.2794)
						)
						(arc
							(start 0.1778 0.2794)
							(mid 0.249642 0.249642)
							(end 0.2794 0.1778)
						)
						(arc
							(start 0.2794 -0.1778)
							(mid 0.249642 -0.249642)
							(end 0.1778 -0.2794)
						)
					)
					(width 0)
					(fill yes)
				)
			)
		)
	)
	(footprint ""
		(layer "F.Cu")
		(at 85.471 -303.403 -90)
		(property "Reference" "R9093"
			(at 0 0 270)
			(layer "F.SilkS")
			(hide yes)
			(effects
				(font
					(size 1.27 1.27)
				)
			)
		)
		(property "Value" "4K7R2F-GP"
			(at 0.064008 -3.993896 270)
			(unlocked yes)
			(layer "F.Fab")
			(hide yes)
			(effects
				(font
					(size 1.016 1.016)
					(thickness 0.1524)
				)
			)
		)
		(property "Device Type" "R402H16"
			(at 0.064008 -5.517896 270)
			(unlocked yes)
			(layer "F.Fab")
			(hide yes)
			(effects
				(font
					(size 1.016 1.016)
					(thickness 0.1524)
				)
			)
		)
		(duplicate_pad_numbers_are_jumpers no)
		(fp_line
			(start -0.508 -0.9398)
			(end -0.508 0.9398)
			(stroke
				(width 0.1524)
				(type default)
			)
			(layer "F.SilkS")
		)
		(fp_line
			(start 0.508 -0.9398)
			(end -0.508 -0.9398)
			(stroke
				(width 0.1524)
				(type default)
			)
			(layer "F.SilkS")
		)
		(fp_rect
			(start -0.508 0.9398)
			(end 0.508 -0.9398)
			(stroke
				(width 0)
				(type default)
			)
			(fill no)
			(layer "F.CrtYd")
		)
		(fp_rect
			(start -0.508 0.9398)
			(end 0.508 -0.9398)
			(stroke
				(width 0)
				(type default)
			)
			(fill no)
			(layer "F.Fab")
		)
		(pad "1" smd custom
			(at 0 -0.4445 270)
			(size 0.1397 0.1397)
			(layers "F.Cu" "F.Mask" "F.Paste")
			(net "CLK_BUF_EU2_SMB_A0_TRI")
			(options
				(clearance outline)
				(anchor circle)
			)
			(primitives
				(gr_poly
					(pts
						(arc
							(start -0.1778 -0.2794)
							(mid -0.249642 -0.249642)
							(end -0.2794 -0.1778)
						)
						(arc
							(start -0.2794 0.1778)
							(mid -0.249642 0.249642)
							(end -0.1778 0.2794)
						)
						(arc
							(start 0.1778 0.2794)
							(mid 0.249642 0.249642)
							(end 0.2794 0.1778)
						)
						(arc
							(start 0.2794 -0.1778)
							(mid 0.249642 -0.249642)
							(end 0.1778 -0.2794)
						)
					)
					(width 0)
					(fill yes)
				)
			)
		)
		(pad "2" smd custom
			(at 0 0.4445 270)
			(size 0.1397 0.1397)
			(layers "F.Cu" "F.Mask" "F.Paste")
			(net "GND")
			(options
				(clearance outline)
				(anchor circle)
			)
			(primitives
				(gr_poly
					(pts
						(arc
							(start -0.1778 -0.2794)
							(mid -0.249642 -0.249642)
							(end -0.2794 -0.1778)
						)
						(arc
							(start -0.2794 0.1778)
							(mid -0.249642 0.249642)
							(end -0.1778 0.2794)
						)
						(arc
							(start 0.1778 0.2794)
							(mid 0.249642 0.249642)
							(end 0.2794 0.1778)
						)
						(arc
							(start 0.2794 -0.1778)
							(mid 0.249642 -0.249642)
							(end 0.1778 -0.2794)
						)
					)
					(width 0)
					(fill yes)
				)
			)
		)
	)
	(footprint ""
		(layer "F.Cu")
		(at 17.1704 -469.4936 180)
		(property "Reference" "Q80"
			(at 0 0 180)
			(layer "F.SilkS")
			(hide yes)
			(effects
				(font
					(size 1.27 1.27)
				)
			)
		)
		(property "Value" "2N7002A-7-GP"
			(at 0.127 -8.9662 180)
			(unlocked yes)
			(layer "F.Fab")
			(hide yes)
			(effects
				(font
					(size 1.016 1.016)
					(thickness 0.1524)
				)
			)
		)
		(property "Device Type" "SOT23DGS2D4H48"
			(at 0.127 -10.4902 180)
			(unlocked yes)
			(layer "F.Fab")
			(hide yes)
			(effects
				(font
					(size 1.016 1.016)
					(thickness 0.1524)
				)
			)
		)
		(duplicate_pad_numbers_are_jumpers no)
		(fp_line
			(start 1.651 1.778)
			(end 1.651 -1.778)
			(stroke
				(width 0.1524)
				(type default)
			)
			(layer "F.SilkS")
		)
		(fp_line
			(start 1.651 -1.778)
			(end -1.651 -1.778)
			(stroke
				(width 0.1524)
				(type default)
			)
			(layer "F.SilkS")
		)
		(fp_line
			(start -1.651 1.778)
			(end 1.651 1.778)
			(stroke
				(width 0.1524)
				(type default)
			)
			(layer "F.SilkS")
		)
		(fp_line
			(start -1.651 -1.778)
			(end -1.651 1.778)
			(stroke
				(width 0.1524)
				(type default)
			)
			(layer "F.SilkS")
		)
		(fp_poly
			(pts
				(xy -1.778 1.8796) (xy -1.778 -1.8796) (xy 1.778 -1.8796) (xy 1.778 1.8796)
			)
			(stroke
				(width 0)
				(type default)
			)
			(fill no)
			(layer "F.CrtYd")
		)
		(fp_poly
			(pts
				(xy -1.778 1.8796) (xy -1.778 -1.8796) (xy 1.778 -1.8796) (xy 1.778 1.8796)
			)
			(stroke
				(width 0)
				(type default)
			)
			(fill no)
			(layer "F.Fab")
		)
		(pad "D" smd custom
			(at 0 -0.9525 180)
			(size 0.1905 0.1905)
			(layers "F.Cu" "F.Mask" "F.Paste")
			(net "ATTN_LED_DR10_MOS_N")
			(options
				(clearance outline)
				(anchor circle)
			)
			(primitives
				(gr_poly
					(pts
						(arc
							(start -0.1778 0.5715)
							(mid -0.321484 0.511984)
							(end -0.381 0.3683)
						)
						(arc
							(start -0.381 -0.3683)
							(mid -0.321484 -0.511984)
							(end -0.1778 -0.5715)
						)
						(arc
							(start 0.1778 -0.5715)
							(mid 0.321484 -0.511984)
							(end 0.381 -0.3683)
						)
						(arc
							(start 0.381 0.3683)
							(mid 0.321484 0.511984)
							(end 0.1778 0.5715)
						)
					)
					(width 0)
					(fill yes)
				)
			)
		)
		(pad "G" smd custom
			(at -0.98425 0.9525 180)
			(size 0.1905 0.1905)
			(layers "F.Cu" "F.Mask" "F.Paste")
			(net "SSD10_CLK0_OE_MOS_N")
			(options
				(clearance outline)
				(anchor circle)
			)
			(primitives
				(gr_poly
					(pts
						(arc
							(start -0.1778 0.5715)
							(mid -0.321484 0.511984)
							(end -0.381 0.3683)
						)
						(arc
							(start -0.381 -0.3683)
							(mid -0.321484 -0.511984)
							(end -0.1778 -0.5715)
						)
						(arc
							(start 0.1778 -0.5715)
							(mid 0.321484 -0.511984)
							(end 0.381 -0.3683)
						)
						(arc
							(start 0.381 0.3683)
							(mid 0.321484 0.511984)
							(end 0.1778 0.5715)
						)
					)
					(width 0)
					(fill yes)
				)
			)
		)
		(pad "S" smd custom
			(at 0.98425 0.9525 180)
			(size 0.1905 0.1905)
			(layers "F.Cu" "F.Mask" "F.Paste")
			(net "ATTN_LED_DR10_R")
			(options
				(clearance outline)
				(anchor circle)
			)
			(primitives
				(gr_poly
					(pts
						(arc
							(start -0.1778 0.5715)
							(mid -0.321484 0.511984)
							(end -0.381 0.3683)
						)
						(arc
							(start -0.381 -0.3683)
							(mid -0.321484 -0.511984)
							(end -0.1778 -0.5715)
						)
						(arc
							(start 0.1778 -0.5715)
							(mid 0.321484 -0.511984)
							(end 0.381 -0.3683)
						)
						(arc
							(start 0.381 0.3683)
							(mid 0.321484 0.511984)
							(end 0.1778 0.5715)
						)
					)
					(width 0)
					(fill yes)
				)
			)
		)
	)
	(footprint ""
		(layer "F.Cu")
		(at 193.526156 -499.943628 90)
		(property "Reference" "R9776"
			(at 0 0 90)
			(layer "F.SilkS")
			(hide yes)
			(effects
				(font
					(size 1.27 1.27)
				)
			)
		)
		(property "Value" "1KR2J-1-GP"
			(at 0.064008 -3.993896 90)
			(unlocked yes)
			(layer "F.Fab")
			(hide yes)
			(effects
				(font
					(size 1.016 1.016)
					(thickness 0.1524)
				)
			)
		)
		(property "Device Type" "R402H16"
			(at 0.064008 -5.517896 90)
			(unlocked yes)
			(layer "F.Fab")
			(hide yes)
			(effects
				(font
					(size 1.016 1.016)
					(thickness 0.1524)
				)
			)
		)
		(duplicate_pad_numbers_are_jumpers no)
		(fp_line
			(start 0.508 -0.9398)
			(end -0.508 -0.9398)
			(stroke
				(width 0.1524)
				(type default)
			)
			(layer "F.SilkS")
		)
		(fp_line
			(start -0.508 -0.9398)
			(end -0.508 0.9398)
			(stroke
				(width 0.1524)
				(type default)
			)
			(layer "F.SilkS")
		)
		(fp_rect
			(start -0.508 0.9398)
			(end 0.508 -0.9398)
			(stroke
				(width 0)
				(type default)
			)
			(fill no)
			(layer "F.CrtYd")
		)
		(fp_rect
			(start -0.508 0.9398)
			(end 0.508 -0.9398)
			(stroke
				(width 0)
				(type default)
			)
			(fill no)
			(layer "F.Fab")
		)
		(pad "1" smd custom
			(at 0 -0.4445 90)
			(size 0.1397 0.1397)
			(layers "F.Cu" "F.Mask" "F.Paste")
			(net "SSD0_PWREN")
			(options
				(clearance outline)
				(anchor circle)
			)
			(primitives
				(gr_poly
					(pts
						(arc
							(start -0.1778 -0.2794)
							(mid -0.249642 -0.249642)
							(end -0.2794 -0.1778)
						)
						(arc
							(start -0.2794 0.1778)
							(mid -0.249642 0.249642)
							(end -0.1778 0.2794)
						)
						(arc
							(start 0.1778 0.2794)
							(mid 0.249642 0.249642)
							(end 0.2794 0.1778)
						)
						(arc
							(start 0.2794 -0.1778)
							(mid 0.249642 -0.249642)
							(end 0.1778 -0.2794)
						)
					)
					(width 0)
					(fill yes)
				)
			)
		)
		(pad "2" smd custom
			(at 0 0.4445 90)
			(size 0.1397 0.1397)
			(layers "F.Cu" "F.Mask" "F.Paste")
			(net "SSD0_PWREN_R")
			(options
				(clearance outline)
				(anchor circle)
			)
			(primitives
				(gr_poly
					(pts
						(arc
							(start -0.1778 -0.2794)
							(mid -0.249642 -0.249642)
							(end -0.2794 -0.1778)
						)
						(arc
							(start -0.2794 0.1778)
							(mid -0.249642 0.249642)
							(end -0.1778 0.2794)
						)
						(arc
							(start 0.1778 0.2794)
							(mid 0.249642 0.249642)
							(end 0.2794 0.1778)
						)
						(arc
							(start 0.2794 -0.1778)
							(mid 0.249642 -0.249642)
							(end 0.1778 -0.2794)
						)
					)
					(width 0)
					(fill yes)
				)
			)
		)
	)
	(footprint ""
		(layer "F.Cu")
		(at 35.0266 -194.3608 180)
		(property "Reference" "PC1215"
			(at 0 0 180)
			(layer "F.SilkS")
			(hide yes)
			(effects
				(font
					(size 1.27 1.27)
				)
			)
		)
		(property "Value" "SC22U25V6KX-GP-U"
			(at -2.860802 -5.279644 180)
			(unlocked yes)
			(layer "F.Fab")
			(hide yes)
			(effects
				(font
					(size 1.016 1.016)
					(thickness 0.1524)
				)
			)
		)
		(property "Device Type" "C1206-TO0D3H75"
			(at -2.860802 -6.803644 180)
			(unlocked yes)
			(layer "F.Fab")
			(hide yes)
			(effects
				(font
					(size 1.016 1.016)
					(thickness 0.1524)
				)
			)
		)
		(duplicate_pad_numbers_are_jumpers no)
		(fp_line
			(start 1.3081 2.3749)
			(end -1.3081 2.3749)
			(stroke
				(width 0.1524)
				(type default)
			)
			(layer "F.SilkS")
		)
		(fp_line
			(start 1.3081 -2.3749)
			(end 1.3081 2.3749)
			(stroke
				(width 0.1524)
				(type default)
			)
			(layer "F.SilkS")
		)
		(fp_line
			(start -1.3081 2.3749)
			(end -1.3081 -2.3749)
			(stroke
				(width 0.1524)
				(type default)
			)
			(layer "F.SilkS")
		)
		(fp_line
			(start -1.3081 -2.3749)
			(end 1.3081 -2.3749)
			(stroke
				(width 0.1524)
				(type default)
			)
			(layer "F.SilkS")
		)
		(fp_rect
			(start -0.8001 1.6002)
			(end 0.8001 -1.6002)
			(stroke
				(width 0)
				(type default)
			)
			(fill no)
			(layer "F.CrtYd")
		)
		(fp_poly
			(pts
				(xy -1.5621 2.4511) (xy -1.5621 1.6002) (xy 0.8001 1.6002) (xy 0.8001 -1.6002) (xy -0.8001 -1.6002)
				(xy -0.8001 1.5875) (xy -1.5621 1.5875) (xy -1.5621 -2.4511) (xy 1.5621 -2.4511) (xy 1.5621 2.4511)
			)
			(stroke
				(width 0)
				(type default)
			)
			(fill no)
			(layer "F.CrtYd")
		)
		(fp_rect
			(start -1.5621 2.4511)
			(end 1.5621 -2.4511)
			(stroke
				(width 0)
				(type default)
			)
			(fill no)
			(layer "F.Fab")
		)
		(pad "1" smd rect
			(at 0 -1.392936 180)
			(size 2.1082 1.4478)
			(layers "F.Cu" "F.Mask" "F.Paste")
			(net "P12V_SSD8")
		)
		(pad "2" smd rect
			(at 0 1.392936 180)
			(size 2.1082 1.4478)
			(layers "F.Cu" "F.Mask" "F.Paste")
			(net "GND")
		)
	)
	(footprint ""
		(layer "F.Cu")
		(at 34.13125 -41.26865 -90)
		(property "Reference" "SR1139"
			(at 0 0 270)
			(layer "F.SilkS")
			(hide yes)
			(effects
				(font
					(size 1.27 1.27)
				)
			)
		)
		(property "Value" "4K7R2F-GP"
			(at 0.064008 -3.993896 270)
			(unlocked yes)
			(layer "F.Fab")
			(hide yes)
			(effects
				(font
					(size 1.016 1.016)
					(thickness 0.1524)
				)
			)
		)
		(property "Device Type" "R402H16"
			(at 0.064008 -5.517896 270)
			(unlocked yes)
			(layer "F.Fab")
			(hide yes)
			(effects
				(font
					(size 1.016 1.016)
					(thickness 0.1524)
				)
			)
		)
		(duplicate_pad_numbers_are_jumpers no)
		(fp_line
			(start -0.508 -0.9398)
			(end -0.508 0.9398)
			(stroke
				(width 0.1524)
				(type default)
			)
			(layer "F.SilkS")
		)
		(fp_line
			(start 0.508 -0.9398)
			(end -0.508 -0.9398)
			(stroke
				(width 0.1524)
				(type default)
			)
			(layer "F.SilkS")
		)
		(fp_rect
			(start -0.508 0.9398)
			(end 0.508 -0.9398)
			(stroke
				(width 0)
				(type default)
			)
			(fill no)
			(layer "F.CrtYd")
		)
		(fp_rect
			(start -0.508 0.9398)
			(end 0.508 -0.9398)
			(stroke
				(width 0)
				(type default)
			)
			(fill no)
			(layer "F.Fab")
		)
		(pad "1" smd custom
			(at 0 -0.4445 270)
			(size 0.1397 0.1397)
			(layers "F.Cu" "F.Mask" "F.Paste")
			(net "P3V3")
			(options
				(clearance outline)
				(anchor circle)
			)
			(primitives
				(gr_poly
					(pts
						(arc
							(start -0.1778 -0.2794)
							(mid -0.249642 -0.249642)
							(end -0.2794 -0.1778)
						)
						(arc
							(start -0.2794 0.1778)
							(mid -0.249642 0.249642)
							(end -0.1778 0.2794)
						)
						(arc
							(start 0.1778 0.2794)
							(mid 0.249642 0.249642)
							(end 0.2794 0.1778)
						)
						(arc
							(start 0.2794 -0.1778)
							(mid 0.249642 -0.249642)
							(end 0.1778 -0.2794)
						)
					)
					(width 0)
					(fill yes)
				)
			)
		)
		(pad "2" smd custom
			(at 0 0.4445 270)
			(size 0.1397 0.1397)
			(layers "F.Cu" "F.Mask" "F.Paste")
			(net "SSD9_CLK0_OE_MOS_N")
			(options
				(clearance outline)
				(anchor circle)
			)
			(primitives
				(gr_poly
					(pts
						(arc
							(start -0.1778 -0.2794)
							(mid -0.249642 -0.249642)
							(end -0.2794 -0.1778)
						)
						(arc
							(start -0.2794 0.1778)
							(mid -0.249642 0.249642)
							(end -0.1778 0.2794)
						)
						(arc
							(start 0.1778 0.2794)
							(mid 0.249642 0.249642)
							(end 0.2794 0.1778)
						)
						(arc
							(start 0.2794 -0.1778)
							(mid 0.249642 -0.249642)
							(end 0.1778 -0.2794)
						)
					)
					(width 0)
					(fill yes)
				)
			)
		)
	)
	(footprint ""
		(layer "F.Cu")
		(at 70.358 -447.929 180)
		(property "Reference" "U50"
			(at 0 0 180)
			(layer "F.SilkS")
			(hide yes)
			(effects
				(font
					(size 1.27 1.27)
				)
			)
		)
		(property "Value" "24LC64T-I-GP"
			(at 0 -12.1412 180)
			(unlocked yes)
			(layer "F.Fab")
			(hide yes)
			(effects
				(font
					(size 1.016 1.016)
					(thickness 0.1524)
				)
			)
		)
		(property "Device Type" "SSOIC8-1H44"
			(at 0 -13.6652 180)
			(unlocked yes)
			(layer "F.Fab")
			(hide yes)
			(effects
				(font
					(size 1.016 1.016)
					(thickness 0.1524)
				)
			)
		)
		(duplicate_pad_numbers_are_jumpers no)
		(fp_line
			(start 1.397 1.778)
			(end -1.778 1.778)
			(stroke
				(width 0.2032)
				(type default)
			)
			(layer "F.SilkS")
		)
		(fp_line
			(start 1.397 -1.778)
			(end 1.397 1.778)
			(stroke
				(width 0.2032)
				(type default)
			)
			(layer "F.SilkS")
		)
		(fp_line
			(start -1.143 0)
			(end -1.778 0.635)
			(stroke
				(width 0.2032)
				(type default)
			)
			(layer "F.SilkS")
		)
		(fp_line
			(start -1.143 0)
			(end -1.778 -0.635)
			(stroke
				(width 0.2032)
				(type default)
			)
			(layer "F.SilkS")
		)
		(fp_line
			(start -1.778 1.778)
			(end -1.778 3.81)
			(stroke
				(width 0.508)
				(type default)
			)
			(layer "F.SilkS")
		)
		(fp_line
			(start -1.778 -1.778)
			(end 1.397 -1.778)
			(stroke
				(width 0.2032)
				(type default)
			)
			(layer "F.SilkS")
		)
		(fp_line
			(start -1.778 -1.778)
			(end -1.778 2.667)
			(stroke
				(width 0.2032)
				(type default)
			)
			(layer "F.SilkS")
		)
		(fp_poly
			(pts
				(xy -2.032 3.81) (xy 2.032 3.81) (xy 2.032 -3.81) (xy -2.032 -3.81)
			)
			(stroke
				(width 0)
				(type default)
			)
			(fill no)
			(layer "F.CrtYd")
		)
		(fp_poly
			(pts
				(xy -2.032 -3.81) (xy 2.032 -3.81) (xy 2.032 3.81) (xy -2.032 3.81)
			)
			(stroke
				(width 0)
				(type default)
			)
			(fill no)
			(layer "F.Fab")
		)
		(pad "1" smd rect
			(at -0.97536 2.8194 180)
			(size 0.3556 1.524)
			(layers "F.Cu" "F.Mask" "F.Paste")
			(net "EEPROM_A0")
		)
		(pad "2" smd rect
			(at -0.32512 2.8194 180)
			(size 0.3556 1.524)
			(layers "F.Cu" "F.Mask" "F.Paste")
			(net "EEPROM_A1")
		)
		(pad "3" smd rect
			(at 0.32512 2.8194 180)
			(size 0.3556 1.524)
			(layers "F.Cu" "F.Mask" "F.Paste")
			(net "EEPROM_A2")
		)
		(pad "4" smd rect
			(at 0.97536 2.8194 180)
			(size 0.3556 1.524)
			(layers "F.Cu" "F.Mask" "F.Paste")
			(net "GND")
		)
		(pad "5" smd rect
			(at 0.97536 -2.8194 180)
			(size 0.3556 1.524)
			(layers "F.Cu" "F.Mask" "F.Paste")
			(net "EEPROM_SDA")
		)
		(pad "6" smd rect
			(at 0.32512 -2.8194 180)
			(size 0.3556 1.524)
			(layers "F.Cu" "F.Mask" "F.Paste")
			(net "EEPROM_SCL")
		)
		(pad "7" smd rect
			(at -0.32512 -2.8194 180)
			(size 0.3556 1.524)
			(layers "F.Cu" "F.Mask" "F.Paste")
			(net "EEPROM_WP")
		)
		(pad "8" smd rect
			(at -0.97536 -2.8194 180)
			(size 0.3556 1.524)
			(layers "F.Cu" "F.Mask" "F.Paste")
			(net "P3V3")
		)
	)
	(footprint ""
		(layer "F.Cu")
		(at 219.329 -449.58 90)
		(property "Reference" "SR1121"
			(at 0 0 90)
			(layer "F.SilkS")
			(hide yes)
			(effects
				(font
					(size 1.27 1.27)
				)
			)
		)
		(property "Value" "4K7R2F-GP"
			(at 0.064008 -3.993896 90)
			(unlocked yes)
			(layer "F.Fab")
			(hide yes)
			(effects
				(font
					(size 1.016 1.016)
					(thickness 0.1524)
				)
			)
		)
		(property "Device Type" "R402H16"
			(at 0.064008 -5.517896 90)
			(unlocked yes)
			(layer "F.Fab")
			(hide yes)
			(effects
				(font
					(size 1.016 1.016)
					(thickness 0.1524)
				)
			)
		)
		(duplicate_pad_numbers_are_jumpers no)
		(fp_line
			(start 0.508 -0.9398)
			(end -0.508 -0.9398)
			(stroke
				(width 0.1524)
				(type default)
			)
			(layer "F.SilkS")
		)
		(fp_line
			(start -0.508 -0.9398)
			(end -0.508 0.9398)
			(stroke
				(width 0.1524)
				(type default)
			)
			(layer "F.SilkS")
		)
		(fp_rect
			(start -0.508 0.9398)
			(end 0.508 -0.9398)
			(stroke
				(width 0)
				(type default)
			)
			(fill no)
			(layer "F.CrtYd")
		)
		(fp_rect
			(start -0.508 0.9398)
			(end 0.508 -0.9398)
			(stroke
				(width 0)
				(type default)
			)
			(fill no)
			(layer "F.Fab")
		)
		(pad "1" smd custom
			(at 0 -0.4445 90)
			(size 0.1397 0.1397)
			(layers "F.Cu" "F.Mask" "F.Paste")
			(net "P3V3")
			(options
				(clearance outline)
				(anchor circle)
			)
			(primitives
				(gr_poly
					(pts
						(arc
							(start -0.1778 -0.2794)
							(mid -0.249642 -0.249642)
							(end -0.2794 -0.1778)
						)
						(arc
							(start -0.2794 0.1778)
							(mid -0.249642 0.249642)
							(end -0.1778 0.2794)
						)
						(arc
							(start 0.1778 0.2794)
							(mid 0.249642 0.249642)
							(end 0.2794 0.1778)
						)
						(arc
							(start 0.2794 -0.1778)
							(mid 0.249642 -0.249642)
							(end 0.1778 -0.2794)
						)
					)
					(width 0)
					(fill yes)
				)
			)
		)
		(pad "2" smd custom
			(at 0 0.4445 90)
			(size 0.1397 0.1397)
			(layers "F.Cu" "F.Mask" "F.Paste")
			(net "SSD0_CLK0_OE_MOS_N")
			(options
				(clearance outline)
				(anchor circle)
			)
			(primitives
				(gr_poly
					(pts
						(arc
							(start -0.1778 -0.2794)
							(mid -0.249642 -0.249642)
							(end -0.2794 -0.1778)
						)
						(arc
							(start -0.2794 0.1778)
							(mid -0.249642 0.249642)
							(end -0.1778 0.2794)
						)
						(arc
							(start 0.1778 0.2794)
							(mid 0.249642 0.249642)
							(end 0.2794 0.1778)
						)
						(arc
							(start 0.2794 -0.1778)
							(mid 0.249642 -0.249642)
							(end 0.1778 -0.2794)
						)
					)
					(width 0)
					(fill yes)
				)
			)
		)
	)
	(footprint ""
		(layer "F.Cu")
		(at 227.203 -240.913158 90)
		(property "Reference" "U199"
			(at 0 0 90)
			(layer "F.SilkS")
			(hide yes)
			(effects
				(font
					(size 1.27 1.27)
				)
			)
		)
		(property "Value" "SN74LVC1G08DCKR-GP"
			(at -2.3368 -8.6868 90)
			(unlocked yes)
			(layer "F.Fab")
			(hide yes)
			(effects
				(font
					(size 1.016 1.016)
					(thickness 0.1524)
				)
			)
		)
		(property "Device Type" "SC70-5H44"
			(at -2.3114 -10.414 90)
			(unlocked yes)
			(layer "F.Fab")
			(hide yes)
			(effects
				(font
					(size 1.016 1.016)
					(thickness 0.1524)
				)
			)
		)
		(duplicate_pad_numbers_are_jumpers no)
		(fp_line
			(start 1.3843 -1.8034)
			(end 1.3843 -1.1176)
			(stroke
				(width 0.3302)
				(type default)
			)
			(layer "F.SilkS")
		)
		(fp_line
			(start 0.6604 -1.8034)
			(end 1.3843 -1.8034)
			(stroke
				(width 0.3302)
				(type default)
			)
			(layer "F.SilkS")
		)
		(fp_line
			(start 1.27 -1.7018)
			(end 1.27 1.7018)
			(stroke
				(width 0.1524)
				(type default)
			)
			(layer "F.SilkS")
		)
		(fp_line
			(start -1.27 -1.7018)
			(end 1.27 -1.7018)
			(stroke
				(width 0.1524)
				(type default)
			)
			(layer "F.SilkS")
		)
		(fp_line
			(start 1.27 1.7018)
			(end -1.27 1.7018)
			(stroke
				(width 0.1524)
				(type default)
			)
			(layer "F.SilkS")
		)
		(fp_line
			(start -1.27 1.7018)
			(end -1.27 -1.7018)
			(stroke
				(width 0.1524)
				(type default)
			)
			(layer "F.SilkS")
		)
		(fp_rect
			(start -1.524 1.9558)
			(end 1.524 -1.9558)
			(stroke
				(width 0)
				(type default)
			)
			(fill no)
			(layer "F.CrtYd")
		)
		(fp_poly
			(pts
				(xy -1.524 -1.9558) (xy 1.524 -1.9558) (xy 1.524 1.9558) (xy -1.524 1.9558)
			)
			(stroke
				(width 0)
				(type default)
			)
			(fill no)
			(layer "F.Fab")
		)
		(pad "1" smd rect
			(at 0.65024 -0.8255 90)
			(size 0.4064 1.2192)
			(layers "F.Cu" "F.Mask" "F.Paste")
			(net "SSD2_CLK0_OE_MOS_N")
		)
		(pad "2" smd rect
			(at 0 -0.8255 90)
			(size 0.4064 1.2192)
			(layers "F.Cu" "F.Mask" "F.Paste")
			(net "ATTN_LED_DR2_N")
		)
		(pad "3" smd rect
			(at -0.65024 -0.8255 90)
			(size 0.4064 1.2192)
			(layers "F.Cu" "F.Mask" "F.Paste")
			(net "GND")
		)
		(pad "4" smd rect
			(at -0.65024 0.8255 90)
			(size 0.4064 1.2192)
			(layers "F.Cu" "F.Mask" "F.Paste")
			(net "ATTN_LED_DR2_AND")
		)
		(pad "5" smd rect
			(at 0.65024 0.8255 90)
			(size 0.4064 1.2192)
			(layers "F.Cu" "F.Mask" "F.Paste")
			(net "P3V3")
		)
	)
	(footprint ""
		(layer "F.Cu")
		(at 226.036886 -247.804178 180)
		(property "Reference" "R9931"
			(at 0 0 180)
			(layer "F.SilkS")
			(hide yes)
			(effects
				(font
					(size 1.27 1.27)
				)
			)
		)
		(property "Value" "4K7R2J-2-GP"
			(at 0.064008 -3.993896 180)
			(unlocked yes)
			(layer "F.Fab")
			(hide yes)
			(effects
				(font
					(size 1.016 1.016)
					(thickness 0.1524)
				)
			)
		)
		(property "Device Type" "R402H16"
			(at 0.064008 -5.517896 180)
			(unlocked yes)
			(layer "F.Fab")
			(hide yes)
			(effects
				(font
					(size 1.016 1.016)
					(thickness 0.1524)
				)
			)
		)
		(duplicate_pad_numbers_are_jumpers no)
		(fp_line
			(start 0.508 -0.9398)
			(end -0.508 -0.9398)
			(stroke
				(width 0.1524)
				(type default)
			)
			(layer "F.SilkS")
		)
		(fp_line
			(start -0.508 -0.9398)
			(end -0.508 0.9398)
			(stroke
				(width 0.1524)
				(type default)
			)
			(layer "F.SilkS")
		)
		(fp_rect
			(start -0.508 0.9398)
			(end 0.508 -0.9398)
			(stroke
				(width 0)
				(type default)
			)
			(fill no)
			(layer "F.CrtYd")
		)
		(fp_rect
			(start -0.508 0.9398)
			(end 0.508 -0.9398)
			(stroke
				(width 0)
				(type default)
			)
			(fill no)
			(layer "F.Fab")
		)
		(pad "1" smd custom
			(at 0 -0.4445 180)
			(size 0.1397 0.1397)
			(layers "F.Cu" "F.Mask" "F.Paste")
			(net "P3V3")
			(options
				(clearance outline)
				(anchor circle)
			)
			(primitives
				(gr_poly
					(pts
						(arc
							(start -0.1778 -0.2794)
							(mid -0.249642 -0.249642)
							(end -0.2794 -0.1778)
						)
						(arc
							(start -0.2794 0.1778)
							(mid -0.249642 0.249642)
							(end -0.1778 0.2794)
						)
						(arc
							(start 0.1778 0.2794)
							(mid 0.249642 0.249642)
							(end 0.2794 0.1778)
						)
						(arc
							(start 0.2794 -0.1778)
							(mid 0.249642 -0.249642)
							(end 0.1778 -0.2794)
						)
					)
					(width 0)
					(fill yes)
				)
			)
		)
		(pad "2" smd custom
			(at 0 0.4445 180)
			(size 0.1397 0.1397)
			(layers "F.Cu" "F.Mask" "F.Paste")
			(net "ATTN_LED_DR2_MOS_N")
			(options
				(clearance outline)
				(anchor circle)
			)
			(primitives
				(gr_poly
					(pts
						(arc
							(start -0.1778 -0.2794)
							(mid -0.249642 -0.249642)
							(end -0.2794 -0.1778)
						)
						(arc
							(start -0.2794 0.1778)
							(mid -0.249642 0.249642)
							(end -0.1778 0.2794)
						)
						(arc
							(start 0.1778 0.2794)
							(mid 0.249642 0.249642)
							(end 0.2794 0.1778)
						)
						(arc
							(start 0.2794 -0.1778)
							(mid 0.249642 -0.249642)
							(end 0.1778 -0.2794)
						)
					)
					(width 0)
					(fill yes)
				)
			)
		)
	)
	(footprint ""
		(layer "F.Cu")
		(at 49.276 -247.396 -90)
		(property "Reference" "R9464"
			(at 0 0 270)
			(layer "F.SilkS")
			(hide yes)
			(effects
				(font
					(size 1.27 1.27)
				)
			)
		)
		(property "Value" "100R2J-2-GP"
			(at 0.064008 -3.993896 270)
			(unlocked yes)
			(layer "F.Fab")
			(hide yes)
			(effects
				(font
					(size 1.016 1.016)
					(thickness 0.1524)
				)
			)
		)
		(property "Device Type" "R402H14"
			(at 0.064008 -5.517896 270)
			(unlocked yes)
			(layer "F.Fab")
			(hide yes)
			(effects
				(font
					(size 1.016 1.016)
					(thickness 0.1524)
				)
			)
		)
		(duplicate_pad_numbers_are_jumpers no)
		(fp_line
			(start -0.508 -0.9398)
			(end -0.508 0.9398)
			(stroke
				(width 0.1524)
				(type default)
			)
			(layer "F.SilkS")
		)
		(fp_line
			(start 0.508 -0.9398)
			(end -0.508 -0.9398)
			(stroke
				(width 0.1524)
				(type default)
			)
			(layer "F.SilkS")
		)
		(fp_rect
			(start -0.508 0.9398)
			(end 0.508 -0.9398)
			(stroke
				(width 0)
				(type default)
			)
			(fill no)
			(layer "F.CrtYd")
		)
		(fp_rect
			(start -0.508 0.9398)
			(end 0.508 -0.9398)
			(stroke
				(width 0)
				(type default)
			)
			(fill no)
			(layer "F.Fab")
		)
		(pad "1" smd custom
			(at 0 -0.4445 270)
			(size 0.1397 0.1397)
			(layers "F.Cu" "F.Mask" "F.Paste")
			(net "P3V3")
			(options
				(clearance outline)
				(anchor circle)
			)
			(primitives
				(gr_poly
					(pts
						(arc
							(start -0.1778 -0.2794)
							(mid -0.249642 -0.249642)
							(end -0.2794 -0.1778)
						)
						(arc
							(start -0.2794 0.1778)
							(mid -0.249642 0.249642)
							(end -0.1778 0.2794)
						)
						(arc
							(start 0.1778 0.2794)
							(mid 0.249642 0.249642)
							(end 0.2794 0.1778)
						)
						(arc
							(start 0.2794 -0.1778)
							(mid 0.249642 -0.249642)
							(end 0.1778 -0.2794)
						)
					)
					(width 0)
					(fill yes)
				)
			)
		)
		(pad "2" smd custom
			(at 0 0.4445 270)
			(size 0.1397 0.1397)
			(layers "F.Cu" "F.Mask" "F.Paste")
			(net "DRV_ACT_7")
			(options
				(clearance outline)
				(anchor circle)
			)
			(primitives
				(gr_poly
					(pts
						(arc
							(start -0.1778 -0.2794)
							(mid -0.249642 -0.249642)
							(end -0.2794 -0.1778)
						)
						(arc
							(start -0.2794 0.1778)
							(mid -0.249642 0.249642)
							(end -0.1778 0.2794)
						)
						(arc
							(start 0.1778 0.2794)
							(mid 0.249642 0.249642)
							(end 0.2794 0.1778)
						)
						(arc
							(start 0.2794 -0.1778)
							(mid 0.249642 -0.249642)
							(end 0.1778 -0.2794)
						)
					)
					(width 0)
					(fill yes)
				)
			)
		)
	)
	(footprint ""
		(layer "F.Cu")
		(at 19.2278 -412.496 180)
		(property "Reference" "R9241"
			(at 0 0 180)
			(layer "F.SilkS")
			(hide yes)
			(effects
				(font
					(size 1.27 1.27)
				)
			)
		)
		(property "Value" "2R2010F-GP"
			(at 0.0762 -4.5466 180)
			(unlocked yes)
			(layer "F.Fab")
			(hide yes)
			(effects
				(font
					(size 1.016 1.016)
					(thickness 0.1524)
				)
			)
		)
		(property "Device Type" "R2010H26"
			(at 0.0762 -6.1468 180)
			(unlocked yes)
			(layer "F.Fab")
			(hide yes)
			(effects
				(font
					(size 1.016 1.016)
					(thickness 0.1524)
				)
			)
		)
		(duplicate_pad_numbers_are_jumpers no)
		(fp_line
			(start 3.302 1.651)
			(end 3.302 -1.651)
			(stroke
				(width 0.1524)
				(type default)
			)
			(layer "F.SilkS")
		)
		(fp_line
			(start 3.302 -1.651)
			(end -3.302 -1.651)
			(stroke
				(width 0.1524)
				(type default)
			)
			(layer "F.SilkS")
		)
		(fp_line
			(start -3.302 1.651)
			(end 3.302 1.651)
			(stroke
				(width 0.1524)
				(type default)
			)
			(layer "F.SilkS")
		)
		(fp_line
			(start -3.302 -1.651)
			(end -3.302 1.651)
			(stroke
				(width 0.1524)
				(type default)
			)
			(layer "F.SilkS")
		)
		(fp_rect
			(start -3.3782 1.7272)
			(end 3.3782 -1.7272)
			(stroke
				(width 0)
				(type default)
			)
			(fill no)
			(layer "F.CrtYd")
		)
		(fp_poly
			(pts
				(xy 3.3782 -1.7272) (xy -3.3782 -1.7272) (xy -3.3782 1.7272) (xy 3.3782 1.7272)
			)
			(stroke
				(width 0)
				(type default)
			)
			(fill no)
			(layer "F.Fab")
		)
		(pad "1" smd rect
			(at -2.3495 0 180)
			(size 1.143 2.794)
			(layers "F.Cu" "F.Mask" "F.Paste")
			(net "P12V_SSD10")
		)
		(pad "2" smd rect
			(at 2.3495 0 180)
			(size 1.143 2.794)
			(layers "F.Cu" "F.Mask" "F.Paste")
			(net "12V_PRECH_SSD10")
		)
	)
	(footprint ""
		(layer "F.Cu")
		(at 33.8328 -495.9858)
		(property "Reference" "PC1208"
			(at 0 0 0)
			(layer "F.SilkS")
			(hide yes)
			(effects
				(font
					(size 1.27 1.27)
				)
			)
		)
		(property "Value" "SCD01U50V2KX-1GP"
			(at 1.1811 -2.7051 0)
			(unlocked yes)
			(layer "F.Fab")
			(hide yes)
			(effects
				(font
					(size 1.016 1.016)
					(thickness 0.1524)
				)
			)
		)
		(property "Device Type" "C402H22"
			(at 1.1811 -4.2291 0)
			(unlocked yes)
			(layer "F.Fab")
			(hide yes)
			(effects
				(font
					(size 1.016 1.016)
					(thickness 0.1524)
				)
			)
		)
		(duplicate_pad_numbers_are_jumpers no)
		(fp_rect
			(start -0.4318 0.9525)
			(end 0.4318 -0.9525)
			(stroke
				(width 0)
				(type default)
			)
			(fill no)
			(layer "F.CrtYd")
		)
		(fp_rect
			(start -0.4318 0.9525)
			(end 0.4318 -0.9525)
			(stroke
				(width 0)
				(type default)
			)
			(fill no)
			(layer "F.Fab")
		)
		(pad "1" smd custom
			(at 0 -0.4445)
			(size 0.1524 0.1524)
			(layers "F.Cu" "F.Mask" "F.Paste")
			(net "P12V_SSD5")
			(options
				(clearance outline)
				(anchor circle)
			)
			(primitives
				(gr_poly
					(pts
						(arc
							(start 0.3048 -0.2032)
							(mid 0.275042 -0.275042)
							(end 0.2032 -0.3048)
						)
						(arc
							(start -0.2032 -0.3048)
							(mid -0.275042 -0.275042)
							(end -0.3048 -0.2032)
						)
						(arc
							(start -0.3048 0.2032)
							(mid -0.275042 0.275042)
							(end -0.2032 0.3048)
						)
						(arc
							(start 0.2032 0.3048)
							(mid 0.275042 0.275042)
							(end 0.3048 0.2032)
						)
					)
					(width 0)
					(fill yes)
				)
			)
		)
		(pad "2" smd custom
			(at 0 0.4445)
			(size 0.1524 0.1524)
			(layers "F.Cu" "F.Mask" "F.Paste")
			(net "GND")
			(options
				(clearance outline)
				(anchor circle)
			)
			(primitives
				(gr_poly
					(pts
						(arc
							(start 0.3048 -0.2032)
							(mid 0.275042 -0.275042)
							(end 0.2032 -0.3048)
						)
						(arc
							(start -0.2032 -0.3048)
							(mid -0.275042 -0.275042)
							(end -0.3048 -0.2032)
						)
						(arc
							(start -0.3048 0.2032)
							(mid -0.275042 0.275042)
							(end -0.2032 0.3048)
						)
						(arc
							(start 0.2032 0.3048)
							(mid 0.275042 0.275042)
							(end 0.3048 0.2032)
						)
					)
					(width 0)
					(fill yes)
				)
			)
		)
	)
	(footprint ""
		(layer "F.Cu")
		(at 30.99435 -145.12925)
		(property "Reference" "SR1137"
			(at 0 0 0)
			(layer "F.SilkS")
			(hide yes)
			(effects
				(font
					(size 1.27 1.27)
				)
			)
		)
		(property "Value" "4K7R2F-GP"
			(at 0.064008 -3.993896 0)
			(unlocked yes)
			(layer "F.Fab")
			(hide yes)
			(effects
				(font
					(size 1.016 1.016)
					(thickness 0.1524)
				)
			)
		)
		(property "Device Type" "R402H16"
			(at 0.064008 -5.517896 0)
			(unlocked yes)
			(layer "F.Fab")
			(hide yes)
			(effects
				(font
					(size 1.016 1.016)
					(thickness 0.1524)
				)
			)
		)
		(duplicate_pad_numbers_are_jumpers no)
		(fp_line
			(start -0.508 -0.9398)
			(end -0.508 0.9398)
			(stroke
				(width 0.1524)
				(type default)
			)
			(layer "F.SilkS")
		)
		(fp_line
			(start 0.508 -0.9398)
			(end -0.508 -0.9398)
			(stroke
				(width 0.1524)
				(type default)
			)
			(layer "F.SilkS")
		)
		(fp_rect
			(start -0.508 0.9398)
			(end 0.508 -0.9398)
			(stroke
				(width 0)
				(type default)
			)
			(fill no)
			(layer "F.CrtYd")
		)
		(fp_rect
			(start -0.508 0.9398)
			(end 0.508 -0.9398)
			(stroke
				(width 0)
				(type default)
			)
			(fill no)
			(layer "F.Fab")
		)
		(pad "1" smd custom
			(at 0 -0.4445)
			(size 0.1397 0.1397)
			(layers "F.Cu" "F.Mask" "F.Paste")
			(net "P3V3")
			(options
				(clearance outline)
				(anchor circle)
			)
			(primitives
				(gr_poly
					(pts
						(arc
							(start -0.1778 -0.2794)
							(mid -0.249642 -0.249642)
							(end -0.2794 -0.1778)
						)
						(arc
							(start -0.2794 0.1778)
							(mid -0.249642 0.249642)
							(end -0.1778 0.2794)
						)
						(arc
							(start 0.1778 0.2794)
							(mid 0.249642 0.249642)
							(end 0.2794 0.1778)
						)
						(arc
							(start 0.2794 -0.1778)
							(mid 0.249642 -0.249642)
							(end 0.1778 -0.2794)
						)
					)
					(width 0)
					(fill yes)
				)
			)
		)
		(pad "2" smd custom
			(at 0 0.4445)
			(size 0.1397 0.1397)
			(layers "F.Cu" "F.Mask" "F.Paste")
			(net "SSD8_CLK0_OE_MOS_N")
			(options
				(clearance outline)
				(anchor circle)
			)
			(primitives
				(gr_poly
					(pts
						(arc
							(start -0.1778 -0.2794)
							(mid -0.249642 -0.249642)
							(end -0.2794 -0.1778)
						)
						(arc
							(start -0.2794 0.1778)
							(mid -0.249642 0.249642)
							(end -0.1778 0.2794)
						)
						(arc
							(start 0.1778 0.2794)
							(mid 0.249642 0.249642)
							(end 0.2794 0.1778)
						)
						(arc
							(start 0.2794 -0.1778)
							(mid 0.249642 -0.249642)
							(end 0.1778 -0.2794)
						)
					)
					(width 0)
					(fill yes)
				)
			)
		)
	)
	(footprint ""
		(layer "F.Cu")
		(at 37.0332 -291.7444)
		(property "Reference" "PC1248"
			(at 0 0 0)
			(layer "F.SilkS")
			(hide yes)
			(effects
				(font
					(size 1.27 1.27)
				)
			)
		)
		(property "Value" "SCD01U50V2KX-1GP"
			(at 1.1811 -2.7051 0)
			(unlocked yes)
			(layer "F.Fab")
			(hide yes)
			(effects
				(font
					(size 1.016 1.016)
					(thickness 0.1524)
				)
			)
		)
		(property "Device Type" "C402H22"
			(at 1.1811 -4.2291 0)
			(unlocked yes)
			(layer "F.Fab")
			(hide yes)
			(effects
				(font
					(size 1.016 1.016)
					(thickness 0.1524)
				)
			)
		)
		(duplicate_pad_numbers_are_jumpers no)
		(fp_rect
			(start -0.4318 0.9525)
			(end 0.4318 -0.9525)
			(stroke
				(width 0)
				(type default)
			)
			(fill no)
			(layer "F.CrtYd")
		)
		(fp_rect
			(start -0.4318 0.9525)
			(end 0.4318 -0.9525)
			(stroke
				(width 0)
				(type default)
			)
			(fill no)
			(layer "F.Fab")
		)
		(pad "1" smd custom
			(at 0 -0.4445)
			(size 0.1524 0.1524)
			(layers "F.Cu" "F.Mask" "F.Paste")
			(net "P12V_SSD7")
			(options
				(clearance outline)
				(anchor circle)
			)
			(primitives
				(gr_poly
					(pts
						(arc
							(start 0.3048 -0.2032)
							(mid 0.275042 -0.275042)
							(end 0.2032 -0.3048)
						)
						(arc
							(start -0.2032 -0.3048)
							(mid -0.275042 -0.275042)
							(end -0.3048 -0.2032)
						)
						(arc
							(start -0.3048 0.2032)
							(mid -0.275042 0.275042)
							(end -0.2032 0.3048)
						)
						(arc
							(start 0.2032 0.3048)
							(mid 0.275042 0.275042)
							(end 0.3048 0.2032)
						)
					)
					(width 0)
					(fill yes)
				)
			)
		)
		(pad "2" smd custom
			(at 0 0.4445)
			(size 0.1524 0.1524)
			(layers "F.Cu" "F.Mask" "F.Paste")
			(net "GND")
			(options
				(clearance outline)
				(anchor circle)
			)
			(primitives
				(gr_poly
					(pts
						(arc
							(start 0.3048 -0.2032)
							(mid 0.275042 -0.275042)
							(end 0.2032 -0.3048)
						)
						(arc
							(start -0.2032 -0.3048)
							(mid -0.275042 -0.275042)
							(end -0.3048 -0.2032)
						)
						(arc
							(start -0.3048 0.2032)
							(mid -0.275042 0.275042)
							(end -0.2032 0.3048)
						)
						(arc
							(start 0.2032 0.3048)
							(mid 0.275042 0.275042)
							(end 0.3048 0.2032)
						)
					)
					(width 0)
					(fill yes)
				)
			)
		)
	)
	(footprint ""
		(layer "F.Cu")
		(at 94.488 -312.801 180)
		(property "Reference" "C8851"
			(at 0 0 180)
			(layer "F.SilkS")
			(hide yes)
			(effects
				(font
					(size 1.27 1.27)
				)
			)
		)
		(property "Value" "SCD1U16V2KX-3GP"
			(at 1.1811 -2.7051 180)
			(unlocked yes)
			(layer "F.Fab")
			(hide yes)
			(effects
				(font
					(size 1.016 1.016)
					(thickness 0.1524)
				)
			)
		)
		(property "Device Type" "C402H22"
			(at 1.1811 -4.2291 180)
			(unlocked yes)
			(layer "F.Fab")
			(hide yes)
			(effects
				(font
					(size 1.016 1.016)
					(thickness 0.1524)
				)
			)
		)
		(duplicate_pad_numbers_are_jumpers no)
		(fp_rect
			(start -0.4318 0.9525)
			(end 0.4318 -0.9525)
			(stroke
				(width 0)
				(type default)
			)
			(fill no)
			(layer "F.CrtYd")
		)
		(fp_rect
			(start -0.4318 0.9525)
			(end 0.4318 -0.9525)
			(stroke
				(width 0)
				(type default)
			)
			(fill no)
			(layer "F.Fab")
		)
		(pad "1" smd custom
			(at 0 -0.4445 180)
			(size 0.1524 0.1524)
			(layers "F.Cu" "F.Mask" "F.Paste")
			(net "VDD_IO_2")
			(options
				(clearance outline)
				(anchor circle)
			)
			(primitives
				(gr_poly
					(pts
						(arc
							(start 0.3048 -0.2032)
							(mid 0.275042 -0.275042)
							(end 0.2032 -0.3048)
						)
						(arc
							(start -0.2032 -0.3048)
							(mid -0.275042 -0.275042)
							(end -0.3048 -0.2032)
						)
						(arc
							(start -0.3048 0.2032)
							(mid -0.275042 0.275042)
							(end -0.2032 0.3048)
						)
						(arc
							(start 0.2032 0.3048)
							(mid 0.275042 0.275042)
							(end 0.3048 0.2032)
						)
					)
					(width 0)
					(fill yes)
				)
			)
		)
		(pad "2" smd custom
			(at 0 0.4445 180)
			(size 0.1524 0.1524)
			(layers "F.Cu" "F.Mask" "F.Paste")
			(net "GND")
			(options
				(clearance outline)
				(anchor circle)
			)
			(primitives
				(gr_poly
					(pts
						(arc
							(start 0.3048 -0.2032)
							(mid 0.275042 -0.275042)
							(end 0.2032 -0.3048)
						)
						(arc
							(start -0.2032 -0.3048)
							(mid -0.275042 -0.275042)
							(end -0.3048 -0.2032)
						)
						(arc
							(start -0.3048 0.2032)
							(mid -0.275042 0.275042)
							(end -0.2032 0.3048)
						)
						(arc
							(start 0.2032 0.3048)
							(mid 0.275042 0.275042)
							(end 0.3048 0.2032)
						)
					)
					(width 0)
					(fill yes)
				)
			)
		)
	)
	(footprint ""
		(layer "F.Cu")
		(at 49.149 -145.669 -90)
		(property "Reference" "R9428"
			(at 0 0 270)
			(layer "F.SilkS")
			(hide yes)
			(effects
				(font
					(size 1.27 1.27)
				)
			)
		)
		(property "Value" "330R2F-GP"
			(at 0.064008 -3.993896 270)
			(unlocked yes)
			(layer "F.Fab")
			(hide yes)
			(effects
				(font
					(size 1.016 1.016)
					(thickness 0.1524)
				)
			)
		)
		(property "Device Type" "R402H16"
			(at 0.064008 -5.517896 270)
			(unlocked yes)
			(layer "F.Fab")
			(hide yes)
			(effects
				(font
					(size 1.016 1.016)
					(thickness 0.1524)
				)
			)
		)
		(duplicate_pad_numbers_are_jumpers no)
		(fp_line
			(start -0.508 -0.9398)
			(end -0.508 0.9398)
			(stroke
				(width 0.1524)
				(type default)
			)
			(layer "F.SilkS")
		)
		(fp_line
			(start 0.508 -0.9398)
			(end -0.508 -0.9398)
			(stroke
				(width 0.1524)
				(type default)
			)
			(layer "F.SilkS")
		)
		(fp_rect
			(start -0.508 0.9398)
			(end 0.508 -0.9398)
			(stroke
				(width 0)
				(type default)
			)
			(fill no)
			(layer "F.CrtYd")
		)
		(fp_rect
			(start -0.508 0.9398)
			(end 0.508 -0.9398)
			(stroke
				(width 0)
				(type default)
			)
			(fill no)
			(layer "F.Fab")
		)
		(pad "1" smd custom
			(at 0 -0.4445 270)
			(size 0.1397 0.1397)
			(layers "F.Cu" "F.Mask" "F.Paste")
			(net "P3V3")
			(options
				(clearance outline)
				(anchor circle)
			)
			(primitives
				(gr_poly
					(pts
						(arc
							(start -0.1778 -0.2794)
							(mid -0.249642 -0.249642)
							(end -0.2794 -0.1778)
						)
						(arc
							(start -0.2794 0.1778)
							(mid -0.249642 0.249642)
							(end -0.1778 0.2794)
						)
						(arc
							(start 0.1778 0.2794)
							(mid 0.249642 0.249642)
							(end 0.2794 0.1778)
						)
						(arc
							(start 0.2794 -0.1778)
							(mid 0.249642 -0.249642)
							(end 0.1778 -0.2794)
						)
					)
					(width 0)
					(fill yes)
				)
			)
		)
		(pad "2" smd custom
			(at 0 0.4445 270)
			(size 0.1397 0.1397)
			(layers "F.Cu" "F.Mask" "F.Paste")
			(net "DRV_ATTN_8")
			(options
				(clearance outline)
				(anchor circle)
			)
			(primitives
				(gr_poly
					(pts
						(arc
							(start -0.1778 -0.2794)
							(mid -0.249642 -0.249642)
							(end -0.2794 -0.1778)
						)
						(arc
							(start -0.2794 0.1778)
							(mid -0.249642 0.249642)
							(end -0.1778 0.2794)
						)
						(arc
							(start 0.1778 0.2794)
							(mid 0.249642 0.249642)
							(end 0.2794 0.1778)
						)
						(arc
							(start 0.2794 -0.1778)
							(mid 0.249642 -0.249642)
							(end 0.1778 -0.2794)
						)
					)
					(width 0)
					(fill yes)
				)
			)
		)
	)
	(footprint ""
		(layer "F.Cu")
		(at 87.757 -113.665 -90)
		(property "Reference" "C9373"
			(at 0 0 270)
			(layer "F.SilkS")
			(hide yes)
			(effects
				(font
					(size 1.27 1.27)
				)
			)
		)
		(property "Value" "SC1KP50V2KX-1GP"
			(at 1.1811 -2.7051 270)
			(unlocked yes)
			(layer "F.Fab")
			(hide yes)
			(effects
				(font
					(size 1.016 1.016)
					(thickness 0.1524)
				)
			)
		)
		(property "Device Type" "C402H22"
			(at 1.1811 -4.2291 270)
			(unlocked yes)
			(layer "F.Fab")
			(hide yes)
			(effects
				(font
					(size 1.016 1.016)
					(thickness 0.1524)
				)
			)
		)
		(duplicate_pad_numbers_are_jumpers no)
		(fp_rect
			(start -0.4318 0.9525)
			(end 0.4318 -0.9525)
			(stroke
				(width 0)
				(type default)
			)
			(fill no)
			(layer "F.CrtYd")
		)
		(fp_rect
			(start -0.4318 0.9525)
			(end 0.4318 -0.9525)
			(stroke
				(width 0)
				(type default)
			)
			(fill no)
			(layer "F.Fab")
		)
		(pad "1" smd custom
			(at 0 -0.4445 270)
			(size 0.1524 0.1524)
			(layers "F.Cu" "F.Mask" "F.Paste")
			(net "SSD13_CLK0_OE_R_N")
			(options
				(clearance outline)
				(anchor circle)
			)
			(primitives
				(gr_poly
					(pts
						(arc
							(start 0.3048 -0.2032)
							(mid 0.275042 -0.275042)
							(end 0.2032 -0.3048)
						)
						(arc
							(start -0.2032 -0.3048)
							(mid -0.275042 -0.275042)
							(end -0.3048 -0.2032)
						)
						(arc
							(start -0.3048 0.2032)
							(mid -0.275042 0.275042)
							(end -0.2032 0.3048)
						)
						(arc
							(start 0.2032 0.3048)
							(mid 0.275042 0.275042)
							(end 0.3048 0.2032)
						)
					)
					(width 0)
					(fill yes)
				)
			)
		)
		(pad "2" smd custom
			(at 0 0.4445 270)
			(size 0.1524 0.1524)
			(layers "F.Cu" "F.Mask" "F.Paste")
			(net "GND")
			(options
				(clearance outline)
				(anchor circle)
			)
			(primitives
				(gr_poly
					(pts
						(arc
							(start 0.3048 -0.2032)
							(mid 0.275042 -0.275042)
							(end 0.2032 -0.3048)
						)
						(arc
							(start -0.2032 -0.3048)
							(mid -0.275042 -0.275042)
							(end -0.3048 -0.2032)
						)
						(arc
							(start -0.3048 0.2032)
							(mid -0.275042 0.275042)
							(end -0.2032 0.3048)
						)
						(arc
							(start 0.2032 0.3048)
							(mid 0.275042 0.275042)
							(end 0.3048 0.2032)
						)
					)
					(width 0)
					(fill yes)
				)
			)
		)
	)
	(footprint ""
		(layer "F.Cu")
		(at 87.757 -443.865 -90)
		(property "Reference" "C9367"
			(at 0 0 270)
			(layer "F.SilkS")
			(hide yes)
			(effects
				(font
					(size 1.27 1.27)
				)
			)
		)
		(property "Value" "SC1KP50V2KX-1GP"
			(at 1.1811 -2.7051 270)
			(unlocked yes)
			(layer "F.Fab")
			(hide yes)
			(effects
				(font
					(size 1.016 1.016)
					(thickness 0.1524)
				)
			)
		)
		(property "Device Type" "C402H22"
			(at 1.1811 -4.2291 270)
			(unlocked yes)
			(layer "F.Fab")
			(hide yes)
			(effects
				(font
					(size 1.016 1.016)
					(thickness 0.1524)
				)
			)
		)
		(duplicate_pad_numbers_are_jumpers no)
		(fp_rect
			(start -0.4318 0.9525)
			(end 0.4318 -0.9525)
			(stroke
				(width 0)
				(type default)
			)
			(fill no)
			(layer "F.CrtYd")
		)
		(fp_rect
			(start -0.4318 0.9525)
			(end 0.4318 -0.9525)
			(stroke
				(width 0)
				(type default)
			)
			(fill no)
			(layer "F.Fab")
		)
		(pad "1" smd custom
			(at 0 -0.4445 270)
			(size 0.1524 0.1524)
			(layers "F.Cu" "F.Mask" "F.Paste")
			(net "SSD5_CLK0_OE_R_N")
			(options
				(clearance outline)
				(anchor circle)
			)
			(primitives
				(gr_poly
					(pts
						(arc
							(start 0.3048 -0.2032)
							(mid 0.275042 -0.275042)
							(end 0.2032 -0.3048)
						)
						(arc
							(start -0.2032 -0.3048)
							(mid -0.275042 -0.275042)
							(end -0.3048 -0.2032)
						)
						(arc
							(start -0.3048 0.2032)
							(mid -0.275042 0.275042)
							(end -0.2032 0.3048)
						)
						(arc
							(start 0.2032 0.3048)
							(mid 0.275042 0.275042)
							(end 0.3048 0.2032)
						)
					)
					(width 0)
					(fill yes)
				)
			)
		)
		(pad "2" smd custom
			(at 0 0.4445 270)
			(size 0.1524 0.1524)
			(layers "F.Cu" "F.Mask" "F.Paste")
			(net "GND")
			(options
				(clearance outline)
				(anchor circle)
			)
			(primitives
				(gr_poly
					(pts
						(arc
							(start 0.3048 -0.2032)
							(mid 0.275042 -0.275042)
							(end 0.2032 -0.3048)
						)
						(arc
							(start -0.2032 -0.3048)
							(mid -0.275042 -0.275042)
							(end -0.3048 -0.2032)
						)
						(arc
							(start -0.3048 0.2032)
							(mid -0.275042 0.275042)
							(end -0.2032 0.3048)
						)
						(arc
							(start 0.2032 0.3048)
							(mid 0.275042 0.275042)
							(end 0.3048 0.2032)
						)
					)
					(width 0)
					(fill yes)
				)
			)
		)
	)
	(footprint ""
		(layer "F.Cu")
		(at 88.138 -318.643)
		(property "Reference" "R9611"
			(at 0 0 0)
			(layer "F.SilkS")
			(hide yes)
			(effects
				(font
					(size 1.27 1.27)
				)
			)
		)
		(property "Value" "10R2F-L-GP"
			(at 0.064008 -3.993896 0)
			(unlocked yes)
			(layer "F.Fab")
			(hide yes)
			(effects
				(font
					(size 1.016 1.016)
					(thickness 0.1524)
				)
			)
		)
		(property "Device Type" "R402H14"
			(at 0.064008 -5.517896 0)
			(unlocked yes)
			(layer "F.Fab")
			(hide yes)
			(effects
				(font
					(size 1.016 1.016)
					(thickness 0.1524)
				)
			)
		)
		(duplicate_pad_numbers_are_jumpers no)
		(fp_line
			(start -0.508 -0.9398)
			(end -0.508 0.9398)
			(stroke
				(width 0.1524)
				(type default)
			)
			(layer "F.SilkS")
		)
		(fp_line
			(start 0.508 -0.9398)
			(end -0.508 -0.9398)
			(stroke
				(width 0.1524)
				(type default)
			)
			(layer "F.SilkS")
		)
		(fp_rect
			(start -0.508 0.9398)
			(end 0.508 -0.9398)
			(stroke
				(width 0)
				(type default)
			)
			(fill no)
			(layer "F.CrtYd")
		)
		(fp_rect
			(start -0.508 0.9398)
			(end 0.508 -0.9398)
			(stroke
				(width 0)
				(type default)
			)
			(fill no)
			(layer "F.Fab")
		)
		(pad "1" smd custom
			(at 0 -0.4445)
			(size 0.1397 0.1397)
			(layers "F.Cu" "F.Mask" "F.Paste")
			(net "SSD11_CLK0_OE_N")
			(options
				(clearance outline)
				(anchor circle)
			)
			(primitives
				(gr_poly
					(pts
						(arc
							(start -0.1778 -0.2794)
							(mid -0.249642 -0.249642)
							(end -0.2794 -0.1778)
						)
						(arc
							(start -0.2794 0.1778)
							(mid -0.249642 0.249642)
							(end -0.1778 0.2794)
						)
						(arc
							(start 0.1778 0.2794)
							(mid 0.249642 0.249642)
							(end 0.2794 0.1778)
						)
						(arc
							(start 0.2794 -0.1778)
							(mid 0.249642 -0.249642)
							(end 0.1778 -0.2794)
						)
					)
					(width 0)
					(fill yes)
				)
			)
		)
		(pad "2" smd custom
			(at 0 0.4445)
			(size 0.1397 0.1397)
			(layers "F.Cu" "F.Mask" "F.Paste")
			(net "SSD11_CLK0_OE_R_N")
			(options
				(clearance outline)
				(anchor circle)
			)
			(primitives
				(gr_poly
					(pts
						(arc
							(start -0.1778 -0.2794)
							(mid -0.249642 -0.249642)
							(end -0.2794 -0.1778)
						)
						(arc
							(start -0.2794 0.1778)
							(mid -0.249642 0.249642)
							(end -0.1778 0.2794)
						)
						(arc
							(start 0.1778 0.2794)
							(mid 0.249642 0.249642)
							(end 0.2794 0.1778)
						)
						(arc
							(start 0.2794 -0.1778)
							(mid 0.249642 -0.249642)
							(end 0.1778 -0.2794)
						)
					)
					(width 0)
					(fill yes)
				)
			)
		)
	)
	(footprint ""
		(layer "F.Cu")
		(at 86.614 -306.324 180)
		(property "Reference" "C8911"
			(at 0 0 180)
			(layer "F.SilkS")
			(hide yes)
			(effects
				(font
					(size 1.27 1.27)
				)
			)
		)
		(property "Value" "SC1U10V2KX-7-GP"
			(at 1.1811 -2.7051 180)
			(unlocked yes)
			(layer "F.Fab")
			(hide yes)
			(effects
				(font
					(size 1.016 1.016)
					(thickness 0.1524)
				)
			)
		)
		(property "Device Type" "C402H22"
			(at 1.1811 -4.2291 180)
			(unlocked yes)
			(layer "F.Fab")
			(hide yes)
			(effects
				(font
					(size 1.016 1.016)
					(thickness 0.1524)
				)
			)
		)
		(duplicate_pad_numbers_are_jumpers no)
		(fp_rect
			(start -0.4318 0.9525)
			(end 0.4318 -0.9525)
			(stroke
				(width 0)
				(type default)
			)
			(fill no)
			(layer "F.CrtYd")
		)
		(fp_rect
			(start -0.4318 0.9525)
			(end 0.4318 -0.9525)
			(stroke
				(width 0)
				(type default)
			)
			(fill no)
			(layer "F.Fab")
		)
		(pad "1" smd custom
			(at 0 -0.4445 180)
			(size 0.1524 0.1524)
			(layers "F.Cu" "F.Mask" "F.Paste")
			(net "VDDR_2")
			(options
				(clearance outline)
				(anchor circle)
			)
			(primitives
				(gr_poly
					(pts
						(arc
							(start 0.3048 -0.2032)
							(mid 0.275042 -0.275042)
							(end 0.2032 -0.3048)
						)
						(arc
							(start -0.2032 -0.3048)
							(mid -0.275042 -0.275042)
							(end -0.3048 -0.2032)
						)
						(arc
							(start -0.3048 0.2032)
							(mid -0.275042 0.275042)
							(end -0.2032 0.3048)
						)
						(arc
							(start 0.2032 0.3048)
							(mid 0.275042 0.275042)
							(end 0.3048 0.2032)
						)
					)
					(width 0)
					(fill yes)
				)
			)
		)
		(pad "2" smd custom
			(at 0 0.4445 180)
			(size 0.1524 0.1524)
			(layers "F.Cu" "F.Mask" "F.Paste")
			(net "GND")
			(options
				(clearance outline)
				(anchor circle)
			)
			(primitives
				(gr_poly
					(pts
						(arc
							(start 0.3048 -0.2032)
							(mid 0.275042 -0.275042)
							(end 0.2032 -0.3048)
						)
						(arc
							(start -0.2032 -0.3048)
							(mid -0.275042 -0.275042)
							(end -0.3048 -0.2032)
						)
						(arc
							(start -0.3048 0.2032)
							(mid -0.275042 0.275042)
							(end -0.2032 0.3048)
						)
						(arc
							(start 0.2032 0.3048)
							(mid 0.275042 0.275042)
							(end 0.3048 0.2032)
						)
					)
					(width 0)
					(fill yes)
				)
			)
		)
	)
	(footprint ""
		(layer "F.Cu")
		(at 22.14245 -95.95485 90)
		(property "Reference" "R9839"
			(at 0 0 90)
			(layer "F.SilkS")
			(hide yes)
			(effects
				(font
					(size 1.27 1.27)
				)
			)
		)
		(property "Value" "1KR2J-1-GP"
			(at 0.064008 -3.993896 90)
			(unlocked yes)
			(layer "F.Fab")
			(hide yes)
			(effects
				(font
					(size 1.016 1.016)
					(thickness 0.1524)
				)
			)
		)
		(property "Device Type" "R402H16"
			(at 0.064008 -5.517896 90)
			(unlocked yes)
			(layer "F.Fab")
			(hide yes)
			(effects
				(font
					(size 1.016 1.016)
					(thickness 0.1524)
				)
			)
		)
		(duplicate_pad_numbers_are_jumpers no)
		(fp_line
			(start 0.508 -0.9398)
			(end -0.508 -0.9398)
			(stroke
				(width 0.1524)
				(type default)
			)
			(layer "F.SilkS")
		)
		(fp_line
			(start -0.508 -0.9398)
			(end -0.508 0.9398)
			(stroke
				(width 0.1524)
				(type default)
			)
			(layer "F.SilkS")
		)
		(fp_rect
			(start -0.508 0.9398)
			(end 0.508 -0.9398)
			(stroke
				(width 0)
				(type default)
			)
			(fill no)
			(layer "F.CrtYd")
		)
		(fp_rect
			(start -0.508 0.9398)
			(end 0.508 -0.9398)
			(stroke
				(width 0)
				(type default)
			)
			(fill no)
			(layer "F.Fab")
		)
		(pad "1" smd custom
			(at 0 -0.4445 90)
			(size 0.1397 0.1397)
			(layers "F.Cu" "F.Mask" "F.Paste")
			(net "SSD9_PWREN")
			(options
				(clearance outline)
				(anchor circle)
			)
			(primitives
				(gr_poly
					(pts
						(arc
							(start -0.1778 -0.2794)
							(mid -0.249642 -0.249642)
							(end -0.2794 -0.1778)
						)
						(arc
							(start -0.2794 0.1778)
							(mid -0.249642 0.249642)
							(end -0.1778 0.2794)
						)
						(arc
							(start 0.1778 0.2794)
							(mid 0.249642 0.249642)
							(end 0.2794 0.1778)
						)
						(arc
							(start 0.2794 -0.1778)
							(mid 0.249642 -0.249642)
							(end 0.1778 -0.2794)
						)
					)
					(width 0)
					(fill yes)
				)
			)
		)
		(pad "2" smd custom
			(at 0 0.4445 90)
			(size 0.1397 0.1397)
			(layers "F.Cu" "F.Mask" "F.Paste")
			(net "SSD9_PWREN_R")
			(options
				(clearance outline)
				(anchor circle)
			)
			(primitives
				(gr_poly
					(pts
						(arc
							(start -0.1778 -0.2794)
							(mid -0.249642 -0.249642)
							(end -0.2794 -0.1778)
						)
						(arc
							(start -0.2794 0.1778)
							(mid -0.249642 0.249642)
							(end -0.1778 0.2794)
						)
						(arc
							(start 0.1778 0.2794)
							(mid 0.249642 0.249642)
							(end 0.2794 0.1778)
						)
						(arc
							(start 0.2794 -0.1778)
							(mid 0.249642 -0.249642)
							(end 0.1778 -0.2794)
						)
					)
					(width 0)
					(fill yes)
				)
			)
		)
	)
	(footprint ""
		(layer "F.Cu")
		(at 25.71115 -101.86035 90)
		(property "Reference" "R9864"
			(at 0 0 90)
			(layer "F.SilkS")
			(hide yes)
			(effects
				(font
					(size 1.27 1.27)
				)
			)
		)
		(property "Value" "2K2R5F-GP"
			(at 0 -8.9535 90)
			(unlocked yes)
			(layer "F.Fab")
			(hide yes)
			(effects
				(font
					(size 1.27 1.016)
					(thickness 0.1524)
				)
			)
		)
		(property "Device Type" "R805H24"
			(at 0 -10.6299 90)
			(unlocked yes)
			(layer "F.Fab")
			(hide yes)
			(effects
				(font
					(size 1.27 1.016)
					(thickness 0.1524)
				)
			)
		)
		(duplicate_pad_numbers_are_jumpers no)
		(fp_line
			(start 0.889 -1.7018)
			(end -0.889 -1.7018)
			(stroke
				(width 0.1524)
				(type default)
			)
			(layer "F.SilkS")
		)
		(fp_line
			(start 0.889 -1.7018)
			(end 0.889 -0.381)
			(stroke
				(width 0.1524)
				(type default)
			)
			(layer "F.SilkS")
		)
		(fp_line
			(start -0.889 -1.7018)
			(end -0.889 0.2794)
			(stroke
				(width 0.1524)
				(type default)
			)
			(layer "F.SilkS")
		)
		(fp_line
			(start -0.889 0.0762)
			(end -0.889 1.7018)
			(stroke
				(width 0.1524)
				(type default)
			)
			(layer "F.SilkS")
		)
		(fp_line
			(start 0.889 1.7018)
			(end 0.889 -0.508)
			(stroke
				(width 0.1524)
				(type default)
			)
			(layer "F.SilkS")
		)
		(fp_line
			(start -0.889 1.7018)
			(end 0.889 1.7018)
			(stroke
				(width 0.1524)
				(type default)
			)
			(layer "F.SilkS")
		)
		(fp_poly
			(pts
				(xy 0.9652 -1.778) (xy 0.9652 1.778) (xy -0.9652 1.778) (xy -0.9652 -1.778)
			)
			(stroke
				(width 0)
				(type default)
			)
			(fill no)
			(layer "F.CrtYd")
		)
		(fp_rect
			(start -0.9652 1.778)
			(end 0.9652 -1.778)
			(stroke
				(width 0)
				(type default)
			)
			(fill no)
			(layer "F.Fab")
		)
		(pad "1" smd rect
			(at 0 -0.9652 90)
			(size 1.397 1.143)
			(layers "F.Cu" "F.Mask" "F.Paste")
			(net "P12V_SSD13")
		)
		(pad "2" smd rect
			(at 0 0.9652 90)
			(size 1.397 1.143)
			(layers "F.Cu" "F.Mask" "F.Paste")
			(net "P12V_MOST13_GATE_D")
		)
	)
	(footprint ""
		(layer "F.Cu")
		(at 24.3078 -297.2816 180)
		(property "Reference" "Q15"
			(at 0 0 180)
			(layer "F.SilkS")
			(hide yes)
			(effects
				(font
					(size 1.27 1.27)
				)
			)
		)
		(property "Value" "2N7002A-7-GP"
			(at 0.127 -8.9662 180)
			(unlocked yes)
			(layer "F.Fab")
			(hide yes)
			(effects
				(font
					(size 1.016 1.016)
					(thickness 0.1524)
				)
			)
		)
		(property "Device Type" "SOT23DGS2D4H48"
			(at 0.127 -10.4902 180)
			(unlocked yes)
			(layer "F.Fab")
			(hide yes)
			(effects
				(font
					(size 1.016 1.016)
					(thickness 0.1524)
				)
			)
		)
		(duplicate_pad_numbers_are_jumpers no)
		(fp_line
			(start 1.651 1.778)
			(end 1.651 -1.778)
			(stroke
				(width 0.1524)
				(type default)
			)
			(layer "F.SilkS")
		)
		(fp_line
			(start 1.651 -1.778)
			(end -1.651 -1.778)
			(stroke
				(width 0.1524)
				(type default)
			)
			(layer "F.SilkS")
		)
		(fp_line
			(start -1.651 1.778)
			(end 1.651 1.778)
			(stroke
				(width 0.1524)
				(type default)
			)
			(layer "F.SilkS")
		)
		(fp_line
			(start -1.651 -1.778)
			(end -1.651 1.778)
			(stroke
				(width 0.1524)
				(type default)
			)
			(layer "F.SilkS")
		)
		(fp_poly
			(pts
				(xy -1.778 1.8796) (xy -1.778 -1.8796) (xy 1.778 -1.8796) (xy 1.778 1.8796)
			)
			(stroke
				(width 0)
				(type default)
			)
			(fill no)
			(layer "F.CrtYd")
		)
		(fp_poly
			(pts
				(xy -1.778 1.8796) (xy -1.778 -1.8796) (xy 1.778 -1.8796) (xy 1.778 1.8796)
			)
			(stroke
				(width 0)
				(type default)
			)
			(fill no)
			(layer "F.Fab")
		)
		(pad "D" smd custom
			(at 0 -0.9525 180)
			(size 0.1905 0.1905)
			(layers "F.Cu" "F.Mask" "F.Paste")
			(net "SW_SSD7_R")
			(options
				(clearance outline)
				(anchor circle)
			)
			(primitives
				(gr_poly
					(pts
						(arc
							(start -0.1778 0.5715)
							(mid -0.321484 0.511984)
							(end -0.381 0.3683)
						)
						(arc
							(start -0.381 -0.3683)
							(mid -0.321484 -0.511984)
							(end -0.1778 -0.5715)
						)
						(arc
							(start 0.1778 -0.5715)
							(mid 0.321484 -0.511984)
							(end 0.381 -0.3683)
						)
						(arc
							(start 0.381 0.3683)
							(mid 0.321484 0.511984)
							(end 0.1778 0.5715)
						)
					)
					(width 0)
					(fill yes)
				)
			)
		)
		(pad "G" smd custom
			(at -0.98425 0.9525 180)
			(size 0.1905 0.1905)
			(layers "F.Cu" "F.Mask" "F.Paste")
			(net "SSD7_PWREN")
			(options
				(clearance outline)
				(anchor circle)
			)
			(primitives
				(gr_poly
					(pts
						(arc
							(start -0.1778 0.5715)
							(mid -0.321484 0.511984)
							(end -0.381 0.3683)
						)
						(arc
							(start -0.381 -0.3683)
							(mid -0.321484 -0.511984)
							(end -0.1778 -0.5715)
						)
						(arc
							(start 0.1778 -0.5715)
							(mid 0.321484 -0.511984)
							(end 0.381 -0.3683)
						)
						(arc
							(start 0.381 0.3683)
							(mid 0.321484 0.511984)
							(end 0.1778 0.5715)
						)
					)
					(width 0)
					(fill yes)
				)
			)
		)
		(pad "S" smd custom
			(at 0.98425 0.9525 180)
			(size 0.1905 0.1905)
			(layers "F.Cu" "F.Mask" "F.Paste")
			(net "GND")
			(options
				(clearance outline)
				(anchor circle)
			)
			(primitives
				(gr_poly
					(pts
						(arc
							(start -0.1778 0.5715)
							(mid -0.321484 0.511984)
							(end -0.381 0.3683)
						)
						(arc
							(start -0.381 -0.3683)
							(mid -0.321484 -0.511984)
							(end -0.1778 -0.5715)
						)
						(arc
							(start 0.1778 -0.5715)
							(mid 0.321484 -0.511984)
							(end 0.381 -0.3683)
						)
						(arc
							(start 0.381 0.3683)
							(mid 0.321484 0.511984)
							(end 0.1778 0.5715)
						)
					)
					(width 0)
					(fill yes)
				)
			)
		)
	)
	(footprint ""
		(layer "F.Cu")
		(at 24.257 -462.661 -90)
		(property "Reference" "R9902"
			(at 0 0 270)
			(layer "F.SilkS")
			(hide yes)
			(effects
				(font
					(size 1.27 1.27)
				)
			)
		)
		(property "Value" "1K82R2F-1-GP"
			(at 0.064008 -3.993896 270)
			(unlocked yes)
			(layer "F.Fab")
			(hide yes)
			(effects
				(font
					(size 1.016 1.016)
					(thickness 0.1524)
				)
			)
		)
		(property "Device Type" "R402H16"
			(at 0.064008 -5.517896 270)
			(unlocked yes)
			(layer "F.Fab")
			(hide yes)
			(effects
				(font
					(size 1.016 1.016)
					(thickness 0.1524)
				)
			)
		)
		(duplicate_pad_numbers_are_jumpers no)
		(fp_line
			(start -0.508 -0.9398)
			(end -0.508 0.9398)
			(stroke
				(width 0.1524)
				(type default)
			)
			(layer "F.SilkS")
		)
		(fp_line
			(start 0.508 -0.9398)
			(end -0.508 -0.9398)
			(stroke
				(width 0.1524)
				(type default)
			)
			(layer "F.SilkS")
		)
		(fp_rect
			(start -0.508 0.9398)
			(end 0.508 -0.9398)
			(stroke
				(width 0)
				(type default)
			)
			(fill no)
			(layer "F.CrtYd")
		)
		(fp_rect
			(start -0.508 0.9398)
			(end 0.508 -0.9398)
			(stroke
				(width 0)
				(type default)
			)
			(fill no)
			(layer "F.Fab")
		)
		(pad "1" smd custom
			(at 0 -0.4445 270)
			(size 0.1397 0.1397)
			(layers "F.Cu" "F.Mask" "F.Paste")
			(net "P12V")
			(options
				(clearance outline)
				(anchor circle)
			)
			(primitives
				(gr_poly
					(pts
						(arc
							(start -0.1778 -0.2794)
							(mid -0.249642 -0.249642)
							(end -0.2794 -0.1778)
						)
						(arc
							(start -0.2794 0.1778)
							(mid -0.249642 0.249642)
							(end -0.1778 0.2794)
						)
						(arc
							(start 0.1778 0.2794)
							(mid 0.249642 0.249642)
							(end 0.2794 0.1778)
						)
						(arc
							(start 0.2794 -0.1778)
							(mid 0.249642 -0.249642)
							(end 0.1778 -0.2794)
						)
					)
					(width 0)
					(fill yes)
				)
			)
		)
		(pad "2" smd custom
			(at 0 0.4445 270)
			(size 0.1397 0.1397)
			(layers "F.Cu" "F.Mask" "F.Paste")
			(net "DRV_ACT_10")
			(options
				(clearance outline)
				(anchor circle)
			)
			(primitives
				(gr_poly
					(pts
						(arc
							(start -0.1778 -0.2794)
							(mid -0.249642 -0.249642)
							(end -0.2794 -0.1778)
						)
						(arc
							(start -0.2794 0.1778)
							(mid -0.249642 0.249642)
							(end -0.1778 0.2794)
						)
						(arc
							(start 0.1778 0.2794)
							(mid 0.249642 0.249642)
							(end 0.2794 0.1778)
						)
						(arc
							(start 0.2794 -0.1778)
							(mid 0.249642 -0.249642)
							(end 0.1778 -0.2794)
						)
					)
					(width 0)
					(fill yes)
				)
			)
		)
	)
	(footprint ""
		(layer "F.Cu")
		(at 210.947 -94.9706 -90)
		(property "Reference" "Q47"
			(at 0 0 270)
			(layer "F.SilkS")
			(hide yes)
			(effects
				(font
					(size 1.27 1.27)
				)
			)
		)
		(property "Value" "2N7002A-7-GP"
			(at 0.127 -8.9662 270)
			(unlocked yes)
			(layer "F.Fab")
			(hide yes)
			(effects
				(font
					(size 1.016 1.016)
					(thickness 0.1524)
				)
			)
		)
		(property "Device Type" "SOT23DGS2D4H48"
			(at 0.127 -10.4902 270)
			(unlocked yes)
			(layer "F.Fab")
			(hide yes)
			(effects
				(font
					(size 1.016 1.016)
					(thickness 0.1524)
				)
			)
		)
		(duplicate_pad_numbers_are_jumpers no)
		(fp_line
			(start -1.651 1.778)
			(end 1.651 1.778)
			(stroke
				(width 0.1524)
				(type default)
			)
			(layer "F.SilkS")
		)
		(fp_line
			(start 1.651 1.778)
			(end 1.651 -1.778)
			(stroke
				(width 0.1524)
				(type default)
			)
			(layer "F.SilkS")
		)
		(fp_line
			(start -1.651 -1.778)
			(end -1.651 1.778)
			(stroke
				(width 0.1524)
				(type default)
			)
			(layer "F.SilkS")
		)
		(fp_line
			(start 1.651 -1.778)
			(end -1.651 -1.778)
			(stroke
				(width 0.1524)
				(type default)
			)
			(layer "F.SilkS")
		)
		(fp_poly
			(pts
				(xy -1.778 1.8796) (xy -1.778 -1.8796) (xy 1.778 -1.8796) (xy 1.778 1.8796)
			)
			(stroke
				(width 0)
				(type default)
			)
			(fill no)
			(layer "F.CrtYd")
		)
		(fp_poly
			(pts
				(xy -1.778 1.8796) (xy -1.778 -1.8796) (xy 1.778 -1.8796) (xy 1.778 1.8796)
			)
			(stroke
				(width 0)
				(type default)
			)
			(fill no)
			(layer "F.Fab")
		)
		(pad "D" smd custom
			(at 0 -0.9525 270)
			(size 0.1905 0.1905)
			(layers "F.Cu" "F.Mask" "F.Paste")
			(net "P12V_MOST4_GATE")
			(options
				(clearance outline)
				(anchor circle)
			)
			(primitives
				(gr_poly
					(pts
						(arc
							(start -0.1778 0.5715)
							(mid -0.321484 0.511984)
							(end -0.381 0.3683)
						)
						(arc
							(start -0.381 -0.3683)
							(mid -0.321484 -0.511984)
							(end -0.1778 -0.5715)
						)
						(arc
							(start 0.1778 -0.5715)
							(mid 0.321484 -0.511984)
							(end 0.381 -0.3683)
						)
						(arc
							(start 0.381 0.3683)
							(mid 0.321484 0.511984)
							(end 0.1778 0.5715)
						)
					)
					(width 0)
					(fill yes)
				)
			)
		)
		(pad "G" smd custom
			(at -0.98425 0.9525 270)
			(size 0.1905 0.1905)
			(layers "F.Cu" "F.Mask" "F.Paste")
			(net "SSD4_PWREN_R")
			(options
				(clearance outline)
				(anchor circle)
			)
			(primitives
				(gr_poly
					(pts
						(arc
							(start -0.1778 0.5715)
							(mid -0.321484 0.511984)
							(end -0.381 0.3683)
						)
						(arc
							(start -0.381 -0.3683)
							(mid -0.321484 -0.511984)
							(end -0.1778 -0.5715)
						)
						(arc
							(start 0.1778 -0.5715)
							(mid 0.321484 -0.511984)
							(end 0.381 -0.3683)
						)
						(arc
							(start 0.381 0.3683)
							(mid 0.321484 0.511984)
							(end 0.1778 0.5715)
						)
					)
					(width 0)
					(fill yes)
				)
			)
		)
		(pad "S" smd custom
			(at 0.98425 0.9525 270)
			(size 0.1905 0.1905)
			(layers "F.Cu" "F.Mask" "F.Paste")
			(net "GND")
			(options
				(clearance outline)
				(anchor circle)
			)
			(primitives
				(gr_poly
					(pts
						(arc
							(start -0.1778 0.5715)
							(mid -0.321484 0.511984)
							(end -0.381 0.3683)
						)
						(arc
							(start -0.381 -0.3683)
							(mid -0.321484 -0.511984)
							(end -0.1778 -0.5715)
						)
						(arc
							(start 0.1778 -0.5715)
							(mid 0.321484 -0.511984)
							(end 0.381 -0.3683)
						)
						(arc
							(start 0.381 0.3683)
							(mid 0.321484 0.511984)
							(end 0.1778 0.5715)
						)
					)
					(width 0)
					(fill yes)
				)
			)
		)
	)
	(footprint ""
		(layer "F.Cu")
		(at 82.931 -308.483 -90)
		(property "Reference" "PR9062"
			(at 0 0 270)
			(layer "F.SilkS")
			(hide yes)
			(effects
				(font
					(size 1.27 1.27)
				)
			)
		)
		(property "Value" "1K4R2F-1-GP"
			(at 0.064008 -3.993896 270)
			(unlocked yes)
			(layer "F.Fab")
			(hide yes)
			(effects
				(font
					(size 1.016 1.016)
					(thickness 0.1524)
				)
			)
		)
		(property "Device Type" "R402H16"
			(at 0.064008 -5.517896 270)
			(unlocked yes)
			(layer "F.Fab")
			(hide yes)
			(effects
				(font
					(size 1.016 1.016)
					(thickness 0.1524)
				)
			)
		)
		(duplicate_pad_numbers_are_jumpers no)
		(fp_line
			(start -0.508 -0.9398)
			(end -0.508 0.9398)
			(stroke
				(width 0.1524)
				(type default)
			)
			(layer "F.SilkS")
		)
		(fp_line
			(start 0.508 -0.9398)
			(end -0.508 -0.9398)
			(stroke
				(width 0.1524)
				(type default)
			)
			(layer "F.SilkS")
		)
		(fp_rect
			(start -0.508 0.9398)
			(end 0.508 -0.9398)
			(stroke
				(width 0)
				(type default)
			)
			(fill no)
			(layer "F.CrtYd")
		)
		(fp_rect
			(start -0.508 0.9398)
			(end 0.508 -0.9398)
			(stroke
				(width 0)
				(type default)
			)
			(fill no)
			(layer "F.Fab")
		)
		(pad "1" smd custom
			(at 0 -0.4445 270)
			(size 0.1397 0.1397)
			(layers "F.Cu" "F.Mask" "F.Paste")
			(net "CLK_BUF_EU2_HIBW_BYPM_LOBW#")
			(options
				(clearance outline)
				(anchor circle)
			)
			(primitives
				(gr_poly
					(pts
						(arc
							(start -0.1778 -0.2794)
							(mid -0.249642 -0.249642)
							(end -0.2794 -0.1778)
						)
						(arc
							(start -0.2794 0.1778)
							(mid -0.249642 0.249642)
							(end -0.1778 0.2794)
						)
						(arc
							(start 0.1778 0.2794)
							(mid 0.249642 0.249642)
							(end 0.2794 0.1778)
						)
						(arc
							(start 0.2794 -0.1778)
							(mid 0.249642 -0.249642)
							(end 0.1778 -0.2794)
						)
					)
					(width 0)
					(fill yes)
				)
			)
		)
		(pad "2" smd custom
			(at 0 0.4445 270)
			(size 0.1397 0.1397)
			(layers "F.Cu" "F.Mask" "F.Paste")
			(net "GND")
			(options
				(clearance outline)
				(anchor circle)
			)
			(primitives
				(gr_poly
					(pts
						(arc
							(start -0.1778 -0.2794)
							(mid -0.249642 -0.249642)
							(end -0.2794 -0.1778)
						)
						(arc
							(start -0.2794 0.1778)
							(mid -0.249642 0.249642)
							(end -0.1778 0.2794)
						)
						(arc
							(start 0.1778 0.2794)
							(mid 0.249642 0.249642)
							(end 0.2794 0.1778)
						)
						(arc
							(start 0.2794 -0.1778)
							(mid 0.249642 -0.249642)
							(end 0.1778 -0.2794)
						)
					)
					(width 0)
					(fill yes)
				)
			)
		)
	)
	(footprint ""
		(layer "F.Cu")
		(at 94.488 -109.474 180)
		(property "Reference" "C8873"
			(at 0 0 180)
			(layer "F.SilkS")
			(hide yes)
			(effects
				(font
					(size 1.27 1.27)
				)
			)
		)
		(property "Value" "SCD1U16V2KX-3GP"
			(at 1.1811 -2.7051 180)
			(unlocked yes)
			(layer "F.Fab")
			(hide yes)
			(effects
				(font
					(size 1.016 1.016)
					(thickness 0.1524)
				)
			)
		)
		(property "Device Type" "C402H22"
			(at 1.1811 -4.2291 180)
			(unlocked yes)
			(layer "F.Fab")
			(hide yes)
			(effects
				(font
					(size 1.016 1.016)
					(thickness 0.1524)
				)
			)
		)
		(duplicate_pad_numbers_are_jumpers no)
		(fp_rect
			(start -0.4318 0.9525)
			(end 0.4318 -0.9525)
			(stroke
				(width 0)
				(type default)
			)
			(fill no)
			(layer "F.CrtYd")
		)
		(fp_rect
			(start -0.4318 0.9525)
			(end 0.4318 -0.9525)
			(stroke
				(width 0)
				(type default)
			)
			(fill no)
			(layer "F.Fab")
		)
		(pad "1" smd custom
			(at 0 -0.4445 180)
			(size 0.1524 0.1524)
			(layers "F.Cu" "F.Mask" "F.Paste")
			(net "VDD_IO_4")
			(options
				(clearance outline)
				(anchor circle)
			)
			(primitives
				(gr_poly
					(pts
						(arc
							(start 0.3048 -0.2032)
							(mid 0.275042 -0.275042)
							(end 0.2032 -0.3048)
						)
						(arc
							(start -0.2032 -0.3048)
							(mid -0.275042 -0.275042)
							(end -0.3048 -0.2032)
						)
						(arc
							(start -0.3048 0.2032)
							(mid -0.275042 0.275042)
							(end -0.2032 0.3048)
						)
						(arc
							(start 0.2032 0.3048)
							(mid 0.275042 0.275042)
							(end 0.3048 0.2032)
						)
					)
					(width 0)
					(fill yes)
				)
			)
		)
		(pad "2" smd custom
			(at 0 0.4445 180)
			(size 0.1524 0.1524)
			(layers "F.Cu" "F.Mask" "F.Paste")
			(net "GND")
			(options
				(clearance outline)
				(anchor circle)
			)
			(primitives
				(gr_poly
					(pts
						(arc
							(start 0.3048 -0.2032)
							(mid 0.275042 -0.275042)
							(end 0.2032 -0.3048)
						)
						(arc
							(start -0.2032 -0.3048)
							(mid -0.275042 -0.275042)
							(end -0.3048 -0.2032)
						)
						(arc
							(start -0.3048 0.2032)
							(mid -0.275042 0.275042)
							(end -0.2032 0.3048)
						)
						(arc
							(start 0.2032 0.3048)
							(mid 0.275042 0.275042)
							(end 0.3048 0.2032)
						)
					)
					(width 0)
					(fill yes)
				)
			)
		)
	)
	(footprint ""
		(layer "F.Cu")
		(at 107.442 -309.88 -90)
		(property "Reference" "R9494"
			(at 0 0 270)
			(layer "F.SilkS")
			(hide yes)
			(effects
				(font
					(size 1.27 1.27)
				)
			)
		)
		(property "Value" "10R2F-L-GP"
			(at 0.064008 -3.993896 270)
			(unlocked yes)
			(layer "F.Fab")
			(hide yes)
			(effects
				(font
					(size 1.016 1.016)
					(thickness 0.1524)
				)
			)
		)
		(property "Device Type" "R402H14"
			(at 0.064008 -5.517896 270)
			(unlocked yes)
			(layer "F.Fab")
			(hide yes)
			(effects
				(font
					(size 1.016 1.016)
					(thickness 0.1524)
				)
			)
		)
		(duplicate_pad_numbers_are_jumpers no)
		(fp_line
			(start -0.508 -0.9398)
			(end -0.508 0.9398)
			(stroke
				(width 0.1524)
				(type default)
			)
			(layer "F.SilkS")
		)
		(fp_line
			(start 0.508 -0.9398)
			(end -0.508 -0.9398)
			(stroke
				(width 0.1524)
				(type default)
			)
			(layer "F.SilkS")
		)
		(fp_rect
			(start -0.508 0.9398)
			(end 0.508 -0.9398)
			(stroke
				(width 0)
				(type default)
			)
			(fill no)
			(layer "F.CrtYd")
		)
		(fp_rect
			(start -0.508 0.9398)
			(end 0.508 -0.9398)
			(stroke
				(width 0)
				(type default)
			)
			(fill no)
			(layer "F.Fab")
		)
		(pad "1" smd custom
			(at 0 -0.4445 270)
			(size 0.1397 0.1397)
			(layers "F.Cu" "F.Mask" "F.Paste")
			(net "SSD1_CLK0_OE_N")
			(options
				(clearance outline)
				(anchor circle)
			)
			(primitives
				(gr_poly
					(pts
						(arc
							(start -0.1778 -0.2794)
							(mid -0.249642 -0.249642)
							(end -0.2794 -0.1778)
						)
						(arc
							(start -0.2794 0.1778)
							(mid -0.249642 0.249642)
							(end -0.1778 0.2794)
						)
						(arc
							(start 0.1778 0.2794)
							(mid 0.249642 0.249642)
							(end 0.2794 0.1778)
						)
						(arc
							(start 0.2794 -0.1778)
							(mid 0.249642 -0.249642)
							(end 0.1778 -0.2794)
						)
					)
					(width 0)
					(fill yes)
				)
			)
		)
		(pad "2" smd custom
			(at 0 0.4445 270)
			(size 0.1397 0.1397)
			(layers "F.Cu" "F.Mask" "F.Paste")
			(net "SSD1_CLK0_OE_R_N")
			(options
				(clearance outline)
				(anchor circle)
			)
			(primitives
				(gr_poly
					(pts
						(arc
							(start -0.1778 -0.2794)
							(mid -0.249642 -0.249642)
							(end -0.2794 -0.1778)
						)
						(arc
							(start -0.2794 0.1778)
							(mid -0.249642 0.249642)
							(end -0.1778 0.2794)
						)
						(arc
							(start 0.1778 0.2794)
							(mid 0.249642 0.249642)
							(end 0.2794 0.1778)
						)
						(arc
							(start 0.2794 -0.1778)
							(mid 0.249642 -0.249642)
							(end 0.1778 -0.2794)
						)
					)
					(width 0)
					(fill yes)
				)
			)
		)
	)
	(footprint ""
		(layer "F.Cu")
		(at 221.0054 -198.6026 -90)
		(property "Reference" "R9798"
			(at 0 0 270)
			(layer "F.SilkS")
			(hide yes)
			(effects
				(font
					(size 1.27 1.27)
				)
			)
		)
		(property "Value" "2K2R5F-GP"
			(at 0 -8.9535 270)
			(unlocked yes)
			(layer "F.Fab")
			(hide yes)
			(effects
				(font
					(size 1.27 1.016)
					(thickness 0.1524)
				)
			)
		)
		(property "Device Type" "R805H24"
			(at 0 -10.6299 270)
			(unlocked yes)
			(layer "F.Fab")
			(hide yes)
			(effects
				(font
					(size 1.27 1.016)
					(thickness 0.1524)
				)
			)
		)
		(duplicate_pad_numbers_are_jumpers no)
		(fp_line
			(start -0.889 1.7018)
			(end 0.889 1.7018)
			(stroke
				(width 0.1524)
				(type default)
			)
			(layer "F.SilkS")
		)
		(fp_line
			(start 0.889 1.7018)
			(end 0.889 -0.508)
			(stroke
				(width 0.1524)
				(type default)
			)
			(layer "F.SilkS")
		)
		(fp_line
			(start -0.889 0.0762)
			(end -0.889 1.7018)
			(stroke
				(width 0.1524)
				(type default)
			)
			(layer "F.SilkS")
		)
		(fp_line
			(start -0.889 -1.7018)
			(end -0.889 0.2794)
			(stroke
				(width 0.1524)
				(type default)
			)
			(layer "F.SilkS")
		)
		(fp_line
			(start 0.889 -1.7018)
			(end 0.889 -0.381)
			(stroke
				(width 0.1524)
				(type default)
			)
			(layer "F.SilkS")
		)
		(fp_line
			(start 0.889 -1.7018)
			(end -0.889 -1.7018)
			(stroke
				(width 0.1524)
				(type default)
			)
			(layer "F.SilkS")
		)
		(fp_poly
			(pts
				(xy 0.9652 -1.778) (xy 0.9652 1.778) (xy -0.9652 1.778) (xy -0.9652 -1.778)
			)
			(stroke
				(width 0)
				(type default)
			)
			(fill no)
			(layer "F.CrtYd")
		)
		(fp_rect
			(start -0.9652 1.778)
			(end 0.9652 -1.778)
			(stroke
				(width 0)
				(type default)
			)
			(fill no)
			(layer "F.Fab")
		)
		(pad "1" smd rect
			(at 0 -0.9652 270)
			(size 1.397 1.143)
			(layers "F.Cu" "F.Mask" "F.Paste")
			(net "P12V_SSD3")
		)
		(pad "2" smd rect
			(at 0 0.9652 270)
			(size 1.397 1.143)
			(layers "F.Cu" "F.Mask" "F.Paste")
			(net "P12V_MOST3_GATE_D")
		)
	)
	(footprint ""
		(layer "F.Cu")
		(at 10.414 -269.875 180)
		(property "Reference" "R9038"
			(at 0 0 180)
			(layer "F.SilkS")
			(hide yes)
			(effects
				(font
					(size 1.27 1.27)
				)
			)
		)
		(property "Value" "0R2J-2-GP"
			(at 0.064008 -3.993896 180)
			(unlocked yes)
			(layer "F.Fab")
			(hide yes)
			(effects
				(font
					(size 1.016 1.016)
					(thickness 0.1524)
				)
			)
		)
		(property "Device Type" "R402H16"
			(at 0.064008 -5.517896 180)
			(unlocked yes)
			(layer "F.Fab")
			(hide yes)
			(effects
				(font
					(size 1.016 1.016)
					(thickness 0.1524)
				)
			)
		)
		(duplicate_pad_numbers_are_jumpers no)
		(fp_line
			(start 0.508 -0.9398)
			(end -0.508 -0.9398)
			(stroke
				(width 0.1524)
				(type default)
			)
			(layer "F.SilkS")
		)
		(fp_line
			(start -0.508 -0.9398)
			(end -0.508 0.9398)
			(stroke
				(width 0.1524)
				(type default)
			)
			(layer "F.SilkS")
		)
		(fp_rect
			(start -0.508 0.9398)
			(end 0.508 -0.9398)
			(stroke
				(width 0)
				(type default)
			)
			(fill no)
			(layer "F.CrtYd")
		)
		(fp_rect
			(start -0.508 0.9398)
			(end 0.508 -0.9398)
			(stroke
				(width 0)
				(type default)
			)
			(fill no)
			(layer "F.Fab")
		)
		(pad "1" smd custom
			(at 0 -0.4445 180)
			(size 0.1397 0.1397)
			(layers "F.Cu" "F.Mask" "F.Paste")
			(net "SD_LATCH_RELEASE_R")
			(options
				(clearance outline)
				(anchor circle)
			)
			(primitives
				(gr_poly
					(pts
						(arc
							(start -0.1778 -0.2794)
							(mid -0.249642 -0.249642)
							(end -0.2794 -0.1778)
						)
						(arc
							(start -0.2794 0.1778)
							(mid -0.249642 0.249642)
							(end -0.1778 0.2794)
						)
						(arc
							(start 0.1778 0.2794)
							(mid 0.249642 0.249642)
							(end 0.2794 0.1778)
						)
						(arc
							(start 0.2794 -0.1778)
							(mid 0.249642 -0.249642)
							(end 0.1778 -0.2794)
						)
					)
					(width 0)
					(fill yes)
				)
			)
		)
		(pad "2" smd custom
			(at 0 0.4445 180)
			(size 0.1397 0.1397)
			(layers "F.Cu" "F.Mask" "F.Paste")
			(net "SD_LATCH_RELEASE")
			(options
				(clearance outline)
				(anchor circle)
			)
			(primitives
				(gr_poly
					(pts
						(arc
							(start -0.1778 -0.2794)
							(mid -0.249642 -0.249642)
							(end -0.2794 -0.1778)
						)
						(arc
							(start -0.2794 0.1778)
							(mid -0.249642 0.249642)
							(end -0.1778 0.2794)
						)
						(arc
							(start 0.1778 0.2794)
							(mid 0.249642 0.249642)
							(end 0.2794 0.1778)
						)
						(arc
							(start 0.2794 -0.1778)
							(mid 0.249642 -0.249642)
							(end 0.1778 -0.2794)
						)
					)
					(width 0)
					(fill yes)
				)
			)
		)
	)
	(footprint ""
		(layer "F.Cu")
		(at 13.1064 -499.1862 -90)
		(property "Reference" "Q52"
			(at 0 0 270)
			(layer "F.SilkS")
			(hide yes)
			(effects
				(font
					(size 1.27 1.27)
				)
			)
		)
		(property "Value" "2N7002A-7-GP"
			(at 0.127 -8.9662 270)
			(unlocked yes)
			(layer "F.Fab")
			(hide yes)
			(effects
				(font
					(size 1.016 1.016)
					(thickness 0.1524)
				)
			)
		)
		(property "Device Type" "SOT23DGS2D4H48"
			(at 0.127 -10.4902 270)
			(unlocked yes)
			(layer "F.Fab")
			(hide yes)
			(effects
				(font
					(size 1.016 1.016)
					(thickness 0.1524)
				)
			)
		)
		(duplicate_pad_numbers_are_jumpers no)
		(fp_line
			(start -1.651 1.778)
			(end 1.651 1.778)
			(stroke
				(width 0.1524)
				(type default)
			)
			(layer "F.SilkS")
		)
		(fp_line
			(start 1.651 1.778)
			(end 1.651 -1.778)
			(stroke
				(width 0.1524)
				(type default)
			)
			(layer "F.SilkS")
		)
		(fp_line
			(start -1.651 -1.778)
			(end -1.651 1.778)
			(stroke
				(width 0.1524)
				(type default)
			)
			(layer "F.SilkS")
		)
		(fp_line
			(start 1.651 -1.778)
			(end -1.651 -1.778)
			(stroke
				(width 0.1524)
				(type default)
			)
			(layer "F.SilkS")
		)
		(fp_poly
			(pts
				(xy -1.778 1.8796) (xy -1.778 -1.8796) (xy 1.778 -1.8796) (xy 1.778 1.8796)
			)
			(stroke
				(width 0)
				(type default)
			)
			(fill no)
			(layer "F.CrtYd")
		)
		(fp_poly
			(pts
				(xy -1.778 1.8796) (xy -1.778 -1.8796) (xy 1.778 -1.8796) (xy 1.778 1.8796)
			)
			(stroke
				(width 0)
				(type default)
			)
			(fill no)
			(layer "F.Fab")
		)
		(pad "D" smd custom
			(at 0 -0.9525 270)
			(size 0.1905 0.1905)
			(layers "F.Cu" "F.Mask" "F.Paste")
			(net "P12V_MOST5_GATE")
			(options
				(clearance outline)
				(anchor circle)
			)
			(primitives
				(gr_poly
					(pts
						(arc
							(start -0.1778 0.5715)
							(mid -0.321484 0.511984)
							(end -0.381 0.3683)
						)
						(arc
							(start -0.381 -0.3683)
							(mid -0.321484 -0.511984)
							(end -0.1778 -0.5715)
						)
						(arc
							(start 0.1778 -0.5715)
							(mid 0.321484 -0.511984)
							(end 0.381 -0.3683)
						)
						(arc
							(start 0.381 0.3683)
							(mid 0.321484 0.511984)
							(end 0.1778 0.5715)
						)
					)
					(width 0)
					(fill yes)
				)
			)
		)
		(pad "G" smd custom
			(at -0.98425 0.9525 270)
			(size 0.1905 0.1905)
			(layers "F.Cu" "F.Mask" "F.Paste")
			(net "SSD5_PWREN_R")
			(options
				(clearance outline)
				(anchor circle)
			)
			(primitives
				(gr_poly
					(pts
						(arc
							(start -0.1778 0.5715)
							(mid -0.321484 0.511984)
							(end -0.381 0.3683)
						)
						(arc
							(start -0.381 -0.3683)
							(mid -0.321484 -0.511984)
							(end -0.1778 -0.5715)
						)
						(arc
							(start 0.1778 -0.5715)
							(mid 0.321484 -0.511984)
							(end 0.381 -0.3683)
						)
						(arc
							(start 0.381 0.3683)
							(mid 0.321484 0.511984)
							(end 0.1778 0.5715)
						)
					)
					(width 0)
					(fill yes)
				)
			)
		)
		(pad "S" smd custom
			(at 0.98425 0.9525 270)
			(size 0.1905 0.1905)
			(layers "F.Cu" "F.Mask" "F.Paste")
			(net "GND")
			(options
				(clearance outline)
				(anchor circle)
			)
			(primitives
				(gr_poly
					(pts
						(arc
							(start -0.1778 0.5715)
							(mid -0.321484 0.511984)
							(end -0.381 0.3683)
						)
						(arc
							(start -0.381 -0.3683)
							(mid -0.321484 -0.511984)
							(end -0.1778 -0.5715)
						)
						(arc
							(start 0.1778 -0.5715)
							(mid 0.321484 -0.511984)
							(end 0.381 -0.3683)
						)
						(arc
							(start 0.381 0.3683)
							(mid 0.321484 0.511984)
							(end 0.1778 0.5715)
						)
					)
					(width 0)
					(fill yes)
				)
			)
		)
	)
	(footprint ""
		(layer "F.Cu")
		(at 46.228 -242.443)
		(property "Reference" "C9525"
			(at 0 0 0)
			(layer "F.SilkS")
			(hide yes)
			(effects
				(font
					(size 1.27 1.27)
				)
			)
		)
		(property "Value" "SCD1U16V2KX-3GP"
			(at 1.1811 -2.7051 0)
			(unlocked yes)
			(layer "F.Fab")
			(hide yes)
			(effects
				(font
					(size 1.016 1.016)
					(thickness 0.1524)
				)
			)
		)
		(property "Device Type" "C402H22"
			(at 1.1811 -4.2291 0)
			(unlocked yes)
			(layer "F.Fab")
			(hide yes)
			(effects
				(font
					(size 1.016 1.016)
					(thickness 0.1524)
				)
			)
		)
		(duplicate_pad_numbers_are_jumpers no)
		(fp_rect
			(start -0.4318 0.9525)
			(end 0.4318 -0.9525)
			(stroke
				(width 0)
				(type default)
			)
			(fill no)
			(layer "F.CrtYd")
		)
		(fp_rect
			(start -0.4318 0.9525)
			(end 0.4318 -0.9525)
			(stroke
				(width 0)
				(type default)
			)
			(fill no)
			(layer "F.Fab")
		)
		(pad "1" smd custom
			(at 0 -0.4445)
			(size 0.1524 0.1524)
			(layers "F.Cu" "F.Mask" "F.Paste")
			(net "P3V3")
			(options
				(clearance outline)
				(anchor circle)
			)
			(primitives
				(gr_poly
					(pts
						(arc
							(start 0.3048 -0.2032)
							(mid 0.275042 -0.275042)
							(end 0.2032 -0.3048)
						)
						(arc
							(start -0.2032 -0.3048)
							(mid -0.275042 -0.275042)
							(end -0.3048 -0.2032)
						)
						(arc
							(start -0.3048 0.2032)
							(mid -0.275042 0.275042)
							(end -0.2032 0.3048)
						)
						(arc
							(start 0.2032 0.3048)
							(mid 0.275042 0.275042)
							(end 0.3048 0.2032)
						)
					)
					(width 0)
					(fill yes)
				)
			)
		)
		(pad "2" smd custom
			(at 0 0.4445)
			(size 0.1524 0.1524)
			(layers "F.Cu" "F.Mask" "F.Paste")
			(net "GND")
			(options
				(clearance outline)
				(anchor circle)
			)
			(primitives
				(gr_poly
					(pts
						(arc
							(start 0.3048 -0.2032)
							(mid 0.275042 -0.275042)
							(end 0.2032 -0.3048)
						)
						(arc
							(start -0.2032 -0.3048)
							(mid -0.275042 -0.275042)
							(end -0.3048 -0.2032)
						)
						(arc
							(start -0.3048 0.2032)
							(mid -0.275042 0.275042)
							(end -0.2032 0.3048)
						)
						(arc
							(start 0.2032 0.3048)
							(mid 0.275042 0.275042)
							(end 0.3048 0.2032)
						)
					)
					(width 0)
					(fill yes)
				)
			)
		)
	)
	(footprint ""
		(layer "F.Cu")
		(at 49.276 -248.539 -90)
		(property "Reference" "R9463"
			(at 0 0 270)
			(layer "F.SilkS")
			(hide yes)
			(effects
				(font
					(size 1.27 1.27)
				)
			)
		)
		(property "Value" "330R2F-GP"
			(at 0.064008 -3.993896 270)
			(unlocked yes)
			(layer "F.Fab")
			(hide yes)
			(effects
				(font
					(size 1.016 1.016)
					(thickness 0.1524)
				)
			)
		)
		(property "Device Type" "R402H16"
			(at 0.064008 -5.517896 270)
			(unlocked yes)
			(layer "F.Fab")
			(hide yes)
			(effects
				(font
					(size 1.016 1.016)
					(thickness 0.1524)
				)
			)
		)
		(duplicate_pad_numbers_are_jumpers no)
		(fp_line
			(start -0.508 -0.9398)
			(end -0.508 0.9398)
			(stroke
				(width 0.1524)
				(type default)
			)
			(layer "F.SilkS")
		)
		(fp_line
			(start 0.508 -0.9398)
			(end -0.508 -0.9398)
			(stroke
				(width 0.1524)
				(type default)
			)
			(layer "F.SilkS")
		)
		(fp_rect
			(start -0.508 0.9398)
			(end 0.508 -0.9398)
			(stroke
				(width 0)
				(type default)
			)
			(fill no)
			(layer "F.CrtYd")
		)
		(fp_rect
			(start -0.508 0.9398)
			(end 0.508 -0.9398)
			(stroke
				(width 0)
				(type default)
			)
			(fill no)
			(layer "F.Fab")
		)
		(pad "1" smd custom
			(at 0 -0.4445 270)
			(size 0.1397 0.1397)
			(layers "F.Cu" "F.Mask" "F.Paste")
			(net "P3V3")
			(options
				(clearance outline)
				(anchor circle)
			)
			(primitives
				(gr_poly
					(pts
						(arc
							(start -0.1778 -0.2794)
							(mid -0.249642 -0.249642)
							(end -0.2794 -0.1778)
						)
						(arc
							(start -0.2794 0.1778)
							(mid -0.249642 0.249642)
							(end -0.1778 0.2794)
						)
						(arc
							(start 0.1778 0.2794)
							(mid 0.249642 0.249642)
							(end 0.2794 0.1778)
						)
						(arc
							(start 0.2794 -0.1778)
							(mid 0.249642 -0.249642)
							(end 0.1778 -0.2794)
						)
					)
					(width 0)
					(fill yes)
				)
			)
		)
		(pad "2" smd custom
			(at 0 0.4445 270)
			(size 0.1397 0.1397)
			(layers "F.Cu" "F.Mask" "F.Paste")
			(net "DRV_ATTN_7")
			(options
				(clearance outline)
				(anchor circle)
			)
			(primitives
				(gr_poly
					(pts
						(arc
							(start -0.1778 -0.2794)
							(mid -0.249642 -0.249642)
							(end -0.2794 -0.1778)
						)
						(arc
							(start -0.2794 0.1778)
							(mid -0.249642 0.249642)
							(end -0.1778 0.2794)
						)
						(arc
							(start 0.1778 0.2794)
							(mid 0.249642 0.249642)
							(end 0.2794 0.1778)
						)
						(arc
							(start 0.2794 -0.1778)
							(mid 0.249642 -0.249642)
							(end 0.1778 -0.2794)
						)
					)
					(width 0)
					(fill yes)
				)
			)
		)
	)
	(footprint ""
		(layer "F.Cu")
		(at 108.966 -205.994)
		(property "Reference" "R9444"
			(at 0 0 0)
			(layer "F.SilkS")
			(hide yes)
			(effects
				(font
					(size 1.27 1.27)
				)
			)
		)
		(property "Value" "4K7R2J-2-GP"
			(at 0.064008 -3.993896 0)
			(unlocked yes)
			(layer "F.Fab")
			(hide yes)
			(effects
				(font
					(size 1.016 1.016)
					(thickness 0.1524)
				)
			)
		)
		(property "Device Type" "R402H16"
			(at 0.064008 -5.517896 0)
			(unlocked yes)
			(layer "F.Fab")
			(hide yes)
			(effects
				(font
					(size 1.016 1.016)
					(thickness 0.1524)
				)
			)
		)
		(duplicate_pad_numbers_are_jumpers no)
		(fp_line
			(start -0.508 -0.9398)
			(end -0.508 0.9398)
			(stroke
				(width 0.1524)
				(type default)
			)
			(layer "F.SilkS")
		)
		(fp_line
			(start 0.508 -0.9398)
			(end -0.508 -0.9398)
			(stroke
				(width 0.1524)
				(type default)
			)
			(layer "F.SilkS")
		)
		(fp_rect
			(start -0.508 0.9398)
			(end 0.508 -0.9398)
			(stroke
				(width 0)
				(type default)
			)
			(fill no)
			(layer "F.CrtYd")
		)
		(fp_rect
			(start -0.508 0.9398)
			(end 0.508 -0.9398)
			(stroke
				(width 0)
				(type default)
			)
			(fill no)
			(layer "F.Fab")
		)
		(pad "1" smd custom
			(at 0 -0.4445)
			(size 0.1397 0.1397)
			(layers "F.Cu" "F.Mask" "F.Paste")
			(net "P3V3")
			(options
				(clearance outline)
				(anchor circle)
			)
			(primitives
				(gr_poly
					(pts
						(arc
							(start -0.1778 -0.2794)
							(mid -0.249642 -0.249642)
							(end -0.2794 -0.1778)
						)
						(arc
							(start -0.2794 0.1778)
							(mid -0.249642 0.249642)
							(end -0.1778 0.2794)
						)
						(arc
							(start 0.1778 0.2794)
							(mid 0.249642 0.249642)
							(end 0.2794 0.1778)
						)
						(arc
							(start 0.2794 -0.1778)
							(mid 0.249642 -0.249642)
							(end 0.1778 -0.2794)
						)
					)
					(width 0)
					(fill yes)
				)
			)
		)
		(pad "2" smd custom
			(at 0 0.4445)
			(size 0.1397 0.1397)
			(layers "F.Cu" "F.Mask" "F.Paste")
			(net "SSD_PRSNT_NET3")
			(options
				(clearance outline)
				(anchor circle)
			)
			(primitives
				(gr_poly
					(pts
						(arc
							(start -0.1778 -0.2794)
							(mid -0.249642 -0.249642)
							(end -0.2794 -0.1778)
						)
						(arc
							(start -0.2794 0.1778)
							(mid -0.249642 0.249642)
							(end -0.1778 0.2794)
						)
						(arc
							(start 0.1778 0.2794)
							(mid 0.249642 0.249642)
							(end 0.2794 0.1778)
						)
						(arc
							(start 0.2794 -0.1778)
							(mid 0.249642 -0.249642)
							(end 0.1778 -0.2794)
						)
					)
					(width 0)
					(fill yes)
				)
			)
		)
	)
	(footprint ""
		(layer "F.Cu")
		(at 44.577 -13.081 90)
		(property "Reference" "U23"
			(at 0 0 90)
			(layer "F.SilkS")
			(hide yes)
			(effects
				(font
					(size 1.27 1.27)
				)
			)
		)
		(property "Value" "P2003EVG-GP"
			(at 0 -11.1252 90)
			(unlocked yes)
			(layer "F.Fab")
			(hide yes)
			(effects
				(font
					(size 1.016 1.016)
					(thickness 0.1524)
				)
			)
		)
		(property "Device Type" "SOIC8H79"
			(at 0 -12.6492 90)
			(unlocked yes)
			(layer "F.Fab")
			(hide yes)
			(effects
				(font
					(size 1.016 1.016)
					(thickness 0.1524)
				)
			)
		)
		(duplicate_pad_numbers_are_jumpers no)
		(fp_line
			(start 2.1336 -1.4224)
			(end -2.7432 -1.4224)
			(stroke
				(width 0.1524)
				(type default)
			)
			(layer "F.SilkS")
		)
		(fp_line
			(start -2.7432 -1.4224)
			(end -2.7432 1.4224)
			(stroke
				(width 0.1524)
				(type default)
			)
			(layer "F.SilkS")
		)
		(fp_line
			(start -2.7432 -0.508)
			(end -2.2352 0)
			(stroke
				(width 0.1524)
				(type default)
			)
			(layer "F.SilkS")
		)
		(fp_line
			(start -2.2352 0)
			(end -2.7432 0.508)
			(stroke
				(width 0.1524)
				(type default)
			)
			(layer "F.SilkS")
		)
		(fp_line
			(start 2.1336 1.4224)
			(end 2.1336 -1.4224)
			(stroke
				(width 0.1524)
				(type default)
			)
			(layer "F.SilkS")
		)
		(fp_line
			(start -2.7432 1.4224)
			(end 2.1336 1.4224)
			(stroke
				(width 0.1524)
				(type default)
			)
			(layer "F.SilkS")
		)
		(fp_line
			(start -2.6162 3.429)
			(end -2.6162 1.4732)
			(stroke
				(width 0.4064)
				(type default)
			)
			(layer "F.SilkS")
		)
		(fp_poly
			(pts
				(xy 2.2098 -1.4224) (xy 2.2098 1.4224) (xy -2.2225 1.4224) (xy -2.2225 -1.4224)
			)
			(stroke
				(width 0)
				(type default)
			)
			(fill yes)
			(layer "F.SilkS")
		)
		(fp_rect
			(start -2.4511 2.9972)
			(end 2.4511 -2.9972)
			(stroke
				(width 0)
				(type default)
			)
			(fill no)
			(layer "F.CrtYd")
		)
		(fp_poly
			(pts
				(xy -2.8194 3.6322) (xy -2.8194 -3.6322) (xy 2.8194 -3.6322) (xy 2.8194 -2.2987) (xy 2.4511 -2.2987)
				(xy 2.4511 -2.9972) (xy -2.4511 -2.9972) (xy -2.4511 2.9972) (xy 2.4511 2.9972) (xy 2.4511 -2.286)
				(xy 2.8194 -2.286) (xy 2.8194 3.6322)
			)
			(stroke
				(width 0)
				(type default)
			)
			(fill no)
			(layer "F.CrtYd")
		)
		(fp_rect
			(start -2.8194 3.6322)
			(end 2.8194 -3.6322)
			(stroke
				(width 0)
				(type default)
			)
			(fill no)
			(layer "F.Fab")
		)
		(pad "1" smd rect
			(at -1.905 2.54 90)
			(size 0.635 1.651)
			(layers "F.Cu" "F.Mask" "F.Paste")
			(net "P12V")
		)
		(pad "2" smd rect
			(at -0.635 2.54 90)
			(size 0.635 1.651)
			(layers "F.Cu" "F.Mask" "F.Paste")
			(net "P12V")
		)
		(pad "3" smd rect
			(at 0.635 2.54 90)
			(size 0.635 1.651)
			(layers "F.Cu" "F.Mask" "F.Paste")
			(net "P12V")
		)
		(pad "4" smd rect
			(at 1.905 2.54 90)
			(size 0.635 1.651)
			(layers "F.Cu" "F.Mask" "F.Paste")
			(net "SW_SSD14_N")
		)
		(pad "5" smd rect
			(at 1.905 -2.54 90)
			(size 0.635 1.651)
			(layers "F.Cu" "F.Mask" "F.Paste")
			(net "P12V_SSD14")
		)
		(pad "6" smd rect
			(at 0.635 -2.54 90)
			(size 0.635 1.651)
			(layers "F.Cu" "F.Mask" "F.Paste")
			(net "P12V_SSD14")
		)
		(pad "7" smd rect
			(at -0.635 -2.54 90)
			(size 0.635 1.651)
			(layers "F.Cu" "F.Mask" "F.Paste")
			(net "P12V_SSD14")
		)
		(pad "8" smd rect
			(at -1.905 -2.54 90)
			(size 0.635 1.651)
			(layers "F.Cu" "F.Mask" "F.Paste")
			(net "P12V_SSD14")
		)
	)
	(footprint ""
		(layer "F.Cu")
		(at 2.999994 -425.141898 90)
		(property "Reference" "J17"
			(at 0 0 90)
			(layer "F.SilkS")
			(hide yes)
			(effects
				(font
					(size 1.27 1.27)
				)
			)
		)
		(property "Value" "PCISLT200-5-GP-U"
			(at -48.7045 -6.7818 90)
			(unlocked yes)
			(layer "F.Fab")
			(hide yes)
			(effects
				(font
					(size 1.016 1.016)
					(thickness 0.1524)
				)
			)
		)
		(property "Device Type" "G639F200221431HR-U"
			(at -48.7045 -8.3058 90)
			(unlocked yes)
			(layer "F.Fab")
			(hide yes)
			(effects
				(font
					(size 1.016 1.016)
					(thickness 0.1524)
				)
			)
		)
		(duplicate_pad_numbers_are_jumpers no)
		(fp_line
			(start 51.7525 -2.999994)
			(end 51.7525 2.9464)
			(stroke
				(width 0.1524)
				(type default)
			)
			(layer "F.SilkS")
		)
		(fp_line
			(start -3.199892 -2.999994)
			(end 51.7525 -2.999994)
			(stroke
				(width 0.1524)
				(type default)
			)
			(layer "F.SilkS")
		)
		(fp_line
			(start -6.400038 -2.999994)
			(end -51.7525 -2.999994)
			(stroke
				(width 0.1524)
				(type default)
			)
			(layer "F.SilkS")
		)
		(fp_line
			(start -51.7525 -2.999994)
			(end -51.7525 2.9464)
			(stroke
				(width 0.1524)
				(type default)
			)
			(layer "F.SilkS")
		)
		(fp_line
			(start -3.700018 -2.499868)
			(end -3.199892 -2.999994)
			(stroke
				(width 0.1524)
				(type default)
			)
			(layer "F.SilkS")
		)
		(fp_line
			(start -5.899912 -2.499868)
			(end -6.400038 -2.999994)
			(stroke
				(width 0.1524)
				(type default)
			)
			(layer "F.SilkS")
		)
		(fp_line
			(start -3.700018 1.400048)
			(end -3.700018 -2.499868)
			(stroke
				(width 0.1524)
				(type default)
			)
			(layer "F.SilkS")
		)
		(fp_line
			(start -5.899912 1.400048)
			(end -5.899912 -2.499868)
			(stroke
				(width 0.1524)
				(type default)
			)
			(layer "F.SilkS")
		)
		(fp_line
			(start 51.7525 2.9464)
			(end -51.7525 2.9464)
			(stroke
				(width 0.1524)
				(type default)
			)
			(layer "F.SilkS")
		)
		(fp_arc
			(start -3.700018 1.400048)
			(mid -4.800092 2.500122)
			(end -5.900166 1.400048)
			(stroke
				(width 0.1524)
				(type default)
			)
			(layer "F.SilkS")
		)
		(fp_poly
			(pts
				(xy -51.4985 2.6924) (xy -51.4985 -5.3086) (xy -46.6979 -5.3086) (xy -46.6979 -18.796) (xy -41.6941 -18.796)
				(xy -41.6941 -10.795) (xy 41.6941 -10.795) (xy 41.6941 -18.796) (xy 46.6979 -18.796) (xy 46.6979 -5.3086)
				(xy 51.4985 -5.3086) (xy 51.4985 2.6924)
			)
			(stroke
				(width 0)
				(type default)
			)
			(fill no)
			(layer "B.CrtYd")
		)
		(fp_poly
			(pts
				(xy -52.0065 3.2004) (xy -52.0065 -5.8166) (xy -47.2059 -5.8166) (xy -47.2059 -19.304) (xy -41.1861 -19.304)
				(xy -41.1861 -11.303) (xy 41.1861 -11.303) (xy 41.1861 -19.304) (xy 47.2059 -19.304) (xy 47.2059 -5.8166)
				(xy 52.0065 -5.8166) (xy 52.0065 -0.00635) (xy 51.4985 -0.00635) (xy 51.4985 -5.3086) (xy 46.6979 -5.3086)
				(xy 46.6979 -18.796) (xy 41.6941 -18.796) (xy 41.6941 -10.795) (xy -41.6941 -10.795) (xy -41.6941 -18.796)
				(xy -46.6979 -18.796) (xy -46.6979 -5.3086) (xy -51.4985 -5.3086) (xy -51.4985 2.6924) (xy 51.4985 2.6924)
				(xy 51.4985 0.00635) (xy 52.0065 0.00635) (xy 52.0065 3.2004)
			)
			(stroke
				(width 0)
				(type default)
			)
			(fill no)
			(layer "B.CrtYd")
		)
		(fp_poly
			(pts
				(xy -51.4985 2.6924) (xy -51.4985 -5.3086) (xy -46.6979 -5.3086) (xy -46.6979 -18.796) (xy -41.6941 -18.796)
				(xy -41.6941 -10.795) (xy 41.6941 -10.795) (xy 41.6941 -18.796) (xy 46.6979 -18.796) (xy 46.6979 -5.3086)
				(xy 51.4985 -5.3086) (xy 51.4985 2.6924)
			)
			(stroke
				(width 0)
				(type default)
			)
			(fill no)
			(layer "F.CrtYd")
		)
		(fp_poly
			(pts
				(xy -52.0065 3.2004) (xy -52.0065 -5.8166) (xy -47.2059 -5.8166) (xy -47.2059 -19.304) (xy -41.1861 -19.304)
				(xy -41.1861 -11.303) (xy 41.1861 -11.303) (xy 41.1861 -19.304) (xy 47.2059 -19.304) (xy 47.2059 -5.8166)
				(xy 52.0065 -5.8166) (xy 52.0065 -0.00635) (xy 51.4985 -0.00635) (xy 51.4985 -5.3086) (xy 46.6979 -5.3086)
				(xy 46.6979 -18.796) (xy 41.6941 -18.796) (xy 41.6941 -10.795) (xy -41.6941 -10.795) (xy -41.6941 -18.796)
				(xy -46.6979 -18.796) (xy -46.6979 -5.3086) (xy -51.4985 -5.3086) (xy -51.4985 2.6924) (xy 51.4985 2.6924)
				(xy 51.4985 0.00635) (xy 52.0065 0.00635) (xy 52.0065 3.2004)
			)
			(stroke
				(width 0)
				(type default)
			)
			(fill no)
			(layer "F.CrtYd")
		)
		(fp_poly
			(pts
				(xy -52.0065 3.2004) (xy -52.0065 -5.8166) (xy -47.2059 -5.8166) (xy -47.2059 -19.304) (xy -41.1861 -19.304)
				(xy -41.1861 -11.303) (xy 41.1861 -11.303) (xy 41.1861 -19.304) (xy 47.2059 -19.304) (xy 47.2059 -5.8166)
				(xy 52.0065 -5.8166) (xy 52.0065 3.2004)
			)
			(stroke
				(width 0)
				(type default)
			)
			(fill no)
			(layer "B.Fab")
		)
		(fp_poly
			(pts
				(xy -52.0065 3.2004) (xy -52.0065 -5.8166) (xy -47.2059 -5.8166) (xy -47.2059 -19.304) (xy -41.1861 -19.304)
				(xy -41.1861 -11.303) (xy 41.1861 -11.303) (xy 41.1861 -19.304) (xy 47.2059 -19.304) (xy 47.2059 -5.8166)
				(xy 52.0065 -5.8166) (xy 52.0065 3.2004)
			)
			(stroke
				(width 0)
				(type default)
			)
			(fill no)
			(layer "F.Fab")
		)
		(fp_text user "Slit"
			(at 10.2108 -6.5786 90)
			(unlocked yes)
			(layer "F.SilkS")
			(effects
				(font
					(size 1.016 1.016)
					(thickness 0.1524)
				)
				(justify left)
			)
		)
		(pad "" np_thru_hole circle
			(at -47.999904 0 90)
			(size 0.254 0.254)
			(drill 2.2098)
			(layers "*.Cu" "*.Mask")
			(clearance 1.3335)
			(thermal_gap 1.3335)
		)
		(pad "" np_thru_hole circle
			(at 47.999904 0 90)
			(size 0.254 0.254)
			(drill 2.2098)
			(layers "*.Cu" "*.Mask")
			(clearance 1.3335)
			(thermal_gap 1.3335)
		)
		(pad "A1" smd rect
			(at -41.20007 -0.750062 90)
			(size 0.508 2.4892)
			(layers "F.Cu" "F.Mask" "F.Paste")
			(net "GND")
		)
		(pad "A2" smd rect
			(at -40.39997 -0.750062 90)
			(size 0.508 2.4892)
			(layers "F.Cu" "F.Mask" "F.Paste")
			(net "PE_100M_CLK1_C_N")
		)
		(pad "A3" smd rect
			(at -39.600124 -0.750062 90)
			(size 0.508 2.4892)
			(layers "F.Cu" "F.Mask" "F.Paste")
			(net "PE_100M_CLK1_C_P")
		)
		(pad "A4" smd rect
			(at -38.800024 -0.750062 90)
			(size 0.508 2.4892)
			(layers "F.Cu" "F.Mask" "F.Paste")
			(net "GND")
		)
		(pad "A5" smd rect
			(at -37.999924 -0.750062 90)
			(size 0.508 2.4892)
			(layers "F.Cu" "F.Mask" "F.Paste")
			(net "PE_TX1_DR1_N")
		)
		(pad "A6" smd rect
			(at -37.200078 -0.750062 90)
			(size 0.508 2.4892)
			(layers "F.Cu" "F.Mask" "F.Paste")
			(net "PE_TX1_DR1_P")
		)
		(pad "A7" smd rect
			(at -36.399978 -0.750062 90)
			(size 0.508 2.4892)
			(layers "F.Cu" "F.Mask" "F.Paste")
			(net "GND")
		)
		(pad "A8" smd rect
			(at -35.599878 -0.750062 90)
			(size 0.508 2.4892)
			(layers "F.Cu" "F.Mask" "F.Paste")
			(net "GND")
		)
		(pad "A9" smd rect
			(at -34.800032 -0.750062 90)
			(size 0.508 2.4892)
			(layers "F.Cu" "F.Mask" "F.Paste")
			(net "PE_TX2_DR1_N")
		)
		(pad "A10" smd rect
			(at -33.999932 -0.750062 90)
			(size 0.508 2.4892)
			(layers "F.Cu" "F.Mask" "F.Paste")
			(net "PE_TX2_DR1_P")
		)
		(pad "A11" smd rect
			(at -33.200086 -0.750062 90)
			(size 0.508 2.4892)
			(layers "F.Cu" "F.Mask" "F.Paste")
			(net "GND")
		)
		(pad "A12" smd rect
			(at -32.399986 -0.750062 90)
			(size 0.508 2.4892)
			(layers "F.Cu" "F.Mask" "F.Paste")
			(net "GND")
		)
		(pad "A13" smd rect
			(at -31.599886 -0.750062 90)
			(size 0.508 2.4892)
			(layers "F.Cu" "F.Mask" "F.Paste")
			(net "PE_TX3_DR1_N")
		)
		(pad "A14" smd rect
			(at -30.80004 -0.750062 90)
			(size 0.508 2.4892)
			(layers "F.Cu" "F.Mask" "F.Paste")
			(net "PE_TX3_DR1_P")
		)
		(pad "A15" smd rect
			(at -29.99994 -0.750062 90)
			(size 0.508 2.4892)
			(layers "F.Cu" "F.Mask" "F.Paste")
			(net "GND")
		)
		(pad "A16" smd rect
			(at -29.200094 -0.750062 90)
			(size 0.508 2.4892)
			(layers "F.Cu" "F.Mask" "F.Paste")
			(net "GND")
		)
		(pad "A17" smd rect
			(at -28.399994 -0.750062 90)
			(size 0.508 2.4892)
			(layers "F.Cu" "F.Mask" "F.Paste")
			(net "PE_TX4_DR1_N")
		)
		(pad "A18" smd rect
			(at -27.599894 -0.750062 90)
			(size 0.508 2.4892)
			(layers "F.Cu" "F.Mask" "F.Paste")
			(net "PE_TX4_DR1_P")
		)
		(pad "A19" smd rect
			(at -26.800048 -0.750062 90)
			(size 0.508 2.4892)
			(layers "F.Cu" "F.Mask" "F.Paste")
			(net "GND")
		)
		(pad "A20" smd rect
			(at -25.999948 -0.750062 90)
			(size 0.508 2.4892)
			(layers "F.Cu" "F.Mask" "F.Paste")
			(net "SSD1_CLK0_OE_R_N")
		)
		(pad "A21" smd rect
			(at -25.200102 -0.750062 90)
			(size 0.508 2.4892)
			(layers "F.Cu" "F.Mask" "F.Paste")
			(net "ATTN_LED_DR1_N")
		)
		(pad "A22" smd rect
			(at -24.400002 -0.750062 90)
			(size 0.508 2.4892)
			(layers "F.Cu" "F.Mask" "F.Paste")
			(net "SSD1_PWREN")
		)
		(pad "A23" smd rect
			(at -23.599902 -0.750062 90)
			(size 0.508 2.4892)
			(layers "F.Cu" "F.Mask" "F.Paste")
			(net "GND")
		)
		(pad "A24" smd rect
			(at -22.800056 -0.750062 90)
			(size 0.508 2.4892)
			(layers "F.Cu" "F.Mask" "F.Paste")
			(net "PE_TX1_DR10_P")
		)
		(pad "A25" smd rect
			(at -21.999956 -0.750062 90)
			(size 0.508 2.4892)
			(layers "F.Cu" "F.Mask" "F.Paste")
			(net "PE_TX1_DR10_N")
		)
		(pad "A26" smd rect
			(at -21.20011 -0.750062 90)
			(size 0.508 2.4892)
			(layers "F.Cu" "F.Mask" "F.Paste")
			(net "GND")
		)
		(pad "A27" smd rect
			(at -20.40001 -0.750062 90)
			(size 0.508 2.4892)
			(layers "F.Cu" "F.Mask" "F.Paste")
			(net "GND")
		)
		(pad "A28" smd rect
			(at -19.59991 -0.750062 90)
			(size 0.508 2.4892)
			(layers "F.Cu" "F.Mask" "F.Paste")
			(net "PE_TX2_DR10_P")
		)
		(pad "A29" smd rect
			(at -18.800064 -0.750062 90)
			(size 0.508 2.4892)
			(layers "F.Cu" "F.Mask" "F.Paste")
			(net "PE_TX2_DR10_N")
		)
		(pad "A30" smd rect
			(at -17.999964 -0.750062 90)
			(size 0.508 2.4892)
			(layers "F.Cu" "F.Mask" "F.Paste")
			(net "GND")
		)
		(pad "A31" smd rect
			(at -17.200118 -0.750062 90)
			(size 0.508 2.4892)
			(layers "F.Cu" "F.Mask" "F.Paste")
			(net "GND")
		)
		(pad "A32" smd rect
			(at -16.400018 -0.750062 90)
			(size 0.508 2.4892)
			(layers "F.Cu" "F.Mask" "F.Paste")
			(net "PE_TX3_DR10_P")
		)
		(pad "A33" smd rect
			(at -15.599918 -0.750062 90)
			(size 0.508 2.4892)
			(layers "F.Cu" "F.Mask" "F.Paste")
			(net "PE_TX3_DR10_N")
		)
		(pad "A34" smd rect
			(at -14.800072 -0.750062 90)
			(size 0.508 2.4892)
			(layers "F.Cu" "F.Mask" "F.Paste")
			(net "GND")
		)
		(pad "A35" smd rect
			(at -13.999972 -0.750062 90)
			(size 0.508 2.4892)
			(layers "F.Cu" "F.Mask" "F.Paste")
			(net "GND")
		)
		(pad "A36" smd rect
			(at -13.200126 -0.750062 90)
			(size 0.508 2.4892)
			(layers "F.Cu" "F.Mask" "F.Paste")
			(net "PE_TX4_DR10_P")
		)
		(pad "A37" smd rect
			(at -12.400026 -0.750062 90)
			(size 0.508 2.4892)
			(layers "F.Cu" "F.Mask" "F.Paste")
			(net "PE_TX4_DR10_N")
		)
		(pad "A38" smd rect
			(at -11.599926 -0.750062 90)
			(size 0.508 2.4892)
			(layers "F.Cu" "F.Mask" "F.Paste")
			(net "GND")
		)
		(pad "A39" smd rect
			(at -10.80008 -0.750062 90)
			(size 0.508 2.4892)
			(layers "F.Cu" "F.Mask" "F.Paste")
			(net "GND")
		)
		(pad "A40" smd rect
			(at -9.99998 -0.750062 90)
			(size 0.508 2.4892)
			(layers "F.Cu" "F.Mask" "F.Paste")
			(net "PE_TX1_DR0_N")
		)
		(pad "A41" smd rect
			(at -9.19988 -0.750062 90)
			(size 0.508 2.4892)
			(layers "F.Cu" "F.Mask" "F.Paste")
			(net "PE_TX1_DR0_P")
		)
		(pad "A42" smd rect
			(at -8.400034 -0.750062 90)
			(size 0.508 2.4892)
			(layers "F.Cu" "F.Mask" "F.Paste")
			(net "GND")
		)
		(pad "A43" smd rect
			(at -7.599934 -0.750062 90)
			(size 0.508 2.4892)
			(layers "F.Cu" "F.Mask" "F.Paste")
			(net "SSD1_PERST_N")
		)
		(pad "A44" smd rect
			(at -6.800088 -0.750062 90)
			(size 0.508 2.4892)
			(layers "F.Cu" "F.Mask" "F.Paste")
			(net "SSD0_PERST_N")
		)
		(pad "A45" smd rect
			(at -2.800096 -0.750062 90)
			(size 0.508 2.4892)
			(layers "F.Cu" "F.Mask" "F.Paste")
			(net "PWM_EXP_A")
		)
		(pad "A46" smd rect
			(at -1.999996 -0.750062 90)
			(size 0.508 2.4892)
			(layers "F.Cu" "F.Mask" "F.Paste")
			(net "PCIE_MATED#_A")
		)
		(pad "A47" smd rect
			(at -1.199896 -0.750062 90)
			(size 0.508 2.4892)
			(layers "F.Cu" "F.Mask" "F.Paste")
			(net "GND")
		)
		(pad "A48" smd rect
			(at -0.40005 -0.750062 90)
			(size 0.508 2.4892)
			(layers "F.Cu" "F.Mask" "F.Paste")
			(net "PE_TX2_DR0_N")
		)
		(pad "A49" smd rect
			(at 0.40005 -0.750062 90)
			(size 0.508 2.4892)
			(layers "F.Cu" "F.Mask" "F.Paste")
			(net "PE_TX2_DR0_P")
		)
		(pad "A50" smd rect
			(at 1.199896 -0.750062 90)
			(size 0.508 2.4892)
			(layers "F.Cu" "F.Mask" "F.Paste")
			(net "GND")
		)
		(pad "A51" smd rect
			(at 1.999996 -0.750062 90)
			(size 0.508 2.4892)
			(layers "F.Cu" "F.Mask" "F.Paste")
			(net "GND")
		)
		(pad "A52" smd rect
			(at 2.800096 -0.750062 90)
			(size 0.508 2.4892)
			(layers "F.Cu" "F.Mask" "F.Paste")
			(net "PE_TX3_DR0_N")
		)
		(pad "A53" smd rect
			(at 3.599942 -0.750062 90)
			(size 0.508 2.4892)
			(layers "F.Cu" "F.Mask" "F.Paste")
			(net "PE_TX3_DR0_P")
		)
		(pad "A54" smd rect
			(at 4.400042 -0.750062 90)
			(size 0.508 2.4892)
			(layers "F.Cu" "F.Mask" "F.Paste")
			(net "GND")
		)
		(pad "A55" smd rect
			(at 5.199888 -0.750062 90)
			(size 0.508 2.4892)
			(layers "F.Cu" "F.Mask" "F.Paste")
			(net "GND")
		)
		(pad "A56" smd rect
			(at 5.999988 -0.750062 90)
			(size 0.508 2.4892)
			(layers "F.Cu" "F.Mask" "F.Paste")
			(net "PE_TX4_DR0_N")
		)
		(pad "A57" smd rect
			(at 6.800088 -0.750062 90)
			(size 0.508 2.4892)
			(layers "F.Cu" "F.Mask" "F.Paste")
			(net "PE_TX4_DR0_P")
		)
		(pad "A58" smd rect
			(at 7.599934 -0.750062 90)
			(size 0.508 2.4892)
			(layers "F.Cu" "F.Mask" "F.Paste")
			(net "GND")
		)
		(pad "A59" smd rect
			(at 8.400034 -0.750062 90)
			(size 0.508 2.4892)
			(layers "F.Cu" "F.Mask" "F.Paste")
			(net "SSD0_PWREN")
		)
		(pad "A60" smd rect
			(at 9.19988 -0.750062 90)
			(size 0.508 2.4892)
			(layers "F.Cu" "F.Mask" "F.Paste")
			(net "ATTN_LED_DR0_N")
		)
		(pad "A61" smd rect
			(at 9.99998 -0.750062 90)
			(size 0.508 2.4892)
			(layers "F.Cu" "F.Mask" "F.Paste")
			(net "SSD0_CLK0_OE_R_N")
		)
		(pad "A62" smd rect
			(at 10.80008 -0.750062 90)
			(size 0.508 2.4892)
			(layers "F.Cu" "F.Mask" "F.Paste")
			(net "GND")
		)
		(pad "A63" smd rect
			(at 11.599926 -0.750062 90)
			(size 0.508 2.4892)
			(layers "F.Cu" "F.Mask" "F.Paste")
			(net "PE_TX1_DR5_P")
		)
		(pad "A64" smd rect
			(at 12.400026 -0.750062 90)
			(size 0.508 2.4892)
			(layers "F.Cu" "F.Mask" "F.Paste")
			(net "PE_TX1_DR5_N")
		)
		(pad "A65" smd rect
			(at 13.200126 -0.750062 90)
			(size 0.508 2.4892)
			(layers "F.Cu" "F.Mask" "F.Paste")
			(net "GND")
		)
		(pad "A66" smd rect
			(at 13.999972 -0.750062 90)
			(size 0.508 2.4892)
			(layers "F.Cu" "F.Mask" "F.Paste")
			(net "GND")
		)
		(pad "A67" smd rect
			(at 14.800072 -0.750062 90)
			(size 0.508 2.4892)
			(layers "F.Cu" "F.Mask" "F.Paste")
			(net "PE_TX2_DR5_P")
		)
		(pad "A68" smd rect
			(at 15.599918 -0.750062 90)
			(size 0.508 2.4892)
			(layers "F.Cu" "F.Mask" "F.Paste")
			(net "PE_TX2_DR5_N")
		)
		(pad "A69" smd rect
			(at 16.400018 -0.750062 90)
			(size 0.508 2.4892)
			(layers "F.Cu" "F.Mask" "F.Paste")
			(net "GND")
		)
		(pad "A70" smd rect
			(at 17.200118 -0.750062 90)
			(size 0.508 2.4892)
			(layers "F.Cu" "F.Mask" "F.Paste")
			(net "GND")
		)
		(pad "A71" smd rect
			(at 17.999964 -0.750062 90)
			(size 0.508 2.4892)
			(layers "F.Cu" "F.Mask" "F.Paste")
			(net "PE_TX3_DR5_P")
		)
		(pad "A72" smd rect
			(at 18.800064 -0.750062 90)
			(size 0.508 2.4892)
			(layers "F.Cu" "F.Mask" "F.Paste")
			(net "PE_TX3_DR5_N")
		)
		(pad "A73" smd rect
			(at 19.59991 -0.750062 90)
			(size 0.508 2.4892)
			(layers "F.Cu" "F.Mask" "F.Paste")
			(net "GND")
		)
		(pad "A74" smd rect
			(at 20.40001 -0.750062 90)
			(size 0.508 2.4892)
			(layers "F.Cu" "F.Mask" "F.Paste")
			(net "GND")
		)
		(pad "A75" smd rect
			(at 21.20011 -0.750062 90)
			(size 0.508 2.4892)
			(layers "F.Cu" "F.Mask" "F.Paste")
			(net "PE_TX4_DR5_P")
		)
		(pad "A76" smd rect
			(at 21.999956 -0.750062 90)
			(size 0.508 2.4892)
			(layers "F.Cu" "F.Mask" "F.Paste")
			(net "PE_TX4_DR5_N")
		)
		(pad "A77" smd rect
			(at 22.800056 -0.750062 90)
			(size 0.508 2.4892)
			(layers "F.Cu" "F.Mask" "F.Paste")
			(net "GND")
		)
		(pad "A78" smd rect
			(at 23.599902 -0.750062 90)
			(size 0.508 2.4892)
			(layers "F.Cu" "F.Mask" "F.Paste")
			(net "PE_100M_CLK4_C_P")
		)
		(pad "A79" smd rect
			(at 24.400002 -0.750062 90)
			(size 0.508 2.4892)
			(layers "F.Cu" "F.Mask" "F.Paste")
			(net "PE_100M_CLK4_C_N")
		)
		(pad "A80" smd rect
			(at 25.200102 -0.750062 90)
			(size 0.508 2.4892)
			(layers "F.Cu" "F.Mask" "F.Paste")
			(net "GND")
		)
		(pad "A81" smd rect
			(at 25.999948 -0.750062 90)
			(size 0.508 2.4892)
			(layers "F.Cu" "F.Mask" "F.Paste")
			(net "SAS_I2C_B_BUF_SCL_R")
		)
		(pad "A82" smd rect
			(at 26.800048 -0.750062 90)
			(size 0.508 2.4892)
			(layers "F.Cu" "F.Mask" "F.Paste")
			(net "SAS_I2C_B_BUF_SDA_R")
		)
		(pad "A83" smd rect
			(at 27.599894 -0.750062 90)
			(size 0.508 2.4892)
			(layers "F.Cu" "F.Mask" "F.Paste")
			(net "GND")
		)
		(pad "A84" smd rect
			(at 28.399994 -0.750062 90)
			(size 0.508 2.4892)
			(layers "F.Cu" "F.Mask" "F.Paste")
			(net "BMC_I2C_SCL_BUF_9")
		)
		(pad "A85" smd rect
			(at 29.200094 -0.750062 90)
			(size 0.508 2.4892)
			(layers "F.Cu" "F.Mask" "F.Paste")
			(net "BMC_I2C_SDA_BUF_9")
		)
		(pad "A86" smd rect
			(at 29.99994 -0.750062 90)
			(size 0.508 2.4892)
			(layers "F.Cu" "F.Mask" "F.Paste")
			(net "GND")
		)
		(pad "A87" smd rect
			(at 30.80004 -0.750062 90)
			(size 0.508 2.4892)
			(layers "F.Cu" "F.Mask" "F.Paste")
			(net "SAS_I2C_C_BUF_SCL_R")
		)
		(pad "A88" smd rect
			(at 31.599886 -0.750062 90)
			(size 0.508 2.4892)
			(layers "F.Cu" "F.Mask" "F.Paste")
			(net "SAS_I2C_C_BUF_SDA_R")
		)
		(pad "A89" smd rect
			(at 32.399986 -0.750062 90)
			(size 0.508 2.4892)
			(layers "F.Cu" "F.Mask" "F.Paste")
			(net "GND")
		)
		(pad "A90" smd rect
			(at 33.200086 -0.750062 90)
			(size 0.508 2.4892)
			(layers "F.Cu" "F.Mask" "F.Paste")
			(net "GND")
		)
		(pad "A91" smd rect
			(at 33.999932 -0.750062 90)
			(size 0.508 2.4892)
			(layers "F.Cu" "F.Mask" "F.Paste")
			(net "GND")
		)
		(pad "A92" smd rect
			(at 34.800032 -0.750062 90)
			(size 0.508 2.4892)
			(layers "F.Cu" "F.Mask" "F.Paste")
			(net "GND")
		)
		(pad "A93" smd rect
			(at 35.599878 -0.750062 90)
			(size 0.508 2.4892)
			(layers "F.Cu" "F.Mask" "F.Paste")
			(net "GND")
		)
		(pad "A94" smd rect
			(at 36.399978 -0.750062 90)
			(size 0.508 2.4892)
			(layers "F.Cu" "F.Mask" "F.Paste")
			(net "GND")
		)
		(pad "A95" smd rect
			(at 37.200078 -0.750062 90)
			(size 0.508 2.4892)
			(layers "F.Cu" "F.Mask" "F.Paste")
			(net "P12V")
		)
		(pad "A96" smd rect
			(at 37.999924 -0.750062 90)
			(size 0.508 2.4892)
			(layers "F.Cu" "F.Mask" "F.Paste")
			(net "P12V")
		)
		(pad "A97" smd rect
			(at 38.800024 -0.750062 90)
			(size 0.508 2.4892)
			(layers "F.Cu" "F.Mask" "F.Paste")
			(net "P12V")
		)
		(pad "A98" smd rect
			(at 39.600124 -0.750062 90)
			(size 0.508 2.4892)
			(layers "F.Cu" "F.Mask" "F.Paste")
			(net "P12V")
		)
		(pad "A99" smd rect
			(at 40.39997 -0.750062 90)
			(size 0.508 2.4892)
			(layers "F.Cu" "F.Mask" "F.Paste")
			(net "P12V")
		)
		(pad "A100" smd rect
			(at 41.20007 -0.750062 90)
			(size 0.508 2.4892)
			(layers "F.Cu" "F.Mask" "F.Paste")
			(net "P12V")
		)
		(pad "B1" smd rect
			(at -41.20007 -1.131062 90)
			(size 0.508 2.4892)
			(drill
				(offset 0 0.381)
			)
			(layers "F.Cu" "F.Mask" "F.Paste")
			(net "GND")
		)
		(pad "B2" smd rect
			(at -40.39997 -1.131062 90)
			(size 0.508 2.4892)
			(drill
				(offset 0 0.381)
			)
			(layers "F.Cu" "F.Mask" "F.Paste")
			(net "PE_100M_CLK2_C_P")
		)
		(pad "B3" smd rect
			(at -39.600124 -1.131062 90)
			(size 0.508 2.4892)
			(drill
				(offset 0 0.381)
			)
			(layers "F.Cu" "F.Mask" "F.Paste")
			(net "PE_100M_CLK2_C_N")
		)
		(pad "B4" smd rect
			(at -38.800024 -1.131062 90)
			(size 0.508 2.4892)
			(drill
				(offset 0 0.381)
			)
			(layers "F.Cu" "F.Mask" "F.Paste")
			(net "GND")
		)
		(pad "B5" smd rect
			(at -37.999924 -1.131062 90)
			(size 0.508 2.4892)
			(drill
				(offset 0 0.381)
			)
			(layers "F.Cu" "F.Mask" "F.Paste")
			(net "SSD10_PERST_N")
		)
		(pad "B6" smd rect
			(at -37.200078 -1.131062 90)
			(size 0.508 2.4892)
			(drill
				(offset 0 0.381)
			)
			(layers "F.Cu" "F.Mask" "F.Paste")
			(net "GND")
		)
		(pad "B7" smd rect
			(at -36.399978 -1.131062 90)
			(size 0.508 2.4892)
			(drill
				(offset 0 0.381)
			)
			(layers "F.Cu" "F.Mask" "F.Paste")
			(net "PE_RX1_DR1_N")
		)
		(pad "B8" smd rect
			(at -35.599878 -1.131062 90)
			(size 0.508 2.4892)
			(drill
				(offset 0 0.381)
			)
			(layers "F.Cu" "F.Mask" "F.Paste")
			(net "PE_RX1_DR1_P")
		)
		(pad "B9" smd rect
			(at -34.800032 -1.131062 90)
			(size 0.508 2.4892)
			(drill
				(offset 0 0.381)
			)
			(layers "F.Cu" "F.Mask" "F.Paste")
			(net "GND")
		)
		(pad "B10" smd rect
			(at -33.999932 -1.131062 90)
			(size 0.508 2.4892)
			(drill
				(offset 0 0.381)
			)
			(layers "F.Cu" "F.Mask" "F.Paste")
			(net "GND")
		)
		(pad "B11" smd rect
			(at -33.200086 -1.131062 90)
			(size 0.508 2.4892)
			(drill
				(offset 0 0.381)
			)
			(layers "F.Cu" "F.Mask" "F.Paste")
			(net "PE_RX2_DR1_N")
		)
		(pad "B12" smd rect
			(at -32.399986 -1.131062 90)
			(size 0.508 2.4892)
			(drill
				(offset 0 0.381)
			)
			(layers "F.Cu" "F.Mask" "F.Paste")
			(net "PE_RX2_DR1_P")
		)
		(pad "B13" smd rect
			(at -31.599886 -1.131062 90)
			(size 0.508 2.4892)
			(drill
				(offset 0 0.381)
			)
			(layers "F.Cu" "F.Mask" "F.Paste")
			(net "GND")
		)
		(pad "B14" smd rect
			(at -30.80004 -1.131062 90)
			(size 0.508 2.4892)
			(drill
				(offset 0 0.381)
			)
			(layers "F.Cu" "F.Mask" "F.Paste")
			(net "GND")
		)
		(pad "B15" smd rect
			(at -29.99994 -1.131062 90)
			(size 0.508 2.4892)
			(drill
				(offset 0 0.381)
			)
			(layers "F.Cu" "F.Mask" "F.Paste")
			(net "PE_RX3_DR1_N")
		)
		(pad "B16" smd rect
			(at -29.200094 -1.131062 90)
			(size 0.508 2.4892)
			(drill
				(offset 0 0.381)
			)
			(layers "F.Cu" "F.Mask" "F.Paste")
			(net "PE_RX3_DR1_P")
		)
		(pad "B17" smd rect
			(at -28.399994 -1.131062 90)
			(size 0.508 2.4892)
			(drill
				(offset 0 0.381)
			)
			(layers "F.Cu" "F.Mask" "F.Paste")
			(net "GND")
		)
		(pad "B18" smd rect
			(at -27.599894 -1.131062 90)
			(size 0.508 2.4892)
			(drill
				(offset 0 0.381)
			)
			(layers "F.Cu" "F.Mask" "F.Paste")
			(net "GND")
		)
		(pad "B19" smd rect
			(at -26.800048 -1.131062 90)
			(size 0.508 2.4892)
			(drill
				(offset 0 0.381)
			)
			(layers "F.Cu" "F.Mask" "F.Paste")
			(net "PE_RX4_DR1_N")
		)
		(pad "B20" smd rect
			(at -25.999948 -1.131062 90)
			(size 0.508 2.4892)
			(drill
				(offset 0 0.381)
			)
			(layers "F.Cu" "F.Mask" "F.Paste")
			(net "PE_RX4_DR1_P")
		)
		(pad "B21" smd rect
			(at -25.200102 -1.131062 90)
			(size 0.508 2.4892)
			(drill
				(offset 0 0.381)
			)
			(layers "F.Cu" "F.Mask" "F.Paste")
			(net "GND")
		)
		(pad "B22" smd rect
			(at -24.400002 -1.131062 90)
			(size 0.508 2.4892)
			(drill
				(offset 0 0.381)
			)
			(layers "F.Cu" "F.Mask" "F.Paste")
			(net "SSD10_PWREN")
		)
		(pad "B23" smd rect
			(at -23.599902 -1.131062 90)
			(size 0.508 2.4892)
			(drill
				(offset 0 0.381)
			)
			(layers "F.Cu" "F.Mask" "F.Paste")
			(net "ATTN_LED_DR10_N")
		)
		(pad "B24" smd rect
			(at -22.800056 -1.131062 90)
			(size 0.508 2.4892)
			(drill
				(offset 0 0.381)
			)
			(layers "F.Cu" "F.Mask" "F.Paste")
			(net "SSD10_CLK0_OE_R_N")
		)
		(pad "B25" smd rect
			(at -21.999956 -1.131062 90)
			(size 0.508 2.4892)
			(drill
				(offset 0 0.381)
			)
			(layers "F.Cu" "F.Mask" "F.Paste")
			(net "GND")
		)
		(pad "B26" smd rect
			(at -21.20011 -1.131062 90)
			(size 0.508 2.4892)
			(drill
				(offset 0 0.381)
			)
			(layers "F.Cu" "F.Mask" "F.Paste")
			(net "PE_RX1_DR10_P")
		)
		(pad "B27" smd rect
			(at -20.40001 -1.131062 90)
			(size 0.508 2.4892)
			(drill
				(offset 0 0.381)
			)
			(layers "F.Cu" "F.Mask" "F.Paste")
			(net "PE_RX1_DR10_N")
		)
		(pad "B28" smd rect
			(at -19.59991 -1.131062 90)
			(size 0.508 2.4892)
			(drill
				(offset 0 0.381)
			)
			(layers "F.Cu" "F.Mask" "F.Paste")
			(net "GND")
		)
		(pad "B29" smd rect
			(at -18.800064 -1.131062 90)
			(size 0.508 2.4892)
			(drill
				(offset 0 0.381)
			)
			(layers "F.Cu" "F.Mask" "F.Paste")
			(net "GND")
		)
		(pad "B30" smd rect
			(at -17.999964 -1.131062 90)
			(size 0.508 2.4892)
			(drill
				(offset 0 0.381)
			)
			(layers "F.Cu" "F.Mask" "F.Paste")
			(net "PE_RX2_DR10_P")
		)
		(pad "B31" smd rect
			(at -17.200118 -1.131062 90)
			(size 0.508 2.4892)
			(drill
				(offset 0 0.381)
			)
			(layers "F.Cu" "F.Mask" "F.Paste")
			(net "PE_RX2_DR10_N")
		)
		(pad "B32" smd rect
			(at -16.400018 -1.131062 90)
			(size 0.508 2.4892)
			(drill
				(offset 0 0.381)
			)
			(layers "F.Cu" "F.Mask" "F.Paste")
			(net "GND")
		)
		(pad "B33" smd rect
			(at -15.599918 -1.131062 90)
			(size 0.508 2.4892)
			(drill
				(offset 0 0.381)
			)
			(layers "F.Cu" "F.Mask" "F.Paste")
			(net "GND")
		)
		(pad "B34" smd rect
			(at -14.800072 -1.131062 90)
			(size 0.508 2.4892)
			(drill
				(offset 0 0.381)
			)
			(layers "F.Cu" "F.Mask" "F.Paste")
			(net "PE_RX3_DR10_P")
		)
		(pad "B35" smd rect
			(at -13.999972 -1.131062 90)
			(size 0.508 2.4892)
			(drill
				(offset 0 0.381)
			)
			(layers "F.Cu" "F.Mask" "F.Paste")
			(net "PE_RX3_DR10_N")
		)
		(pad "B36" smd rect
			(at -13.200126 -1.131062 90)
			(size 0.508 2.4892)
			(drill
				(offset 0 0.381)
			)
			(layers "F.Cu" "F.Mask" "F.Paste")
			(net "GND")
		)
		(pad "B37" smd rect
			(at -12.400026 -1.131062 90)
			(size 0.508 2.4892)
			(drill
				(offset 0 0.381)
			)
			(layers "F.Cu" "F.Mask" "F.Paste")
			(net "GND")
		)
		(pad "B38" smd rect
			(at -11.599926 -1.131062 90)
			(size 0.508 2.4892)
			(drill
				(offset 0 0.381)
			)
			(layers "F.Cu" "F.Mask" "F.Paste")
			(net "PE_RX4_DR10_P")
		)
		(pad "B39" smd rect
			(at -10.80008 -1.131062 90)
			(size 0.508 2.4892)
			(drill
				(offset 0 0.381)
			)
			(layers "F.Cu" "F.Mask" "F.Paste")
			(net "PE_RX4_DR10_N")
		)
		(pad "B40" smd rect
			(at -9.99998 -1.131062 90)
			(size 0.508 2.4892)
			(drill
				(offset 0 0.381)
			)
			(layers "F.Cu" "F.Mask" "F.Paste")
			(net "GND")
		)
		(pad "B41" smd rect
			(at -9.19988 -1.131062 90)
			(size 0.508 2.4892)
			(drill
				(offset 0 0.381)
			)
			(layers "F.Cu" "F.Mask" "F.Paste")
			(net "GND")
		)
		(pad "B42" smd rect
			(at -8.400034 -1.131062 90)
			(size 0.508 2.4892)
			(drill
				(offset 0 0.381)
			)
			(layers "F.Cu" "F.Mask" "F.Paste")
			(net "PE_RX1_DR0_N")
		)
		(pad "B43" smd rect
			(at -7.599934 -1.131062 90)
			(size 0.508 2.4892)
			(drill
				(offset 0 0.381)
			)
			(layers "F.Cu" "F.Mask" "F.Paste")
			(net "PE_RX1_DR0_P")
		)
		(pad "B44" smd rect
			(at -6.800088 -1.131062 90)
			(size 0.508 2.4892)
			(drill
				(offset 0 0.381)
			)
			(layers "F.Cu" "F.Mask" "F.Paste")
			(net "GND")
		)
		(pad "B45" smd rect
			(at -2.800096 -1.131062 90)
			(size 0.508 2.4892)
			(drill
				(offset 0 0.381)
			)
			(layers "F.Cu" "F.Mask" "F.Paste")
			(net "GND")
		)
		(pad "B46" smd rect
			(at -1.999996 -1.131062 90)
			(size 0.508 2.4892)
			(drill
				(offset 0 0.381)
			)
			(layers "F.Cu" "F.Mask" "F.Paste")
			(net "PE_RX2_DR0_N")
		)
		(pad "B47" smd rect
			(at -1.199896 -1.131062 90)
			(size 0.508 2.4892)
			(drill
				(offset 0 0.381)
			)
			(layers "F.Cu" "F.Mask" "F.Paste")
			(net "PE_RX2_DR0_P")
		)
		(pad "B48" smd rect
			(at -0.40005 -1.131062 90)
			(size 0.508 2.4892)
			(drill
				(offset 0 0.381)
			)
			(layers "F.Cu" "F.Mask" "F.Paste")
			(net "GND")
		)
		(pad "B49" smd rect
			(at 0.40005 -1.131062 90)
			(size 0.508 2.4892)
			(drill
				(offset 0 0.381)
			)
			(layers "F.Cu" "F.Mask" "F.Paste")
			(net "GND")
		)
		(pad "B50" smd rect
			(at 1.199896 -1.131062 90)
			(size 0.508 2.4892)
			(drill
				(offset 0 0.381)
			)
			(layers "F.Cu" "F.Mask" "F.Paste")
			(net "PE_RX3_DR0_N")
		)
		(pad "B51" smd rect
			(at 1.999996 -1.131062 90)
			(size 0.508 2.4892)
			(drill
				(offset 0 0.381)
			)
			(layers "F.Cu" "F.Mask" "F.Paste")
			(net "PE_RX3_DR0_P")
		)
		(pad "B52" smd rect
			(at 2.800096 -1.131062 90)
			(size 0.508 2.4892)
			(drill
				(offset 0 0.381)
			)
			(layers "F.Cu" "F.Mask" "F.Paste")
			(net "GND")
		)
		(pad "B53" smd rect
			(at 3.599942 -1.131062 90)
			(size 0.508 2.4892)
			(drill
				(offset 0 0.381)
			)
			(layers "F.Cu" "F.Mask" "F.Paste")
			(net "GND")
		)
		(pad "B54" smd rect
			(at 4.400042 -1.131062 90)
			(size 0.508 2.4892)
			(drill
				(offset 0 0.381)
			)
			(layers "F.Cu" "F.Mask" "F.Paste")
			(net "PE_RX4_DR0_N")
		)
		(pad "B55" smd rect
			(at 5.199888 -1.131062 90)
			(size 0.508 2.4892)
			(drill
				(offset 0 0.381)
			)
			(layers "F.Cu" "F.Mask" "F.Paste")
			(net "PE_RX4_DR0_P")
		)
		(pad "B56" smd rect
			(at 5.999988 -1.131062 90)
			(size 0.508 2.4892)
			(drill
				(offset 0 0.381)
			)
			(layers "F.Cu" "F.Mask" "F.Paste")
			(net "GND")
		)
		(pad "B57" smd rect
			(at 6.800088 -1.131062 90)
			(size 0.508 2.4892)
			(drill
				(offset 0 0.381)
			)
			(layers "F.Cu" "F.Mask" "F.Paste")
			(net "SSD5_CLK0_OE_R_N")
		)
		(pad "B58" smd rect
			(at 7.599934 -1.131062 90)
			(size 0.508 2.4892)
			(drill
				(offset 0 0.381)
			)
			(layers "F.Cu" "F.Mask" "F.Paste")
			(net "ATTN_LED_DR5_N")
		)
		(pad "B59" smd rect
			(at 8.400034 -1.131062 90)
			(size 0.508 2.4892)
			(drill
				(offset 0 0.381)
			)
			(layers "F.Cu" "F.Mask" "F.Paste")
			(net "SSD5_PWREN")
		)
		(pad "B60" smd rect
			(at 9.19988 -1.131062 90)
			(size 0.508 2.4892)
			(drill
				(offset 0 0.381)
			)
			(layers "F.Cu" "F.Mask" "F.Paste")
			(net "GND")
		)
		(pad "B61" smd rect
			(at 9.99998 -1.131062 90)
			(size 0.508 2.4892)
			(drill
				(offset 0 0.381)
			)
			(layers "F.Cu" "F.Mask" "F.Paste")
			(net "PE_RX1_DR5_P")
		)
		(pad "B62" smd rect
			(at 10.80008 -1.131062 90)
			(size 0.508 2.4892)
			(drill
				(offset 0 0.381)
			)
			(layers "F.Cu" "F.Mask" "F.Paste")
			(net "PE_RX1_DR5_N")
		)
		(pad "B63" smd rect
			(at 11.599926 -1.131062 90)
			(size 0.508 2.4892)
			(drill
				(offset 0 0.381)
			)
			(layers "F.Cu" "F.Mask" "F.Paste")
			(net "GND")
		)
		(pad "B64" smd rect
			(at 12.400026 -1.131062 90)
			(size 0.508 2.4892)
			(drill
				(offset 0 0.381)
			)
			(layers "F.Cu" "F.Mask" "F.Paste")
			(net "GND")
		)
		(pad "B65" smd rect
			(at 13.200126 -1.131062 90)
			(size 0.508 2.4892)
			(drill
				(offset 0 0.381)
			)
			(layers "F.Cu" "F.Mask" "F.Paste")
			(net "PE_RX2_DR5_P")
		)
		(pad "B66" smd rect
			(at 13.999972 -1.131062 90)
			(size 0.508 2.4892)
			(drill
				(offset 0 0.381)
			)
			(layers "F.Cu" "F.Mask" "F.Paste")
			(net "PE_RX2_DR5_N")
		)
		(pad "B67" smd rect
			(at 14.800072 -1.131062 90)
			(size 0.508 2.4892)
			(drill
				(offset 0 0.381)
			)
			(layers "F.Cu" "F.Mask" "F.Paste")
			(net "GND")
		)
		(pad "B68" smd rect
			(at 15.599918 -1.131062 90)
			(size 0.508 2.4892)
			(drill
				(offset 0 0.381)
			)
			(layers "F.Cu" "F.Mask" "F.Paste")
			(net "GND")
		)
		(pad "B69" smd rect
			(at 16.400018 -1.131062 90)
			(size 0.508 2.4892)
			(drill
				(offset 0 0.381)
			)
			(layers "F.Cu" "F.Mask" "F.Paste")
			(net "PE_RX3_DR5_P")
		)
		(pad "B70" smd rect
			(at 17.200118 -1.131062 90)
			(size 0.508 2.4892)
			(drill
				(offset 0 0.381)
			)
			(layers "F.Cu" "F.Mask" "F.Paste")
			(net "PE_RX3_DR5_N")
		)
		(pad "B71" smd rect
			(at 17.999964 -1.131062 90)
			(size 0.508 2.4892)
			(drill
				(offset 0 0.381)
			)
			(layers "F.Cu" "F.Mask" "F.Paste")
			(net "GND")
		)
		(pad "B72" smd rect
			(at 18.800064 -1.131062 90)
			(size 0.508 2.4892)
			(drill
				(offset 0 0.381)
			)
			(layers "F.Cu" "F.Mask" "F.Paste")
			(net "GND")
		)
		(pad "B73" smd rect
			(at 19.59991 -1.131062 90)
			(size 0.508 2.4892)
			(drill
				(offset 0 0.381)
			)
			(layers "F.Cu" "F.Mask" "F.Paste")
			(net "PE_RX4_DR5_P")
		)
		(pad "B74" smd rect
			(at 20.40001 -1.131062 90)
			(size 0.508 2.4892)
			(drill
				(offset 0 0.381)
			)
			(layers "F.Cu" "F.Mask" "F.Paste")
			(net "PE_RX4_DR5_N")
		)
		(pad "B75" smd rect
			(at 21.20011 -1.131062 90)
			(size 0.508 2.4892)
			(drill
				(offset 0 0.381)
			)
			(layers "F.Cu" "F.Mask" "F.Paste")
			(net "GND")
		)
		(pad "B76" smd rect
			(at 21.999956 -1.131062 90)
			(size 0.508 2.4892)
			(drill
				(offset 0 0.381)
			)
			(layers "F.Cu" "F.Mask" "F.Paste")
			(net "PE_100M_CLK3_C_P")
		)
		(pad "B77" smd rect
			(at 22.800056 -1.131062 90)
			(size 0.508 2.4892)
			(drill
				(offset 0 0.381)
			)
			(layers "F.Cu" "F.Mask" "F.Paste")
			(net "PE_100M_CLK3_C_N")
		)
		(pad "B78" smd rect
			(at 23.599902 -1.131062 90)
			(size 0.508 2.4892)
			(drill
				(offset 0 0.381)
			)
			(layers "F.Cu" "F.Mask" "F.Paste")
			(net "GND")
		)
		(pad "B79" smd rect
			(at 24.400002 -1.131062 90)
			(size 0.508 2.4892)
			(drill
				(offset 0 0.381)
			)
			(layers "F.Cu" "F.Mask" "F.Paste")
			(net "BMC_I2C_SCL_BUF_8")
		)
		(pad "B80" smd rect
			(at 25.200102 -1.131062 90)
			(size 0.508 2.4892)
			(drill
				(offset 0 0.381)
			)
			(layers "F.Cu" "F.Mask" "F.Paste")
			(net "BMC_I2C_SDA_BUF_8")
		)
		(pad "B81" smd rect
			(at 25.999948 -1.131062 90)
			(size 0.508 2.4892)
			(drill
				(offset 0 0.381)
			)
			(layers "F.Cu" "F.Mask" "F.Paste")
			(net "GND")
		)
		(pad "B82" smd rect
			(at 26.800048 -1.131062 90)
			(size 0.508 2.4892)
			(drill
				(offset 0 0.381)
			)
			(layers "F.Cu" "F.Mask" "F.Paste")
			(net "SSD5_PERST_N")
		)
		(pad "B83" smd rect
			(at 27.599894 -1.131062 90)
			(size 0.508 2.4892)
			(drill
				(offset 0 0.381)
			)
			(layers "F.Cu" "F.Mask" "F.Paste")
			(net "PEER_1A&2A_HB")
		)
		(pad "B84" smd rect
			(at 28.399994 -1.131062 90)
			(size 0.508 2.4892)
			(drill
				(offset 0 0.381)
			)
			(layers "F.Cu" "F.Mask" "F.Paste")
			(net "SELF_1A&2A_HB")
		)
		(pad "B85" smd rect
			(at 29.200094 -1.131062 90)
			(size 0.508 2.4892)
			(drill
				(offset 0 0.381)
			)
			(layers "F.Cu" "F.Mask" "F.Paste")
			(net "FCB_HW_REVISION")
		)
		(pad "B86" smd rect
			(at 29.99994 -1.131062 90)
			(size 0.508 2.4892)
			(drill
				(offset 0 0.381)
			)
			(layers "F.Cu" "F.Mask" "F.Paste")
			(net "DPB_HW_REVISION")
		)
		(pad "B87" smd rect
			(at 30.80004 -1.131062 90)
			(size 0.508 2.4892)
			(drill
				(offset 0 0.381)
			)
			(layers "F.Cu" "F.Mask" "F.Paste")
			(net "SELF_TRAY_PRESENT_R")
		)
		(pad "B88" smd rect
			(at 31.599886 -1.131062 90)
			(size 0.508 2.4892)
			(drill
				(offset 0 0.381)
			)
			(layers "F.Cu" "F.Mask" "F.Paste")
			(net "PEER_TRAY_PRESENT")
		)
		(pad "B89" smd rect
			(at 32.399986 -1.131062 90)
			(size 0.508 2.4892)
			(drill
				(offset 0 0.381)
			)
			(layers "F.Cu" "F.Mask" "F.Paste")
			(net "GND")
		)
		(pad "B90" smd rect
			(at 33.200086 -1.131062 90)
			(size 0.508 2.4892)
			(drill
				(offset 0 0.381)
			)
			(layers "F.Cu" "F.Mask" "F.Paste")
			(net "GND")
		)
		(pad "B91" smd rect
			(at 33.999932 -1.131062 90)
			(size 0.508 2.4892)
			(drill
				(offset 0 0.381)
			)
			(layers "F.Cu" "F.Mask" "F.Paste")
			(net "GND")
		)
		(pad "B92" smd rect
			(at 34.800032 -1.131062 90)
			(size 0.508 2.4892)
			(drill
				(offset 0 0.381)
			)
			(layers "F.Cu" "F.Mask" "F.Paste")
			(net "GND")
		)
		(pad "B93" smd rect
			(at 35.599878 -1.131062 90)
			(size 0.508 2.4892)
			(drill
				(offset 0 0.381)
			)
			(layers "F.Cu" "F.Mask" "F.Paste")
			(net "GND")
		)
		(pad "B94" smd rect
			(at 36.399978 -1.131062 90)
			(size 0.508 2.4892)
			(drill
				(offset 0 0.381)
			)
			(layers "F.Cu" "F.Mask" "F.Paste")
			(net "GND")
		)
		(pad "B95" smd rect
			(at 37.200078 -1.131062 90)
			(size 0.508 2.4892)
			(drill
				(offset 0 0.381)
			)
			(layers "F.Cu" "F.Mask" "F.Paste")
			(net "P12V")
		)
		(pad "B96" smd rect
			(at 37.999924 -1.131062 90)
			(size 0.508 2.4892)
			(drill
				(offset 0 0.381)
			)
			(layers "F.Cu" "F.Mask" "F.Paste")
			(net "P12V")
		)
		(pad "B97" smd rect
			(at 38.800024 -1.131062 90)
			(size 0.508 2.4892)
			(drill
				(offset 0 0.381)
			)
			(layers "F.Cu" "F.Mask" "F.Paste")
			(net "P12V")
		)
		(pad "B98" smd rect
			(at 39.600124 -1.131062 90)
			(size 0.508 2.4892)
			(drill
				(offset 0 0.381)
			)
			(layers "F.Cu" "F.Mask" "F.Paste")
			(net "P12V")
		)
		(pad "B99" smd rect
			(at 40.39997 -1.131062 90)
			(size 0.508 2.4892)
			(drill
				(offset 0 0.381)
			)
			(layers "F.Cu" "F.Mask" "F.Paste")
			(net "P12V")
		)
		(pad "B100" smd rect
			(at 41.20007 -1.131062 90)
			(size 0.508 2.4892)
			(drill
				(offset 0 0.381)
			)
			(layers "F.Cu" "F.Mask" "F.Paste")
			(net "P12V")
		)
		(zone
			(layers "F.Cu" "B.Cu" "In1.Cu" "In2.Cu" "In3.Cu" "In4.Cu" "In5.Cu" "In6.Cu")
			(hatch none 0.5)
			(connect_pads
				(clearance 0)
			)
			(min_thickness 0.25)
			(keepout
				(tracks not_allowed)
				(vias allowed)
				(pads allowed)
				(copperpour not_allowed)
				(footprints allowed)
			)
			(placement
				(enabled no)
				(sheetname "")
			)
			(fill
				(thermal_gap 0.5)
				(thermal_bridge_width 0.5)
				(island_removal_mode 0)
			)
			(polygon
				(pts
					(arc
						(start 4.409694 -473.141802)
						(mid 1.590294 -473.141802)
						(end 4.409694 -473.141802)
					)
				)
			)
		)
		(zone
			(layers "F.Cu" "B.Cu" "In1.Cu" "In2.Cu" "In3.Cu" "In4.Cu" "In5.Cu" "In6.Cu")
			(hatch none 0.5)
			(connect_pads
				(clearance 0)
			)
			(min_thickness 0.25)
			(keepout
				(tracks not_allowed)
				(vias allowed)
				(pads allowed)
				(copperpour not_allowed)
				(footprints allowed)
			)
			(placement
				(enabled no)
				(sheetname "")
			)
			(fill
				(thermal_gap 0.5)
				(thermal_bridge_width 0.5)
				(island_removal_mode 0)
			)
			(polygon
				(pts
					(arc
						(start 4.409694 -377.141994)
						(mid 1.590294 -377.141994)
						(end 4.409694 -377.141994)
					)
				)
			)
		)
	)
	(footprint ""
		(layer "F.Cu")
		(at 91.313 -110.236 180)
		(property "Reference" "R9061"
			(at 0 0 180)
			(layer "F.SilkS")
			(hide yes)
			(effects
				(font
					(size 1.27 1.27)
				)
			)
		)
		(property "Value" "27R2F-GP"
			(at 0.064008 -3.993896 180)
			(unlocked yes)
			(layer "F.Fab")
			(hide yes)
			(effects
				(font
					(size 1.016 1.016)
					(thickness 0.1524)
				)
			)
		)
		(property "Device Type" "R402H16"
			(at 0.064008 -5.517896 180)
			(unlocked yes)
			(layer "F.Fab")
			(hide yes)
			(effects
				(font
					(size 1.016 1.016)
					(thickness 0.1524)
				)
			)
		)
		(duplicate_pad_numbers_are_jumpers no)
		(fp_line
			(start 0.508 -0.9398)
			(end -0.508 -0.9398)
			(stroke
				(width 0.1524)
				(type default)
			)
			(layer "F.SilkS")
		)
		(fp_line
			(start -0.508 -0.9398)
			(end -0.508 0.9398)
			(stroke
				(width 0.1524)
				(type default)
			)
			(layer "F.SilkS")
		)
		(fp_rect
			(start -0.508 0.9398)
			(end 0.508 -0.9398)
			(stroke
				(width 0)
				(type default)
			)
			(fill no)
			(layer "F.CrtYd")
		)
		(fp_rect
			(start -0.508 0.9398)
			(end 0.508 -0.9398)
			(stroke
				(width 0)
				(type default)
			)
			(fill no)
			(layer "F.Fab")
		)
		(pad "1" smd custom
			(at 0 -0.4445 180)
			(size 0.1397 0.1397)
			(layers "F.Cu" "F.Mask" "F.Paste")
			(net "PE_CLK_100M_DR13_2_R_P")
			(options
				(clearance outline)
				(anchor circle)
			)
			(primitives
				(gr_poly
					(pts
						(arc
							(start -0.1778 -0.2794)
							(mid -0.249642 -0.249642)
							(end -0.2794 -0.1778)
						)
						(arc
							(start -0.2794 0.1778)
							(mid -0.249642 0.249642)
							(end -0.1778 0.2794)
						)
						(arc
							(start 0.1778 0.2794)
							(mid 0.249642 0.249642)
							(end 0.2794 0.1778)
						)
						(arc
							(start 0.2794 -0.1778)
							(mid 0.249642 -0.249642)
							(end 0.1778 -0.2794)
						)
					)
					(width 0)
					(fill yes)
				)
			)
		)
		(pad "2" smd custom
			(at 0 0.4445 180)
			(size 0.1397 0.1397)
			(layers "F.Cu" "F.Mask" "F.Paste")
			(net "PE_CLK100M_DR13_2_P")
			(options
				(clearance outline)
				(anchor circle)
			)
			(primitives
				(gr_poly
					(pts
						(arc
							(start -0.1778 -0.2794)
							(mid -0.249642 -0.249642)
							(end -0.2794 -0.1778)
						)
						(arc
							(start -0.2794 0.1778)
							(mid -0.249642 0.249642)
							(end -0.1778 0.2794)
						)
						(arc
							(start 0.1778 0.2794)
							(mid 0.249642 0.249642)
							(end 0.2794 0.1778)
						)
						(arc
							(start 0.2794 -0.1778)
							(mid 0.249642 -0.249642)
							(end 0.1778 -0.2794)
						)
					)
					(width 0)
					(fill yes)
				)
			)
		)
	)
	(footprint ""
		(layer "F.Cu")
		(at 55.2958 -451.1548 -90)
		(property "Reference" "R9917"
			(at 0 0 270)
			(layer "F.SilkS")
			(hide yes)
			(effects
				(font
					(size 1.27 1.27)
				)
			)
		)
		(property "Value" "47KR2J-2-GP"
			(at 0.064008 -3.993896 270)
			(unlocked yes)
			(layer "F.Fab")
			(hide yes)
			(effects
				(font
					(size 1.016 1.016)
					(thickness 0.1524)
				)
			)
		)
		(property "Device Type" "R402H16"
			(at 0.064008 -5.517896 270)
			(unlocked yes)
			(layer "F.Fab")
			(hide yes)
			(effects
				(font
					(size 1.016 1.016)
					(thickness 0.1524)
				)
			)
		)
		(duplicate_pad_numbers_are_jumpers no)
		(fp_line
			(start -0.508 -0.9398)
			(end -0.508 0.9398)
			(stroke
				(width 0.1524)
				(type default)
			)
			(layer "F.SilkS")
		)
		(fp_line
			(start 0.508 -0.9398)
			(end -0.508 -0.9398)
			(stroke
				(width 0.1524)
				(type default)
			)
			(layer "F.SilkS")
		)
		(fp_rect
			(start -0.508 0.9398)
			(end 0.508 -0.9398)
			(stroke
				(width 0)
				(type default)
			)
			(fill no)
			(layer "F.CrtYd")
		)
		(fp_rect
			(start -0.508 0.9398)
			(end 0.508 -0.9398)
			(stroke
				(width 0)
				(type default)
			)
			(fill no)
			(layer "F.Fab")
		)
		(pad "1" smd custom
			(at 0 -0.4445 270)
			(size 0.1397 0.1397)
			(layers "F.Cu" "F.Mask" "F.Paste")
			(net "P3V3")
			(options
				(clearance outline)
				(anchor circle)
			)
			(primitives
				(gr_poly
					(pts
						(arc
							(start -0.1778 -0.2794)
							(mid -0.249642 -0.249642)
							(end -0.2794 -0.1778)
						)
						(arc
							(start -0.2794 0.1778)
							(mid -0.249642 0.249642)
							(end -0.1778 0.2794)
						)
						(arc
							(start 0.1778 0.2794)
							(mid 0.249642 0.249642)
							(end 0.2794 0.1778)
						)
						(arc
							(start 0.2794 -0.1778)
							(mid 0.249642 -0.249642)
							(end 0.1778 -0.2794)
						)
					)
					(width 0)
					(fill yes)
				)
			)
		)
		(pad "2" smd custom
			(at 0 0.4445 270)
			(size 0.1397 0.1397)
			(layers "F.Cu" "F.Mask" "F.Paste")
			(net "ATTN_LED_DR5_N")
			(options
				(clearance outline)
				(anchor circle)
			)
			(primitives
				(gr_poly
					(pts
						(arc
							(start -0.1778 -0.2794)
							(mid -0.249642 -0.249642)
							(end -0.2794 -0.1778)
						)
						(arc
							(start -0.2794 0.1778)
							(mid -0.249642 0.249642)
							(end -0.1778 0.2794)
						)
						(arc
							(start 0.1778 0.2794)
							(mid 0.249642 0.249642)
							(end 0.2794 0.1778)
						)
						(arc
							(start 0.2794 -0.1778)
							(mid 0.249642 -0.249642)
							(end 0.1778 -0.2794)
						)
					)
					(width 0)
					(fill yes)
				)
			)
		)
	)
	(footprint ""
		(layer "F.Cu")
		(at 56.134 -447.04 180)
		(property "Reference" "Q54"
			(at 0 0 180)
			(layer "F.SilkS")
			(hide yes)
			(effects
				(font
					(size 1.27 1.27)
				)
			)
		)
		(property "Value" "2N7002A-7-GP"
			(at 0.127 -8.9662 180)
			(unlocked yes)
			(layer "F.Fab")
			(hide yes)
			(effects
				(font
					(size 1.016 1.016)
					(thickness 0.1524)
				)
			)
		)
		(property "Device Type" "SOT23DGS2D4H48"
			(at 0.127 -10.4902 180)
			(unlocked yes)
			(layer "F.Fab")
			(hide yes)
			(effects
				(font
					(size 1.016 1.016)
					(thickness 0.1524)
				)
			)
		)
		(duplicate_pad_numbers_are_jumpers no)
		(fp_line
			(start 1.651 1.778)
			(end 1.651 -1.778)
			(stroke
				(width 0.1524)
				(type default)
			)
			(layer "F.SilkS")
		)
		(fp_line
			(start 1.651 -1.778)
			(end -1.651 -1.778)
			(stroke
				(width 0.1524)
				(type default)
			)
			(layer "F.SilkS")
		)
		(fp_line
			(start -1.651 1.778)
			(end 1.651 1.778)
			(stroke
				(width 0.1524)
				(type default)
			)
			(layer "F.SilkS")
		)
		(fp_line
			(start -1.651 -1.778)
			(end -1.651 1.778)
			(stroke
				(width 0.1524)
				(type default)
			)
			(layer "F.SilkS")
		)
		(fp_poly
			(pts
				(xy -1.778 1.8796) (xy -1.778 -1.8796) (xy 1.778 -1.8796) (xy 1.778 1.8796)
			)
			(stroke
				(width 0)
				(type default)
			)
			(fill no)
			(layer "F.CrtYd")
		)
		(fp_poly
			(pts
				(xy -1.778 1.8796) (xy -1.778 -1.8796) (xy 1.778 -1.8796) (xy 1.778 1.8796)
			)
			(stroke
				(width 0)
				(type default)
			)
			(fill no)
			(layer "F.Fab")
		)
		(pad "D" smd custom
			(at 0 -0.9525 180)
			(size 0.1905 0.1905)
			(layers "F.Cu" "F.Mask" "F.Paste")
			(net "SSD5_CLK0_OE_MOS_N")
			(options
				(clearance outline)
				(anchor circle)
			)
			(primitives
				(gr_poly
					(pts
						(arc
							(start -0.1778 0.5715)
							(mid -0.321484 0.511984)
							(end -0.381 0.3683)
						)
						(arc
							(start -0.381 -0.3683)
							(mid -0.321484 -0.511984)
							(end -0.1778 -0.5715)
						)
						(arc
							(start 0.1778 -0.5715)
							(mid 0.321484 -0.511984)
							(end 0.381 -0.3683)
						)
						(arc
							(start 0.381 0.3683)
							(mid 0.321484 0.511984)
							(end 0.1778 0.5715)
						)
					)
					(width 0)
					(fill yes)
				)
			)
		)
		(pad "G" smd custom
			(at -0.98425 0.9525 180)
			(size 0.1905 0.1905)
			(layers "F.Cu" "F.Mask" "F.Paste")
			(net "SSD5_CLK0_OE_R_N")
			(options
				(clearance outline)
				(anchor circle)
			)
			(primitives
				(gr_poly
					(pts
						(arc
							(start -0.1778 0.5715)
							(mid -0.321484 0.511984)
							(end -0.381 0.3683)
						)
						(arc
							(start -0.381 -0.3683)
							(mid -0.321484 -0.511984)
							(end -0.1778 -0.5715)
						)
						(arc
							(start 0.1778 -0.5715)
							(mid 0.321484 -0.511984)
							(end 0.381 -0.3683)
						)
						(arc
							(start 0.381 0.3683)
							(mid 0.321484 0.511984)
							(end 0.1778 0.5715)
						)
					)
					(width 0)
					(fill yes)
				)
			)
		)
		(pad "S" smd custom
			(at 0.98425 0.9525 180)
			(size 0.1905 0.1905)
			(layers "F.Cu" "F.Mask" "F.Paste")
			(net "GND")
			(options
				(clearance outline)
				(anchor circle)
			)
			(primitives
				(gr_poly
					(pts
						(arc
							(start -0.1778 0.5715)
							(mid -0.321484 0.511984)
							(end -0.381 0.3683)
						)
						(arc
							(start -0.381 -0.3683)
							(mid -0.321484 -0.511984)
							(end -0.1778 -0.5715)
						)
						(arc
							(start 0.1778 -0.5715)
							(mid 0.321484 -0.511984)
							(end 0.381 -0.3683)
						)
						(arc
							(start 0.381 0.3683)
							(mid 0.321484 0.511984)
							(end 0.1778 0.5715)
						)
					)
					(width 0)
					(fill yes)
				)
			)
		)
	)
	(footprint ""
		(layer "F.Cu")
		(at 85.471 -430.53 -90)
		(property "Reference" "R9034"
			(at 0 0 270)
			(layer "F.SilkS")
			(hide yes)
			(effects
				(font
					(size 1.27 1.27)
				)
			)
		)
		(property "Value" "4K7R2F-GP"
			(at 0.064008 -3.993896 270)
			(unlocked yes)
			(layer "F.Fab")
			(hide yes)
			(effects
				(font
					(size 1.016 1.016)
					(thickness 0.1524)
				)
			)
		)
		(property "Device Type" "R402H16"
			(at 0.064008 -5.517896 270)
			(unlocked yes)
			(layer "F.Fab")
			(hide yes)
			(effects
				(font
					(size 1.016 1.016)
					(thickness 0.1524)
				)
			)
		)
		(duplicate_pad_numbers_are_jumpers no)
		(fp_line
			(start -0.508 -0.9398)
			(end -0.508 0.9398)
			(stroke
				(width 0.1524)
				(type default)
			)
			(layer "F.SilkS")
		)
		(fp_line
			(start 0.508 -0.9398)
			(end -0.508 -0.9398)
			(stroke
				(width 0.1524)
				(type default)
			)
			(layer "F.SilkS")
		)
		(fp_rect
			(start -0.508 0.9398)
			(end 0.508 -0.9398)
			(stroke
				(width 0)
				(type default)
			)
			(fill no)
			(layer "F.CrtYd")
		)
		(fp_rect
			(start -0.508 0.9398)
			(end 0.508 -0.9398)
			(stroke
				(width 0)
				(type default)
			)
			(fill no)
			(layer "F.Fab")
		)
		(pad "1" smd custom
			(at 0 -0.4445 270)
			(size 0.1397 0.1397)
			(layers "F.Cu" "F.Mask" "F.Paste")
			(net "CLK_BUF_EU1_SMB_A0_TRI")
			(options
				(clearance outline)
				(anchor circle)
			)
			(primitives
				(gr_poly
					(pts
						(arc
							(start -0.1778 -0.2794)
							(mid -0.249642 -0.249642)
							(end -0.2794 -0.1778)
						)
						(arc
							(start -0.2794 0.1778)
							(mid -0.249642 0.249642)
							(end -0.1778 0.2794)
						)
						(arc
							(start 0.1778 0.2794)
							(mid 0.249642 0.249642)
							(end 0.2794 0.1778)
						)
						(arc
							(start 0.2794 -0.1778)
							(mid 0.249642 -0.249642)
							(end 0.1778 -0.2794)
						)
					)
					(width 0)
					(fill yes)
				)
			)
		)
		(pad "2" smd custom
			(at 0 0.4445 270)
			(size 0.1397 0.1397)
			(layers "F.Cu" "F.Mask" "F.Paste")
			(net "GND")
			(options
				(clearance outline)
				(anchor circle)
			)
			(primitives
				(gr_poly
					(pts
						(arc
							(start -0.1778 -0.2794)
							(mid -0.249642 -0.249642)
							(end -0.2794 -0.1778)
						)
						(arc
							(start -0.2794 0.1778)
							(mid -0.249642 0.249642)
							(end -0.1778 0.2794)
						)
						(arc
							(start 0.1778 0.2794)
							(mid 0.249642 0.249642)
							(end 0.2794 0.1778)
						)
						(arc
							(start 0.2794 -0.1778)
							(mid 0.249642 -0.249642)
							(end 0.1778 -0.2794)
						)
					)
					(width 0)
					(fill yes)
				)
			)
		)
	)
	(footprint ""
		(layer "F.Cu")
		(at 32.2326 -108.1024 90)
		(property "Reference" "U22"
			(at 0 0 90)
			(layer "F.SilkS")
			(hide yes)
			(effects
				(font
					(size 1.27 1.27)
				)
			)
		)
		(property "Value" "P2003EVG-GP"
			(at 0 -11.1252 90)
			(unlocked yes)
			(layer "F.Fab")
			(hide yes)
			(effects
				(font
					(size 1.016 1.016)
					(thickness 0.1524)
				)
			)
		)
		(property "Device Type" "SOIC8H79"
			(at 0 -12.6492 90)
			(unlocked yes)
			(layer "F.Fab")
			(hide yes)
			(effects
				(font
					(size 1.016 1.016)
					(thickness 0.1524)
				)
			)
		)
		(duplicate_pad_numbers_are_jumpers no)
		(fp_line
			(start 2.1336 -1.4224)
			(end -2.7432 -1.4224)
			(stroke
				(width 0.1524)
				(type default)
			)
			(layer "F.SilkS")
		)
		(fp_line
			(start -2.7432 -1.4224)
			(end -2.7432 1.4224)
			(stroke
				(width 0.1524)
				(type default)
			)
			(layer "F.SilkS")
		)
		(fp_line
			(start -2.7432 -0.508)
			(end -2.2352 0)
			(stroke
				(width 0.1524)
				(type default)
			)
			(layer "F.SilkS")
		)
		(fp_line
			(start -2.2352 0)
			(end -2.7432 0.508)
			(stroke
				(width 0.1524)
				(type default)
			)
			(layer "F.SilkS")
		)
		(fp_line
			(start 2.1336 1.4224)
			(end 2.1336 -1.4224)
			(stroke
				(width 0.1524)
				(type default)
			)
			(layer "F.SilkS")
		)
		(fp_line
			(start -2.7432 1.4224)
			(end 2.1336 1.4224)
			(stroke
				(width 0.1524)
				(type default)
			)
			(layer "F.SilkS")
		)
		(fp_line
			(start -2.6162 3.429)
			(end -2.6162 1.4732)
			(stroke
				(width 0.4064)
				(type default)
			)
			(layer "F.SilkS")
		)
		(fp_poly
			(pts
				(xy 2.2098 -1.4224) (xy 2.2098 1.4224) (xy -2.2225 1.4224) (xy -2.2225 -1.4224)
			)
			(stroke
				(width 0)
				(type default)
			)
			(fill yes)
			(layer "F.SilkS")
		)
		(fp_rect
			(start -2.4511 2.9972)
			(end 2.4511 -2.9972)
			(stroke
				(width 0)
				(type default)
			)
			(fill no)
			(layer "F.CrtYd")
		)
		(fp_poly
			(pts
				(xy -2.8194 3.6322) (xy -2.8194 -3.6322) (xy 2.8194 -3.6322) (xy 2.8194 -2.2987) (xy 2.4511 -2.2987)
				(xy 2.4511 -2.9972) (xy -2.4511 -2.9972) (xy -2.4511 2.9972) (xy 2.4511 2.9972) (xy 2.4511 -2.286)
				(xy 2.8194 -2.286) (xy 2.8194 3.6322)
			)
			(stroke
				(width 0)
				(type default)
			)
			(fill no)
			(layer "F.CrtYd")
		)
		(fp_rect
			(start -2.8194 3.6322)
			(end 2.8194 -3.6322)
			(stroke
				(width 0)
				(type default)
			)
			(fill no)
			(layer "F.Fab")
		)
		(pad "1" smd rect
			(at -1.905 2.54 90)
			(size 0.635 1.651)
			(layers "F.Cu" "F.Mask" "F.Paste")
			(net "P12V")
		)
		(pad "2" smd rect
			(at -0.635 2.54 90)
			(size 0.635 1.651)
			(layers "F.Cu" "F.Mask" "F.Paste")
			(net "P12V")
		)
		(pad "3" smd rect
			(at 0.635 2.54 90)
			(size 0.635 1.651)
			(layers "F.Cu" "F.Mask" "F.Paste")
			(net "P12V")
		)
		(pad "4" smd rect
			(at 1.905 2.54 90)
			(size 0.635 1.651)
			(layers "F.Cu" "F.Mask" "F.Paste")
			(net "SW_SSD13_N")
		)
		(pad "5" smd rect
			(at 1.905 -2.54 90)
			(size 0.635 1.651)
			(layers "F.Cu" "F.Mask" "F.Paste")
			(net "P12V_SSD13")
		)
		(pad "6" smd rect
			(at 0.635 -2.54 90)
			(size 0.635 1.651)
			(layers "F.Cu" "F.Mask" "F.Paste")
			(net "P12V_SSD13")
		)
		(pad "7" smd rect
			(at -0.635 -2.54 90)
			(size 0.635 1.651)
			(layers "F.Cu" "F.Mask" "F.Paste")
			(net "P12V_SSD13")
		)
		(pad "8" smd rect
			(at -1.905 -2.54 90)
			(size 0.635 1.651)
			(layers "F.Cu" "F.Mask" "F.Paste")
			(net "P12V_SSD13")
		)
	)
	(footprint ""
		(layer "F.Cu")
		(at 82.931 -211.9376 90)
		(property "Reference" "R9355"
			(at 0 0 90)
			(layer "F.SilkS")
			(hide yes)
			(effects
				(font
					(size 1.27 1.27)
				)
			)
		)
		(property "Value" "2D2R2F-GP"
			(at 0.064008 -3.993896 90)
			(unlocked yes)
			(layer "F.Fab")
			(hide yes)
			(effects
				(font
					(size 1.016 1.016)
					(thickness 0.1524)
				)
			)
		)
		(property "Device Type" "R402H16"
			(at 0.064008 -5.517896 90)
			(unlocked yes)
			(layer "F.Fab")
			(hide yes)
			(effects
				(font
					(size 1.016 1.016)
					(thickness 0.1524)
				)
			)
		)
		(duplicate_pad_numbers_are_jumpers no)
		(fp_line
			(start 0.508 -0.9398)
			(end -0.508 -0.9398)
			(stroke
				(width 0.1524)
				(type default)
			)
			(layer "F.SilkS")
		)
		(fp_line
			(start -0.508 -0.9398)
			(end -0.508 0.9398)
			(stroke
				(width 0.1524)
				(type default)
			)
			(layer "F.SilkS")
		)
		(fp_rect
			(start -0.508 0.9398)
			(end 0.508 -0.9398)
			(stroke
				(width 0)
				(type default)
			)
			(fill no)
			(layer "F.CrtYd")
		)
		(fp_rect
			(start -0.508 0.9398)
			(end 0.508 -0.9398)
			(stroke
				(width 0)
				(type default)
			)
			(fill no)
			(layer "F.Fab")
		)
		(pad "1" smd custom
			(at 0 -0.4445 90)
			(size 0.1397 0.1397)
			(layers "F.Cu" "F.Mask" "F.Paste")
			(net "VDD_DIFF_3")
			(options
				(clearance outline)
				(anchor circle)
			)
			(primitives
				(gr_poly
					(pts
						(arc
							(start -0.1778 -0.2794)
							(mid -0.249642 -0.249642)
							(end -0.2794 -0.1778)
						)
						(arc
							(start -0.2794 0.1778)
							(mid -0.249642 0.249642)
							(end -0.1778 0.2794)
						)
						(arc
							(start 0.1778 0.2794)
							(mid 0.249642 0.249642)
							(end 0.2794 0.1778)
						)
						(arc
							(start 0.2794 -0.1778)
							(mid 0.249642 -0.249642)
							(end 0.1778 -0.2794)
						)
					)
					(width 0)
					(fill yes)
				)
			)
		)
		(pad "2" smd custom
			(at 0 0.4445 90)
			(size 0.1397 0.1397)
			(layers "F.Cu" "F.Mask" "F.Paste")
			(net "VDDR_3")
			(options
				(clearance outline)
				(anchor circle)
			)
			(primitives
				(gr_poly
					(pts
						(arc
							(start -0.1778 -0.2794)
							(mid -0.249642 -0.249642)
							(end -0.2794 -0.1778)
						)
						(arc
							(start -0.2794 0.1778)
							(mid -0.249642 0.249642)
							(end -0.1778 0.2794)
						)
						(arc
							(start 0.1778 0.2794)
							(mid 0.249642 0.249642)
							(end 0.2794 0.1778)
						)
						(arc
							(start 0.2794 -0.1778)
							(mid 0.249642 -0.249642)
							(end 0.1778 -0.2794)
						)
					)
					(width 0)
					(fill yes)
				)
			)
		)
	)
	(footprint ""
		(layer "F.Cu")
		(at 30.607 -308.0004 90)
		(property "Reference" "Q81"
			(at 0 0 90)
			(layer "F.SilkS")
			(hide yes)
			(effects
				(font
					(size 1.27 1.27)
				)
			)
		)
		(property "Value" "2N7002A-7-GP"
			(at 0.127 -8.9662 90)
			(unlocked yes)
			(layer "F.Fab")
			(hide yes)
			(effects
				(font
					(size 1.016 1.016)
					(thickness 0.1524)
				)
			)
		)
		(property "Device Type" "SOT23DGS2D4H48"
			(at 0.127 -10.4902 90)
			(unlocked yes)
			(layer "F.Fab")
			(hide yes)
			(effects
				(font
					(size 1.016 1.016)
					(thickness 0.1524)
				)
			)
		)
		(duplicate_pad_numbers_are_jumpers no)
		(fp_line
			(start 1.651 -1.778)
			(end -1.651 -1.778)
			(stroke
				(width 0.1524)
				(type default)
			)
			(layer "F.SilkS")
		)
		(fp_line
			(start -1.651 -1.778)
			(end -1.651 1.778)
			(stroke
				(width 0.1524)
				(type default)
			)
			(layer "F.SilkS")
		)
		(fp_line
			(start 1.651 1.778)
			(end 1.651 -1.778)
			(stroke
				(width 0.1524)
				(type default)
			)
			(layer "F.SilkS")
		)
		(fp_line
			(start -1.651 1.778)
			(end 1.651 1.778)
			(stroke
				(width 0.1524)
				(type default)
			)
			(layer "F.SilkS")
		)
		(fp_poly
			(pts
				(xy -1.778 1.8796) (xy -1.778 -1.8796) (xy 1.778 -1.8796) (xy 1.778 1.8796)
			)
			(stroke
				(width 0)
				(type default)
			)
			(fill no)
			(layer "F.CrtYd")
		)
		(fp_poly
			(pts
				(xy -1.778 1.8796) (xy -1.778 -1.8796) (xy 1.778 -1.8796) (xy 1.778 1.8796)
			)
			(stroke
				(width 0)
				(type default)
			)
			(fill no)
			(layer "F.Fab")
		)
		(pad "D" smd custom
			(at 0 -0.9525 90)
			(size 0.1905 0.1905)
			(layers "F.Cu" "F.Mask" "F.Paste")
			(net "P12V_MOST11_GATE_D")
			(options
				(clearance outline)
				(anchor circle)
			)
			(primitives
				(gr_poly
					(pts
						(arc
							(start -0.1778 0.5715)
							(mid -0.321484 0.511984)
							(end -0.381 0.3683)
						)
						(arc
							(start -0.381 -0.3683)
							(mid -0.321484 -0.511984)
							(end -0.1778 -0.5715)
						)
						(arc
							(start 0.1778 -0.5715)
							(mid 0.321484 -0.511984)
							(end 0.381 -0.3683)
						)
						(arc
							(start 0.381 0.3683)
							(mid 0.321484 0.511984)
							(end 0.1778 0.5715)
						)
					)
					(width 0)
					(fill yes)
				)
			)
		)
		(pad "G" smd custom
			(at -0.98425 0.9525 90)
			(size 0.1905 0.1905)
			(layers "F.Cu" "F.Mask" "F.Paste")
			(net "P12V_MOST11_GATE")
			(options
				(clearance outline)
				(anchor circle)
			)
			(primitives
				(gr_poly
					(pts
						(arc
							(start -0.1778 0.5715)
							(mid -0.321484 0.511984)
							(end -0.381 0.3683)
						)
						(arc
							(start -0.381 -0.3683)
							(mid -0.321484 -0.511984)
							(end -0.1778 -0.5715)
						)
						(arc
							(start 0.1778 -0.5715)
							(mid 0.321484 -0.511984)
							(end 0.381 -0.3683)
						)
						(arc
							(start 0.381 0.3683)
							(mid 0.321484 0.511984)
							(end 0.1778 0.5715)
						)
					)
					(width 0)
					(fill yes)
				)
			)
		)
		(pad "S" smd custom
			(at 0.98425 0.9525 90)
			(size 0.1905 0.1905)
			(layers "F.Cu" "F.Mask" "F.Paste")
			(net "GND")
			(options
				(clearance outline)
				(anchor circle)
			)
			(primitives
				(gr_poly
					(pts
						(arc
							(start -0.1778 0.5715)
							(mid -0.321484 0.511984)
							(end -0.381 0.3683)
						)
						(arc
							(start -0.381 -0.3683)
							(mid -0.321484 -0.511984)
							(end -0.1778 -0.5715)
						)
						(arc
							(start 0.1778 -0.5715)
							(mid 0.321484 -0.511984)
							(end 0.381 -0.3683)
						)
						(arc
							(start 0.381 0.3683)
							(mid 0.321484 0.511984)
							(end 0.1778 0.5715)
						)
					)
					(width 0)
					(fill yes)
				)
			)
		)
	)
	(footprint ""
		(layer "F.Cu")
		(at 208.153 -396.113)
		(property "Reference" "R552"
			(at 0 0 0)
			(layer "F.SilkS")
			(hide yes)
			(effects
				(font
					(size 1.27 1.27)
				)
			)
		)
		(property "Value" "200KR2F-L-GP"
			(at 0.064008 -3.993896 0)
			(unlocked yes)
			(layer "F.Fab")
			(hide yes)
			(effects
				(font
					(size 1.016 1.016)
					(thickness 0.1524)
				)
			)
		)
		(property "Device Type" "R402H16"
			(at 0.064008 -5.517896 0)
			(unlocked yes)
			(layer "F.Fab")
			(hide yes)
			(effects
				(font
					(size 1.016 1.016)
					(thickness 0.1524)
				)
			)
		)
		(duplicate_pad_numbers_are_jumpers no)
		(fp_line
			(start -0.508 -0.9398)
			(end -0.508 0.9398)
			(stroke
				(width 0.1524)
				(type default)
			)
			(layer "F.SilkS")
		)
		(fp_line
			(start 0.508 -0.9398)
			(end -0.508 -0.9398)
			(stroke
				(width 0.1524)
				(type default)
			)
			(layer "F.SilkS")
		)
		(fp_rect
			(start -0.508 0.9398)
			(end 0.508 -0.9398)
			(stroke
				(width 0)
				(type default)
			)
			(fill no)
			(layer "F.CrtYd")
		)
		(fp_rect
			(start -0.508 0.9398)
			(end 0.508 -0.9398)
			(stroke
				(width 0)
				(type default)
			)
			(fill no)
			(layer "F.Fab")
		)
		(pad "1" smd custom
			(at 0 -0.4445)
			(size 0.1397 0.1397)
			(layers "F.Cu" "F.Mask" "F.Paste")
			(net "SW_SSD1_R")
			(options
				(clearance outline)
				(anchor circle)
			)
			(primitives
				(gr_poly
					(pts
						(arc
							(start -0.1778 -0.2794)
							(mid -0.249642 -0.249642)
							(end -0.2794 -0.1778)
						)
						(arc
							(start -0.2794 0.1778)
							(mid -0.249642 0.249642)
							(end -0.1778 0.2794)
						)
						(arc
							(start 0.1778 0.2794)
							(mid 0.249642 0.249642)
							(end 0.2794 0.1778)
						)
						(arc
							(start 0.2794 -0.1778)
							(mid 0.249642 -0.249642)
							(end 0.1778 -0.2794)
						)
					)
					(width 0)
					(fill yes)
				)
			)
		)
		(pad "2" smd custom
			(at 0 0.4445)
			(size 0.1397 0.1397)
			(layers "F.Cu" "F.Mask" "F.Paste")
			(net "SW_SSD1_N")
			(options
				(clearance outline)
				(anchor circle)
			)
			(primitives
				(gr_poly
					(pts
						(arc
							(start -0.1778 -0.2794)
							(mid -0.249642 -0.249642)
							(end -0.2794 -0.1778)
						)
						(arc
							(start -0.2794 0.1778)
							(mid -0.249642 0.249642)
							(end -0.1778 0.2794)
						)
						(arc
							(start 0.1778 0.2794)
							(mid 0.249642 0.249642)
							(end 0.2794 0.1778)
						)
						(arc
							(start 0.2794 -0.1778)
							(mid 0.249642 -0.249642)
							(end 0.1778 -0.2794)
						)
					)
					(width 0)
					(fill yes)
				)
			)
		)
	)
	(footprint ""
		(layer "F.Cu")
		(at 29.972 -374.65 180)
		(property "Reference" "R332"
			(at 0 0 180)
			(layer "F.SilkS")
			(hide yes)
			(effects
				(font
					(size 1.27 1.27)
				)
			)
		)
		(property "Value" "4K7R2J-2-GP"
			(at 0.064008 -3.993896 180)
			(unlocked yes)
			(layer "F.Fab")
			(hide yes)
			(effects
				(font
					(size 1.016 1.016)
					(thickness 0.1524)
				)
			)
		)
		(property "Device Type" "R402H16"
			(at 0.064008 -5.517896 180)
			(unlocked yes)
			(layer "F.Fab")
			(hide yes)
			(effects
				(font
					(size 1.016 1.016)
					(thickness 0.1524)
				)
			)
		)
		(duplicate_pad_numbers_are_jumpers no)
		(fp_line
			(start 0.508 -0.9398)
			(end -0.508 -0.9398)
			(stroke
				(width 0.1524)
				(type default)
			)
			(layer "F.SilkS")
		)
		(fp_line
			(start -0.508 -0.9398)
			(end -0.508 0.9398)
			(stroke
				(width 0.1524)
				(type default)
			)
			(layer "F.SilkS")
		)
		(fp_rect
			(start -0.508 0.9398)
			(end 0.508 -0.9398)
			(stroke
				(width 0)
				(type default)
			)
			(fill no)
			(layer "F.CrtYd")
		)
		(fp_rect
			(start -0.508 0.9398)
			(end 0.508 -0.9398)
			(stroke
				(width 0)
				(type default)
			)
			(fill no)
			(layer "F.Fab")
		)
		(pad "1" smd custom
			(at 0 -0.4445 180)
			(size 0.1397 0.1397)
			(layers "F.Cu" "F.Mask" "F.Paste")
			(net "P3V3")
			(options
				(clearance outline)
				(anchor circle)
			)
			(primitives
				(gr_poly
					(pts
						(arc
							(start -0.1778 -0.2794)
							(mid -0.249642 -0.249642)
							(end -0.2794 -0.1778)
						)
						(arc
							(start -0.2794 0.1778)
							(mid -0.249642 0.249642)
							(end -0.1778 0.2794)
						)
						(arc
							(start 0.1778 0.2794)
							(mid 0.249642 0.249642)
							(end 0.2794 0.1778)
						)
						(arc
							(start 0.2794 -0.1778)
							(mid 0.249642 -0.249642)
							(end 0.1778 -0.2794)
						)
					)
					(width 0)
					(fill yes)
				)
			)
		)
		(pad "2" smd custom
			(at 0 0.4445 180)
			(size 0.1397 0.1397)
			(layers "F.Cu" "F.Mask" "F.Paste")
			(net "I2C_B_TMP4_A1")
			(options
				(clearance outline)
				(anchor circle)
			)
			(primitives
				(gr_poly
					(pts
						(arc
							(start -0.1778 -0.2794)
							(mid -0.249642 -0.249642)
							(end -0.2794 -0.1778)
						)
						(arc
							(start -0.2794 0.1778)
							(mid -0.249642 0.249642)
							(end -0.1778 0.2794)
						)
						(arc
							(start 0.1778 0.2794)
							(mid 0.249642 0.249642)
							(end 0.2794 0.1778)
						)
						(arc
							(start 0.2794 -0.1778)
							(mid 0.249642 -0.249642)
							(end 0.1778 -0.2794)
						)
					)
					(width 0)
					(fill yes)
				)
			)
		)
	)
	(footprint ""
		(layer "F.Cu")
		(at 106.045 -308.229 180)
		(property "Reference" "C9353"
			(at 0 0 180)
			(layer "F.SilkS")
			(hide yes)
			(effects
				(font
					(size 1.27 1.27)
				)
			)
		)
		(property "Value" "SC1KP50V2KX-1GP"
			(at 1.1811 -2.7051 180)
			(unlocked yes)
			(layer "F.Fab")
			(hide yes)
			(effects
				(font
					(size 1.016 1.016)
					(thickness 0.1524)
				)
			)
		)
		(property "Device Type" "C402H22"
			(at 1.1811 -4.2291 180)
			(unlocked yes)
			(layer "F.Fab")
			(hide yes)
			(effects
				(font
					(size 1.016 1.016)
					(thickness 0.1524)
				)
			)
		)
		(duplicate_pad_numbers_are_jumpers no)
		(fp_rect
			(start -0.4318 0.9525)
			(end 0.4318 -0.9525)
			(stroke
				(width 0)
				(type default)
			)
			(fill no)
			(layer "F.CrtYd")
		)
		(fp_rect
			(start -0.4318 0.9525)
			(end 0.4318 -0.9525)
			(stroke
				(width 0)
				(type default)
			)
			(fill no)
			(layer "F.Fab")
		)
		(pad "1" smd custom
			(at 0 -0.4445 180)
			(size 0.1524 0.1524)
			(layers "F.Cu" "F.Mask" "F.Paste")
			(net "SSD_PRSNT1")
			(options
				(clearance outline)
				(anchor circle)
			)
			(primitives
				(gr_poly
					(pts
						(arc
							(start 0.3048 -0.2032)
							(mid 0.275042 -0.275042)
							(end 0.2032 -0.3048)
						)
						(arc
							(start -0.2032 -0.3048)
							(mid -0.275042 -0.275042)
							(end -0.3048 -0.2032)
						)
						(arc
							(start -0.3048 0.2032)
							(mid -0.275042 0.275042)
							(end -0.2032 0.3048)
						)
						(arc
							(start 0.2032 0.3048)
							(mid 0.275042 0.275042)
							(end 0.3048 0.2032)
						)
					)
					(width 0)
					(fill yes)
				)
			)
		)
		(pad "2" smd custom
			(at 0 0.4445 180)
			(size 0.1524 0.1524)
			(layers "F.Cu" "F.Mask" "F.Paste")
			(net "GND")
			(options
				(clearance outline)
				(anchor circle)
			)
			(primitives
				(gr_poly
					(pts
						(arc
							(start 0.3048 -0.2032)
							(mid 0.275042 -0.275042)
							(end 0.2032 -0.3048)
						)
						(arc
							(start -0.2032 -0.3048)
							(mid -0.275042 -0.275042)
							(end -0.3048 -0.2032)
						)
						(arc
							(start -0.3048 0.2032)
							(mid -0.275042 0.275042)
							(end -0.2032 0.3048)
						)
						(arc
							(start 0.2032 0.3048)
							(mid 0.275042 0.275042)
							(end 0.3048 0.2032)
						)
					)
					(width 0)
					(fill yes)
				)
			)
		)
	)
	(footprint ""
		(layer "F.Cu")
		(at 99.949 -299.593 180)
		(property "Reference" "C8850"
			(at 0 0 180)
			(layer "F.SilkS")
			(hide yes)
			(effects
				(font
					(size 1.27 1.27)
				)
			)
		)
		(property "Value" "SCD1U16V2KX-3GP"
			(at 1.1811 -2.7051 180)
			(unlocked yes)
			(layer "F.Fab")
			(hide yes)
			(effects
				(font
					(size 1.016 1.016)
					(thickness 0.1524)
				)
			)
		)
		(property "Device Type" "C402H22"
			(at 1.1811 -4.2291 180)
			(unlocked yes)
			(layer "F.Fab")
			(hide yes)
			(effects
				(font
					(size 1.016 1.016)
					(thickness 0.1524)
				)
			)
		)
		(duplicate_pad_numbers_are_jumpers no)
		(fp_rect
			(start -0.4318 0.9525)
			(end 0.4318 -0.9525)
			(stroke
				(width 0)
				(type default)
			)
			(fill no)
			(layer "F.CrtYd")
		)
		(fp_rect
			(start -0.4318 0.9525)
			(end 0.4318 -0.9525)
			(stroke
				(width 0)
				(type default)
			)
			(fill no)
			(layer "F.Fab")
		)
		(pad "1" smd custom
			(at 0 -0.4445 180)
			(size 0.1524 0.1524)
			(layers "F.Cu" "F.Mask" "F.Paste")
			(net "VDD_IO_2")
			(options
				(clearance outline)
				(anchor circle)
			)
			(primitives
				(gr_poly
					(pts
						(arc
							(start 0.3048 -0.2032)
							(mid 0.275042 -0.275042)
							(end 0.2032 -0.3048)
						)
						(arc
							(start -0.2032 -0.3048)
							(mid -0.275042 -0.275042)
							(end -0.3048 -0.2032)
						)
						(arc
							(start -0.3048 0.2032)
							(mid -0.275042 0.275042)
							(end -0.2032 0.3048)
						)
						(arc
							(start 0.2032 0.3048)
							(mid 0.275042 0.275042)
							(end 0.3048 0.2032)
						)
					)
					(width 0)
					(fill yes)
				)
			)
		)
		(pad "2" smd custom
			(at 0 0.4445 180)
			(size 0.1524 0.1524)
			(layers "F.Cu" "F.Mask" "F.Paste")
			(net "GND")
			(options
				(clearance outline)
				(anchor circle)
			)
			(primitives
				(gr_poly
					(pts
						(arc
							(start 0.3048 -0.2032)
							(mid 0.275042 -0.275042)
							(end 0.2032 -0.3048)
						)
						(arc
							(start -0.2032 -0.3048)
							(mid -0.275042 -0.275042)
							(end -0.3048 -0.2032)
						)
						(arc
							(start -0.3048 0.2032)
							(mid -0.275042 0.275042)
							(end -0.2032 0.3048)
						)
						(arc
							(start 0.2032 0.3048)
							(mid 0.275042 0.275042)
							(end 0.3048 0.2032)
						)
					)
					(width 0)
					(fill yes)
				)
			)
		)
	)
	(footprint ""
		(layer "F.Cu")
		(at 99.187 -224.282)
		(property "Reference" "R9602"
			(at 0 0 0)
			(layer "F.SilkS")
			(hide yes)
			(effects
				(font
					(size 1.27 1.27)
				)
			)
		)
		(property "Value" "10R2F-L-GP"
			(at 0.064008 -3.993896 0)
			(unlocked yes)
			(layer "F.Fab")
			(hide yes)
			(effects
				(font
					(size 1.016 1.016)
					(thickness 0.1524)
				)
			)
		)
		(property "Device Type" "R402H14"
			(at 0.064008 -5.517896 0)
			(unlocked yes)
			(layer "F.Fab")
			(hide yes)
			(effects
				(font
					(size 1.016 1.016)
					(thickness 0.1524)
				)
			)
		)
		(duplicate_pad_numbers_are_jumpers no)
		(fp_line
			(start -0.508 -0.9398)
			(end -0.508 0.9398)
			(stroke
				(width 0.1524)
				(type default)
			)
			(layer "F.SilkS")
		)
		(fp_line
			(start 0.508 -0.9398)
			(end -0.508 -0.9398)
			(stroke
				(width 0.1524)
				(type default)
			)
			(layer "F.SilkS")
		)
		(fp_rect
			(start -0.508 0.9398)
			(end 0.508 -0.9398)
			(stroke
				(width 0)
				(type default)
			)
			(fill no)
			(layer "F.CrtYd")
		)
		(fp_rect
			(start -0.508 0.9398)
			(end 0.508 -0.9398)
			(stroke
				(width 0)
				(type default)
			)
			(fill no)
			(layer "F.Fab")
		)
		(pad "1" smd custom
			(at 0 -0.4445)
			(size 0.1397 0.1397)
			(layers "F.Cu" "F.Mask" "F.Paste")
			(net "SSD_PRSNT_NET7")
			(options
				(clearance outline)
				(anchor circle)
			)
			(primitives
				(gr_poly
					(pts
						(arc
							(start -0.1778 -0.2794)
							(mid -0.249642 -0.249642)
							(end -0.2794 -0.1778)
						)
						(arc
							(start -0.2794 0.1778)
							(mid -0.249642 0.249642)
							(end -0.1778 0.2794)
						)
						(arc
							(start 0.1778 0.2794)
							(mid 0.249642 0.249642)
							(end 0.2794 0.1778)
						)
						(arc
							(start 0.2794 -0.1778)
							(mid 0.249642 -0.249642)
							(end 0.1778 -0.2794)
						)
					)
					(width 0)
					(fill yes)
				)
			)
		)
		(pad "2" smd custom
			(at 0 0.4445)
			(size 0.1397 0.1397)
			(layers "F.Cu" "F.Mask" "F.Paste")
			(net "SSD_PRSNT7")
			(options
				(clearance outline)
				(anchor circle)
			)
			(primitives
				(gr_poly
					(pts
						(arc
							(start -0.1778 -0.2794)
							(mid -0.249642 -0.249642)
							(end -0.2794 -0.1778)
						)
						(arc
							(start -0.2794 0.1778)
							(mid -0.249642 0.249642)
							(end -0.1778 0.2794)
						)
						(arc
							(start 0.1778 0.2794)
							(mid 0.249642 0.249642)
							(end 0.2794 0.1778)
						)
						(arc
							(start 0.2794 -0.1778)
							(mid 0.249642 -0.249642)
							(end 0.1778 -0.2794)
						)
					)
					(width 0)
					(fill yes)
				)
			)
		)
	)
	(footprint ""
		(layer "F.Cu")
		(at 88.519 -31.877 180)
		(property "Reference" "R379"
			(at 0 0 180)
			(layer "F.SilkS")
			(hide yes)
			(effects
				(font
					(size 1.27 1.27)
				)
			)
		)
		(property "Value" "0R2J-2-GP"
			(at 0.064008 -3.993896 180)
			(unlocked yes)
			(layer "F.Fab")
			(hide yes)
			(effects
				(font
					(size 1.016 1.016)
					(thickness 0.1524)
				)
			)
		)
		(property "Device Type" "R402H16"
			(at 0.064008 -5.517896 180)
			(unlocked yes)
			(layer "F.Fab")
			(hide yes)
			(effects
				(font
					(size 1.016 1.016)
					(thickness 0.1524)
				)
			)
		)
		(duplicate_pad_numbers_are_jumpers no)
		(fp_line
			(start 0.508 -0.9398)
			(end -0.508 -0.9398)
			(stroke
				(width 0.1524)
				(type default)
			)
			(layer "F.SilkS")
		)
		(fp_line
			(start -0.508 -0.9398)
			(end -0.508 0.9398)
			(stroke
				(width 0.1524)
				(type default)
			)
			(layer "F.SilkS")
		)
		(fp_rect
			(start -0.508 0.9398)
			(end 0.508 -0.9398)
			(stroke
				(width 0)
				(type default)
			)
			(fill no)
			(layer "F.CrtYd")
		)
		(fp_rect
			(start -0.508 0.9398)
			(end 0.508 -0.9398)
			(stroke
				(width 0)
				(type default)
			)
			(fill no)
			(layer "F.Fab")
		)
		(pad "1" smd custom
			(at 0 -0.4445 180)
			(size 0.1397 0.1397)
			(layers "F.Cu" "F.Mask" "F.Paste")
			(net "VOL_SEN_SCL")
			(options
				(clearance outline)
				(anchor circle)
			)
			(primitives
				(gr_poly
					(pts
						(arc
							(start -0.1778 -0.2794)
							(mid -0.249642 -0.249642)
							(end -0.2794 -0.1778)
						)
						(arc
							(start -0.2794 0.1778)
							(mid -0.249642 0.249642)
							(end -0.1778 0.2794)
						)
						(arc
							(start 0.1778 0.2794)
							(mid 0.249642 0.249642)
							(end 0.2794 0.1778)
						)
						(arc
							(start 0.2794 -0.1778)
							(mid 0.249642 -0.249642)
							(end 0.1778 -0.2794)
						)
					)
					(width 0)
					(fill yes)
				)
			)
		)
		(pad "2" smd custom
			(at 0 0.4445 180)
			(size 0.1397 0.1397)
			(layers "F.Cu" "F.Mask" "F.Paste")
			(net "I2C_B_SCL")
			(options
				(clearance outline)
				(anchor circle)
			)
			(primitives
				(gr_poly
					(pts
						(arc
							(start -0.1778 -0.2794)
							(mid -0.249642 -0.249642)
							(end -0.2794 -0.1778)
						)
						(arc
							(start -0.2794 0.1778)
							(mid -0.249642 0.249642)
							(end -0.1778 0.2794)
						)
						(arc
							(start 0.1778 0.2794)
							(mid 0.249642 0.249642)
							(end 0.2794 0.1778)
						)
						(arc
							(start 0.2794 -0.1778)
							(mid 0.249642 -0.249642)
							(end 0.1778 -0.2794)
						)
					)
					(width 0)
					(fill yes)
				)
			)
		)
	)
	(footprint ""
		(layer "F.Cu")
		(at 51.562 -138.303)
		(property "Reference" "R322"
			(at 0 0 0)
			(layer "F.SilkS")
			(hide yes)
			(effects
				(font
					(size 1.27 1.27)
				)
			)
		)
		(property "Value" "4K7R2J-2-GP"
			(at 0.064008 -3.993896 0)
			(unlocked yes)
			(layer "F.Fab")
			(hide yes)
			(effects
				(font
					(size 1.016 1.016)
					(thickness 0.1524)
				)
			)
		)
		(property "Device Type" "R402H16"
			(at 0.064008 -5.517896 0)
			(unlocked yes)
			(layer "F.Fab")
			(hide yes)
			(effects
				(font
					(size 1.016 1.016)
					(thickness 0.1524)
				)
			)
		)
		(duplicate_pad_numbers_are_jumpers no)
		(fp_line
			(start -0.508 -0.9398)
			(end -0.508 0.9398)
			(stroke
				(width 0.1524)
				(type default)
			)
			(layer "F.SilkS")
		)
		(fp_line
			(start 0.508 -0.9398)
			(end -0.508 -0.9398)
			(stroke
				(width 0.1524)
				(type default)
			)
			(layer "F.SilkS")
		)
		(fp_rect
			(start -0.508 0.9398)
			(end 0.508 -0.9398)
			(stroke
				(width 0)
				(type default)
			)
			(fill no)
			(layer "F.CrtYd")
		)
		(fp_rect
			(start -0.508 0.9398)
			(end 0.508 -0.9398)
			(stroke
				(width 0)
				(type default)
			)
			(fill no)
			(layer "F.Fab")
		)
		(pad "1" smd custom
			(at 0 -0.4445)
			(size 0.1397 0.1397)
			(layers "F.Cu" "F.Mask" "F.Paste")
			(net "P3V3")
			(options
				(clearance outline)
				(anchor circle)
			)
			(primitives
				(gr_poly
					(pts
						(arc
							(start -0.1778 -0.2794)
							(mid -0.249642 -0.249642)
							(end -0.2794 -0.1778)
						)
						(arc
							(start -0.2794 0.1778)
							(mid -0.249642 0.249642)
							(end -0.1778 0.2794)
						)
						(arc
							(start 0.1778 0.2794)
							(mid 0.249642 0.249642)
							(end 0.2794 0.1778)
						)
						(arc
							(start 0.2794 -0.1778)
							(mid 0.249642 -0.249642)
							(end 0.1778 -0.2794)
						)
					)
					(width 0)
					(fill yes)
				)
			)
		)
		(pad "2" smd custom
			(at 0 0.4445)
			(size 0.1397 0.1397)
			(layers "F.Cu" "F.Mask" "F.Paste")
			(net "I2C_B_TMP1_A0")
			(options
				(clearance outline)
				(anchor circle)
			)
			(primitives
				(gr_poly
					(pts
						(arc
							(start -0.1778 -0.2794)
							(mid -0.249642 -0.249642)
							(end -0.2794 -0.1778)
						)
						(arc
							(start -0.2794 0.1778)
							(mid -0.249642 0.249642)
							(end -0.1778 0.2794)
						)
						(arc
							(start 0.1778 0.2794)
							(mid 0.249642 0.249642)
							(end 0.2794 0.1778)
						)
						(arc
							(start 0.2794 -0.1778)
							(mid 0.249642 -0.249642)
							(end 0.1778 -0.2794)
						)
					)
					(width 0)
					(fill yes)
				)
			)
		)
	)
	(footprint ""
		(layer "F.Cu")
		(at 225.1075 -451.4215 90)
		(property "Reference" "R9912"
			(at 0 0 90)
			(layer "F.SilkS")
			(hide yes)
			(effects
				(font
					(size 1.27 1.27)
				)
			)
		)
		(property "Value" "47KR2J-2-GP"
			(at 0.064008 -3.993896 90)
			(unlocked yes)
			(layer "F.Fab")
			(hide yes)
			(effects
				(font
					(size 1.016 1.016)
					(thickness 0.1524)
				)
			)
		)
		(property "Device Type" "R402H16"
			(at 0.064008 -5.517896 90)
			(unlocked yes)
			(layer "F.Fab")
			(hide yes)
			(effects
				(font
					(size 1.016 1.016)
					(thickness 0.1524)
				)
			)
		)
		(duplicate_pad_numbers_are_jumpers no)
		(fp_line
			(start 0.508 -0.9398)
			(end -0.508 -0.9398)
			(stroke
				(width 0.1524)
				(type default)
			)
			(layer "F.SilkS")
		)
		(fp_line
			(start -0.508 -0.9398)
			(end -0.508 0.9398)
			(stroke
				(width 0.1524)
				(type default)
			)
			(layer "F.SilkS")
		)
		(fp_rect
			(start -0.508 0.9398)
			(end 0.508 -0.9398)
			(stroke
				(width 0)
				(type default)
			)
			(fill no)
			(layer "F.CrtYd")
		)
		(fp_rect
			(start -0.508 0.9398)
			(end 0.508 -0.9398)
			(stroke
				(width 0)
				(type default)
			)
			(fill no)
			(layer "F.Fab")
		)
		(pad "1" smd custom
			(at 0 -0.4445 90)
			(size 0.1397 0.1397)
			(layers "F.Cu" "F.Mask" "F.Paste")
			(net "P3V3")
			(options
				(clearance outline)
				(anchor circle)
			)
			(primitives
				(gr_poly
					(pts
						(arc
							(start -0.1778 -0.2794)
							(mid -0.249642 -0.249642)
							(end -0.2794 -0.1778)
						)
						(arc
							(start -0.2794 0.1778)
							(mid -0.249642 0.249642)
							(end -0.1778 0.2794)
						)
						(arc
							(start 0.1778 0.2794)
							(mid 0.249642 0.249642)
							(end 0.2794 0.1778)
						)
						(arc
							(start 0.2794 -0.1778)
							(mid 0.249642 -0.249642)
							(end 0.1778 -0.2794)
						)
					)
					(width 0)
					(fill yes)
				)
			)
		)
		(pad "2" smd custom
			(at 0 0.4445 90)
			(size 0.1397 0.1397)
			(layers "F.Cu" "F.Mask" "F.Paste")
			(net "ATTN_LED_DR0_N")
			(options
				(clearance outline)
				(anchor circle)
			)
			(primitives
				(gr_poly
					(pts
						(arc
							(start -0.1778 -0.2794)
							(mid -0.249642 -0.249642)
							(end -0.2794 -0.1778)
						)
						(arc
							(start -0.2794 0.1778)
							(mid -0.249642 0.249642)
							(end -0.1778 0.2794)
						)
						(arc
							(start 0.1778 0.2794)
							(mid 0.249642 0.249642)
							(end 0.2794 0.1778)
						)
						(arc
							(start 0.2794 -0.1778)
							(mid 0.249642 -0.249642)
							(end 0.1778 -0.2794)
						)
					)
					(width 0)
					(fill yes)
				)
			)
		)
	)
	(footprint ""
		(layer "F.Cu")
		(at 234.061 -245.491 -90)
		(property "Reference" "R9894"
			(at 0 0 270)
			(layer "F.SilkS")
			(hide yes)
			(effects
				(font
					(size 1.27 1.27)
				)
			)
		)
		(property "Value" "1K82R2F-1-GP"
			(at 0.064008 -3.993896 270)
			(unlocked yes)
			(layer "F.Fab")
			(hide yes)
			(effects
				(font
					(size 1.016 1.016)
					(thickness 0.1524)
				)
			)
		)
		(property "Device Type" "R402H16"
			(at 0.064008 -5.517896 270)
			(unlocked yes)
			(layer "F.Fab")
			(hide yes)
			(effects
				(font
					(size 1.016 1.016)
					(thickness 0.1524)
				)
			)
		)
		(duplicate_pad_numbers_are_jumpers no)
		(fp_line
			(start -0.508 -0.9398)
			(end -0.508 0.9398)
			(stroke
				(width 0.1524)
				(type default)
			)
			(layer "F.SilkS")
		)
		(fp_line
			(start 0.508 -0.9398)
			(end -0.508 -0.9398)
			(stroke
				(width 0.1524)
				(type default)
			)
			(layer "F.SilkS")
		)
		(fp_rect
			(start -0.508 0.9398)
			(end 0.508 -0.9398)
			(stroke
				(width 0)
				(type default)
			)
			(fill no)
			(layer "F.CrtYd")
		)
		(fp_rect
			(start -0.508 0.9398)
			(end 0.508 -0.9398)
			(stroke
				(width 0)
				(type default)
			)
			(fill no)
			(layer "F.Fab")
		)
		(pad "1" smd custom
			(at 0 -0.4445 270)
			(size 0.1397 0.1397)
			(layers "F.Cu" "F.Mask" "F.Paste")
			(net "P12V")
			(options
				(clearance outline)
				(anchor circle)
			)
			(primitives
				(gr_poly
					(pts
						(arc
							(start -0.1778 -0.2794)
							(mid -0.249642 -0.249642)
							(end -0.2794 -0.1778)
						)
						(arc
							(start -0.2794 0.1778)
							(mid -0.249642 0.249642)
							(end -0.1778 0.2794)
						)
						(arc
							(start 0.1778 0.2794)
							(mid 0.249642 0.249642)
							(end 0.2794 0.1778)
						)
						(arc
							(start 0.2794 -0.1778)
							(mid 0.249642 -0.249642)
							(end 0.1778 -0.2794)
						)
					)
					(width 0)
					(fill yes)
				)
			)
		)
		(pad "2" smd custom
			(at 0 0.4445 270)
			(size 0.1397 0.1397)
			(layers "F.Cu" "F.Mask" "F.Paste")
			(net "DRV_ACT_2")
			(options
				(clearance outline)
				(anchor circle)
			)
			(primitives
				(gr_poly
					(pts
						(arc
							(start -0.1778 -0.2794)
							(mid -0.249642 -0.249642)
							(end -0.2794 -0.1778)
						)
						(arc
							(start -0.2794 0.1778)
							(mid -0.249642 0.249642)
							(end -0.1778 0.2794)
						)
						(arc
							(start 0.1778 0.2794)
							(mid 0.249642 0.249642)
							(end 0.2794 0.1778)
						)
						(arc
							(start 0.2794 -0.1778)
							(mid 0.249642 -0.249642)
							(end 0.1778 -0.2794)
						)
					)
					(width 0)
					(fill yes)
				)
			)
		)
	)
	(footprint ""
		(layer "F.Cu")
		(at 32.131 -185.801 -90)
		(property "Reference" "R404"
			(at 0 0 270)
			(layer "F.SilkS")
			(hide yes)
			(effects
				(font
					(size 1.27 1.27)
				)
			)
		)
		(property "Value" "0R2J-2-GP"
			(at 0.064008 -3.993896 270)
			(unlocked yes)
			(layer "F.Fab")
			(hide yes)
			(effects
				(font
					(size 1.016 1.016)
					(thickness 0.1524)
				)
			)
		)
		(property "Device Type" "R402H16"
			(at 0.064008 -5.517896 270)
			(unlocked yes)
			(layer "F.Fab")
			(hide yes)
			(effects
				(font
					(size 1.016 1.016)
					(thickness 0.1524)
				)
			)
		)
		(duplicate_pad_numbers_are_jumpers no)
		(fp_line
			(start -0.508 -0.9398)
			(end -0.508 0.9398)
			(stroke
				(width 0.1524)
				(type default)
			)
			(layer "F.SilkS")
		)
		(fp_line
			(start 0.508 -0.9398)
			(end -0.508 -0.9398)
			(stroke
				(width 0.1524)
				(type default)
			)
			(layer "F.SilkS")
		)
		(fp_rect
			(start -0.508 0.9398)
			(end 0.508 -0.9398)
			(stroke
				(width 0)
				(type default)
			)
			(fill no)
			(layer "F.CrtYd")
		)
		(fp_rect
			(start -0.508 0.9398)
			(end 0.508 -0.9398)
			(stroke
				(width 0)
				(type default)
			)
			(fill no)
			(layer "F.Fab")
		)
		(pad "1" smd custom
			(at 0 -0.4445 270)
			(size 0.1397 0.1397)
			(layers "F.Cu" "F.Mask" "F.Paste")
			(net "SDA_DR8_R")
			(options
				(clearance outline)
				(anchor circle)
			)
			(primitives
				(gr_poly
					(pts
						(arc
							(start -0.1778 -0.2794)
							(mid -0.249642 -0.249642)
							(end -0.2794 -0.1778)
						)
						(arc
							(start -0.2794 0.1778)
							(mid -0.249642 0.249642)
							(end -0.1778 0.2794)
						)
						(arc
							(start 0.1778 0.2794)
							(mid 0.249642 0.249642)
							(end 0.2794 0.1778)
						)
						(arc
							(start 0.2794 -0.1778)
							(mid 0.249642 -0.249642)
							(end 0.1778 -0.2794)
						)
					)
					(width 0)
					(fill yes)
				)
			)
		)
		(pad "2" smd custom
			(at 0 0.4445 270)
			(size 0.1397 0.1397)
			(layers "F.Cu" "F.Mask" "F.Paste")
			(net "SDA_DR8")
			(options
				(clearance outline)
				(anchor circle)
			)
			(primitives
				(gr_poly
					(pts
						(arc
							(start -0.1778 -0.2794)
							(mid -0.249642 -0.249642)
							(end -0.2794 -0.1778)
						)
						(arc
							(start -0.2794 0.1778)
							(mid -0.249642 0.249642)
							(end -0.1778 0.2794)
						)
						(arc
							(start 0.1778 0.2794)
							(mid 0.249642 0.249642)
							(end 0.2794 0.1778)
						)
						(arc
							(start 0.2794 -0.1778)
							(mid 0.249642 -0.249642)
							(end 0.1778 -0.2794)
						)
					)
					(width 0)
					(fill yes)
				)
			)
		)
	)
	(footprint ""
		(layer "F.Cu")
		(at 210.49996 -48.999902 -90)
		(property "Reference" "U48"
			(at 0 0 270)
			(layer "F.SilkS")
			(hide yes)
			(effects
				(font
					(size 1.27 1.27)
				)
			)
		)
		(property "Value" "TMP75AIDGKR-GP"
			(at -0.1143 -9.1948 270)
			(unlocked yes)
			(layer "F.Fab")
			(hide yes)
			(effects
				(font
					(size 1.016 1.016)
					(thickness 0.1524)
				)
			)
		)
		(property "Device Type" "MSOP8-1H44"
			(at -0.1143 -10.795 270)
			(unlocked yes)
			(layer "F.Fab")
			(hide yes)
			(effects
				(font
					(size 1.016 1.016)
					(thickness 0.1524)
				)
			)
		)
		(duplicate_pad_numbers_are_jumpers no)
		(fp_line
			(start -1.778 1.0922)
			(end -1.778 3.048)
			(stroke
				(width 0.508)
				(type default)
			)
			(layer "F.SilkS")
		)
		(fp_line
			(start -1.9558 1.016)
			(end 1.0795 1.016)
			(stroke
				(width 0.1524)
				(type default)
			)
			(layer "F.SilkS")
		)
		(fp_line
			(start 1.0795 1.016)
			(end 1.0795 -1.016)
			(stroke
				(width 0.1524)
				(type default)
			)
			(layer "F.SilkS")
		)
		(fp_line
			(start -1.4478 -0.0381)
			(end -1.9558 0.4699)
			(stroke
				(width 0.1524)
				(type default)
			)
			(layer "F.SilkS")
		)
		(fp_line
			(start -1.9558 -0.5461)
			(end -1.4478 -0.0381)
			(stroke
				(width 0.1524)
				(type default)
			)
			(layer "F.SilkS")
		)
		(fp_line
			(start -1.9558 -1.016)
			(end -1.9558 1.016)
			(stroke
				(width 0.1524)
				(type default)
			)
			(layer "F.SilkS")
		)
		(fp_line
			(start 1.0795 -1.016)
			(end -1.9558 -1.016)
			(stroke
				(width 0.1524)
				(type default)
			)
			(layer "F.SilkS")
		)
		(fp_poly
			(pts
				(xy -1.1557 -1.016) (xy -1.1557 1.016) (xy 1.1557 1.016) (xy 1.1557 -1.016)
			)
			(stroke
				(width 0)
				(type default)
			)
			(fill yes)
			(layer "F.SilkS")
		)
		(fp_rect
			(start -1.4986 2.4511)
			(end 1.4986 -2.4511)
			(stroke
				(width 0)
				(type default)
			)
			(fill no)
			(layer "F.CrtYd")
		)
		(fp_poly
			(pts
				(xy -2.032 3.302) (xy -2.032 -3.302) (xy 2.032 -3.302) (xy 2.032 -2.1209) (xy 1.4986 -2.1209) (xy 1.4986 -2.4511)
				(xy -1.4986 -2.4511) (xy -1.4986 2.4511) (xy 1.4986 2.4511) (xy 1.4986 -2.1082) (xy 2.032 -2.1082)
				(xy 2.032 3.302)
			)
			(stroke
				(width 0)
				(type default)
			)
			(fill no)
			(layer "F.CrtYd")
		)
		(fp_rect
			(start -2.032 3.302)
			(end 2.032 -3.302)
			(stroke
				(width 0)
				(type default)
			)
			(fill no)
			(layer "F.Fab")
		)
		(pad "1" smd rect
			(at -0.97536 2.05486 270)
			(size 0.3556 1.524)
			(layers "F.Cu" "F.Mask" "F.Paste")
			(net "TMP3_SDA")
		)
		(pad "2" smd rect
			(at -0.32512 2.05486 270)
			(size 0.3556 1.524)
			(layers "F.Cu" "F.Mask" "F.Paste")
			(net "TMP3_SCL")
		)
		(pad "3" smd rect
			(at 0.32512 2.05486 270)
			(size 0.3556 1.524)
			(layers "F.Cu" "F.Mask" "F.Paste")
			(net "I2C_B_TMP3_ALERT")
		)
		(pad "4" smd rect
			(at 0.97536 2.05486 270)
			(size 0.3556 1.524)
			(layers "F.Cu" "F.Mask" "F.Paste")
			(net "GND")
		)
		(pad "5" smd rect
			(at 0.97536 -2.05486 270)
			(size 0.3556 1.524)
			(layers "F.Cu" "F.Mask" "F.Paste")
			(net "I2C_B_TMP3_A2")
		)
		(pad "6" smd rect
			(at 0.32512 -2.05486 270)
			(size 0.3556 1.524)
			(layers "F.Cu" "F.Mask" "F.Paste")
			(net "I2C_B_TMP3_A1")
		)
		(pad "7" smd rect
			(at -0.32512 -2.05486 270)
			(size 0.3556 1.524)
			(layers "F.Cu" "F.Mask" "F.Paste")
			(net "I2C_B_TMP3_A0")
		)
		(pad "8" smd rect
			(at -0.97536 -2.05486 270)
			(size 0.3556 1.524)
			(layers "F.Cu" "F.Mask" "F.Paste")
			(net "P3V3")
		)
	)
	(footprint ""
		(layer "F.Cu")
		(at 82.931 -306.2732 90)
		(property "Reference" "R9351"
			(at 0 0 90)
			(layer "F.SilkS")
			(hide yes)
			(effects
				(font
					(size 1.27 1.27)
				)
			)
		)
		(property "Value" "2D2R2F-GP"
			(at 0.064008 -3.993896 90)
			(unlocked yes)
			(layer "F.Fab")
			(hide yes)
			(effects
				(font
					(size 1.016 1.016)
					(thickness 0.1524)
				)
			)
		)
		(property "Device Type" "R402H16"
			(at 0.064008 -5.517896 90)
			(unlocked yes)
			(layer "F.Fab")
			(hide yes)
			(effects
				(font
					(size 1.016 1.016)
					(thickness 0.1524)
				)
			)
		)
		(duplicate_pad_numbers_are_jumpers no)
		(fp_line
			(start 0.508 -0.9398)
			(end -0.508 -0.9398)
			(stroke
				(width 0.1524)
				(type default)
			)
			(layer "F.SilkS")
		)
		(fp_line
			(start -0.508 -0.9398)
			(end -0.508 0.9398)
			(stroke
				(width 0.1524)
				(type default)
			)
			(layer "F.SilkS")
		)
		(fp_rect
			(start -0.508 0.9398)
			(end 0.508 -0.9398)
			(stroke
				(width 0)
				(type default)
			)
			(fill no)
			(layer "F.CrtYd")
		)
		(fp_rect
			(start -0.508 0.9398)
			(end 0.508 -0.9398)
			(stroke
				(width 0)
				(type default)
			)
			(fill no)
			(layer "F.Fab")
		)
		(pad "1" smd custom
			(at 0 -0.4445 90)
			(size 0.1397 0.1397)
			(layers "F.Cu" "F.Mask" "F.Paste")
			(net "VDD_DIFF_2")
			(options
				(clearance outline)
				(anchor circle)
			)
			(primitives
				(gr_poly
					(pts
						(arc
							(start -0.1778 -0.2794)
							(mid -0.249642 -0.249642)
							(end -0.2794 -0.1778)
						)
						(arc
							(start -0.2794 0.1778)
							(mid -0.249642 0.249642)
							(end -0.1778 0.2794)
						)
						(arc
							(start 0.1778 0.2794)
							(mid 0.249642 0.249642)
							(end 0.2794 0.1778)
						)
						(arc
							(start 0.2794 -0.1778)
							(mid 0.249642 -0.249642)
							(end 0.1778 -0.2794)
						)
					)
					(width 0)
					(fill yes)
				)
			)
		)
		(pad "2" smd custom
			(at 0 0.4445 90)
			(size 0.1397 0.1397)
			(layers "F.Cu" "F.Mask" "F.Paste")
			(net "VDDR_2")
			(options
				(clearance outline)
				(anchor circle)
			)
			(primitives
				(gr_poly
					(pts
						(arc
							(start -0.1778 -0.2794)
							(mid -0.249642 -0.249642)
							(end -0.2794 -0.1778)
						)
						(arc
							(start -0.2794 0.1778)
							(mid -0.249642 0.249642)
							(end -0.1778 0.2794)
						)
						(arc
							(start 0.1778 0.2794)
							(mid 0.249642 0.249642)
							(end 0.2794 0.1778)
						)
						(arc
							(start 0.2794 -0.1778)
							(mid 0.249642 -0.249642)
							(end 0.1778 -0.2794)
						)
					)
					(width 0)
					(fill yes)
				)
			)
		)
	)
	(footprint ""
		(layer "F.Cu")
		(at 43.016424 -42.877994 -90)
		(property "Reference" "R9945"
			(at 0 0 270)
			(layer "F.SilkS")
			(hide yes)
			(effects
				(font
					(size 1.27 1.27)
				)
			)
		)
		(property "Value" "4K7R2J-2-GP"
			(at 0.064008 -3.993896 270)
			(unlocked yes)
			(layer "F.Fab")
			(hide yes)
			(effects
				(font
					(size 1.016 1.016)
					(thickness 0.1524)
				)
			)
		)
		(property "Device Type" "R402H16"
			(at 0.064008 -5.517896 270)
			(unlocked yes)
			(layer "F.Fab")
			(hide yes)
			(effects
				(font
					(size 1.016 1.016)
					(thickness 0.1524)
				)
			)
		)
		(duplicate_pad_numbers_are_jumpers no)
		(fp_line
			(start -0.508 -0.9398)
			(end -0.508 0.9398)
			(stroke
				(width 0.1524)
				(type default)
			)
			(layer "F.SilkS")
		)
		(fp_line
			(start 0.508 -0.9398)
			(end -0.508 -0.9398)
			(stroke
				(width 0.1524)
				(type default)
			)
			(layer "F.SilkS")
		)
		(fp_rect
			(start -0.508 0.9398)
			(end 0.508 -0.9398)
			(stroke
				(width 0)
				(type default)
			)
			(fill no)
			(layer "F.CrtYd")
		)
		(fp_rect
			(start -0.508 0.9398)
			(end 0.508 -0.9398)
			(stroke
				(width 0)
				(type default)
			)
			(fill no)
			(layer "F.Fab")
		)
		(pad "1" smd custom
			(at 0 -0.4445 270)
			(size 0.1397 0.1397)
			(layers "F.Cu" "F.Mask" "F.Paste")
			(net "P3V3")
			(options
				(clearance outline)
				(anchor circle)
			)
			(primitives
				(gr_poly
					(pts
						(arc
							(start -0.1778 -0.2794)
							(mid -0.249642 -0.249642)
							(end -0.2794 -0.1778)
						)
						(arc
							(start -0.2794 0.1778)
							(mid -0.249642 0.249642)
							(end -0.1778 0.2794)
						)
						(arc
							(start 0.1778 0.2794)
							(mid 0.249642 0.249642)
							(end 0.2794 0.1778)
						)
						(arc
							(start 0.2794 -0.1778)
							(mid 0.249642 -0.249642)
							(end 0.1778 -0.2794)
						)
					)
					(width 0)
					(fill yes)
				)
			)
		)
		(pad "2" smd custom
			(at 0 0.4445 270)
			(size 0.1397 0.1397)
			(layers "F.Cu" "F.Mask" "F.Paste")
			(net "ATTN_LED_DR9_MOS_N")
			(options
				(clearance outline)
				(anchor circle)
			)
			(primitives
				(gr_poly
					(pts
						(arc
							(start -0.1778 -0.2794)
							(mid -0.249642 -0.249642)
							(end -0.2794 -0.1778)
						)
						(arc
							(start -0.2794 0.1778)
							(mid -0.249642 0.249642)
							(end -0.1778 0.2794)
						)
						(arc
							(start 0.1778 0.2794)
							(mid 0.249642 0.249642)
							(end 0.2794 0.1778)
						)
						(arc
							(start 0.2794 -0.1778)
							(mid 0.249642 -0.249642)
							(end 0.1778 -0.2794)
						)
					)
					(width 0)
					(fill yes)
				)
			)
		)
	)
	(footprint ""
		(layer "F.Cu")
		(at 212.852 -498.475 180)
		(property "Reference" "PC1185"
			(at 0 0 180)
			(layer "F.SilkS")
			(hide yes)
			(effects
				(font
					(size 1.27 1.27)
				)
			)
		)
		(property "Value" "SC22U25V6KX-GP-U"
			(at -2.860802 -5.279644 180)
			(unlocked yes)
			(layer "F.Fab")
			(hide yes)
			(effects
				(font
					(size 1.016 1.016)
					(thickness 0.1524)
				)
			)
		)
		(property "Device Type" "C1206-TO0D3H75"
			(at -2.860802 -6.803644 180)
			(unlocked yes)
			(layer "F.Fab")
			(hide yes)
			(effects
				(font
					(size 1.016 1.016)
					(thickness 0.1524)
				)
			)
		)
		(duplicate_pad_numbers_are_jumpers no)
		(fp_line
			(start 1.3081 2.3749)
			(end -1.3081 2.3749)
			(stroke
				(width 0.1524)
				(type default)
			)
			(layer "F.SilkS")
		)
		(fp_line
			(start 1.3081 -2.3749)
			(end 1.3081 2.3749)
			(stroke
				(width 0.1524)
				(type default)
			)
			(layer "F.SilkS")
		)
		(fp_line
			(start -1.3081 2.3749)
			(end -1.3081 -2.3749)
			(stroke
				(width 0.1524)
				(type default)
			)
			(layer "F.SilkS")
		)
		(fp_line
			(start -1.3081 -2.3749)
			(end 1.3081 -2.3749)
			(stroke
				(width 0.1524)
				(type default)
			)
			(layer "F.SilkS")
		)
		(fp_rect
			(start -0.8001 1.6002)
			(end 0.8001 -1.6002)
			(stroke
				(width 0)
				(type default)
			)
			(fill no)
			(layer "F.CrtYd")
		)
		(fp_poly
			(pts
				(xy -1.5621 2.4511) (xy -1.5621 1.6002) (xy 0.8001 1.6002) (xy 0.8001 -1.6002) (xy -0.8001 -1.6002)
				(xy -0.8001 1.5875) (xy -1.5621 1.5875) (xy -1.5621 -2.4511) (xy 1.5621 -2.4511) (xy 1.5621 2.4511)
			)
			(stroke
				(width 0)
				(type default)
			)
			(fill no)
			(layer "F.CrtYd")
		)
		(fp_rect
			(start -1.5621 2.4511)
			(end 1.5621 -2.4511)
			(stroke
				(width 0)
				(type default)
			)
			(fill no)
			(layer "F.Fab")
		)
		(pad "1" smd rect
			(at 0 -1.392936 180)
			(size 2.1082 1.4478)
			(layers "F.Cu" "F.Mask" "F.Paste")
			(net "P12V_SSD0")
		)
		(pad "2" smd rect
			(at 0 1.392936 180)
			(size 2.1082 1.4478)
			(layers "F.Cu" "F.Mask" "F.Paste")
			(net "GND")
		)
	)
	(footprint ""
		(layer "F.Cu")
		(at 227.886768 -454.867264 -90)
		(property "Reference" "R9927"
			(at 0 0 270)
			(layer "F.SilkS")
			(hide yes)
			(effects
				(font
					(size 1.27 1.27)
				)
			)
		)
		(property "Value" "4K7R2J-2-GP"
			(at 0.064008 -3.993896 270)
			(unlocked yes)
			(layer "F.Fab")
			(hide yes)
			(effects
				(font
					(size 1.016 1.016)
					(thickness 0.1524)
				)
			)
		)
		(property "Device Type" "R402H16"
			(at 0.064008 -5.517896 270)
			(unlocked yes)
			(layer "F.Fab")
			(hide yes)
			(effects
				(font
					(size 1.016 1.016)
					(thickness 0.1524)
				)
			)
		)
		(duplicate_pad_numbers_are_jumpers no)
		(fp_line
			(start -0.508 -0.9398)
			(end -0.508 0.9398)
			(stroke
				(width 0.1524)
				(type default)
			)
			(layer "F.SilkS")
		)
		(fp_line
			(start 0.508 -0.9398)
			(end -0.508 -0.9398)
			(stroke
				(width 0.1524)
				(type default)
			)
			(layer "F.SilkS")
		)
		(fp_rect
			(start -0.508 0.9398)
			(end 0.508 -0.9398)
			(stroke
				(width 0)
				(type default)
			)
			(fill no)
			(layer "F.CrtYd")
		)
		(fp_rect
			(start -0.508 0.9398)
			(end 0.508 -0.9398)
			(stroke
				(width 0)
				(type default)
			)
			(fill no)
			(layer "F.Fab")
		)
		(pad "1" smd custom
			(at 0 -0.4445 270)
			(size 0.1397 0.1397)
			(layers "F.Cu" "F.Mask" "F.Paste")
			(net "P3V3")
			(options
				(clearance outline)
				(anchor circle)
			)
			(primitives
				(gr_poly
					(pts
						(arc
							(start -0.1778 -0.2794)
							(mid -0.249642 -0.249642)
							(end -0.2794 -0.1778)
						)
						(arc
							(start -0.2794 0.1778)
							(mid -0.249642 0.249642)
							(end -0.1778 0.2794)
						)
						(arc
							(start 0.1778 0.2794)
							(mid 0.249642 0.249642)
							(end 0.2794 0.1778)
						)
						(arc
							(start 0.2794 -0.1778)
							(mid 0.249642 -0.249642)
							(end 0.1778 -0.2794)
						)
					)
					(width 0)
					(fill yes)
				)
			)
		)
		(pad "2" smd custom
			(at 0 0.4445 270)
			(size 0.1397 0.1397)
			(layers "F.Cu" "F.Mask" "F.Paste")
			(net "ATTN_LED_DR0_MOS_N")
			(options
				(clearance outline)
				(anchor circle)
			)
			(primitives
				(gr_poly
					(pts
						(arc
							(start -0.1778 -0.2794)
							(mid -0.249642 -0.249642)
							(end -0.2794 -0.1778)
						)
						(arc
							(start -0.2794 0.1778)
							(mid -0.249642 0.249642)
							(end -0.1778 0.2794)
						)
						(arc
							(start 0.1778 0.2794)
							(mid 0.249642 0.249642)
							(end 0.2794 0.1778)
						)
						(arc
							(start 0.2794 -0.1778)
							(mid 0.249642 -0.249642)
							(end 0.1778 -0.2794)
						)
					)
					(width 0)
					(fill yes)
				)
			)
		)
	)
	(footprint ""
		(layer "F.Cu")
		(at 225.1075 -245.421658 90)
		(property "Reference" "R9914"
			(at 0 0 90)
			(layer "F.SilkS")
			(hide yes)
			(effects
				(font
					(size 1.27 1.27)
				)
			)
		)
		(property "Value" "47KR2J-2-GP"
			(at 0.064008 -3.993896 90)
			(unlocked yes)
			(layer "F.Fab")
			(hide yes)
			(effects
				(font
					(size 1.016 1.016)
					(thickness 0.1524)
				)
			)
		)
		(property "Device Type" "R402H16"
			(at 0.064008 -5.517896 90)
			(unlocked yes)
			(layer "F.Fab")
			(hide yes)
			(effects
				(font
					(size 1.016 1.016)
					(thickness 0.1524)
				)
			)
		)
		(duplicate_pad_numbers_are_jumpers no)
		(fp_line
			(start 0.508 -0.9398)
			(end -0.508 -0.9398)
			(stroke
				(width 0.1524)
				(type default)
			)
			(layer "F.SilkS")
		)
		(fp_line
			(start -0.508 -0.9398)
			(end -0.508 0.9398)
			(stroke
				(width 0.1524)
				(type default)
			)
			(layer "F.SilkS")
		)
		(fp_rect
			(start -0.508 0.9398)
			(end 0.508 -0.9398)
			(stroke
				(width 0)
				(type default)
			)
			(fill no)
			(layer "F.CrtYd")
		)
		(fp_rect
			(start -0.508 0.9398)
			(end 0.508 -0.9398)
			(stroke
				(width 0)
				(type default)
			)
			(fill no)
			(layer "F.Fab")
		)
		(pad "1" smd custom
			(at 0 -0.4445 90)
			(size 0.1397 0.1397)
			(layers "F.Cu" "F.Mask" "F.Paste")
			(net "P3V3")
			(options
				(clearance outline)
				(anchor circle)
			)
			(primitives
				(gr_poly
					(pts
						(arc
							(start -0.1778 -0.2794)
							(mid -0.249642 -0.249642)
							(end -0.2794 -0.1778)
						)
						(arc
							(start -0.2794 0.1778)
							(mid -0.249642 0.249642)
							(end -0.1778 0.2794)
						)
						(arc
							(start 0.1778 0.2794)
							(mid 0.249642 0.249642)
							(end 0.2794 0.1778)
						)
						(arc
							(start 0.2794 -0.1778)
							(mid 0.249642 -0.249642)
							(end 0.1778 -0.2794)
						)
					)
					(width 0)
					(fill yes)
				)
			)
		)
		(pad "2" smd custom
			(at 0 0.4445 90)
			(size 0.1397 0.1397)
			(layers "F.Cu" "F.Mask" "F.Paste")
			(net "ATTN_LED_DR2_N")
			(options
				(clearance outline)
				(anchor circle)
			)
			(primitives
				(gr_poly
					(pts
						(arc
							(start -0.1778 -0.2794)
							(mid -0.249642 -0.249642)
							(end -0.2794 -0.1778)
						)
						(arc
							(start -0.2794 0.1778)
							(mid -0.249642 0.249642)
							(end -0.1778 0.2794)
						)
						(arc
							(start 0.1778 0.2794)
							(mid 0.249642 0.249642)
							(end 0.2794 0.1778)
						)
						(arc
							(start 0.2794 -0.1778)
							(mid 0.249642 -0.249642)
							(end 0.1778 -0.2794)
						)
					)
					(width 0)
					(fill yes)
				)
			)
		)
	)
	(footprint ""
		(layer "F.Cu")
		(at 24.7904 -311.5056)
		(property "Reference" "PC1222"
			(at 0 0 0)
			(layer "F.SilkS")
			(hide yes)
			(effects
				(font
					(size 1.27 1.27)
				)
			)
		)
		(property "Value" "SCD1U50V3KX-GP"
			(at 0 -2.8194 0)
			(unlocked yes)
			(layer "F.Fab")
			(hide yes)
			(effects
				(font
					(size 1.016 1.016)
					(thickness 0.1524)
				)
			)
		)
		(property "Device Type" "C603H36"
			(at 0 -4.3434 0)
			(unlocked yes)
			(layer "F.Fab")
			(hide yes)
			(effects
				(font
					(size 1.016 1.016)
					(thickness 0.1524)
				)
			)
		)
		(duplicate_pad_numbers_are_jumpers no)
		(fp_line
			(start 0.508 0)
			(end -0.508 0)
			(stroke
				(width 0.2032)
				(type default)
			)
			(layer "F.SilkS")
		)
		(fp_rect
			(start -0.5842 1.3335)
			(end 0.5842 -1.3335)
			(stroke
				(width 0)
				(type default)
			)
			(fill no)
			(layer "F.CrtYd")
		)
		(fp_rect
			(start -0.5842 1.3335)
			(end 0.5842 -1.3335)
			(stroke
				(width 0)
				(type default)
			)
			(fill no)
			(layer "F.Fab")
		)
		(pad "1" smd custom
			(at 0 -0.762)
			(size 0.2159 0.2159)
			(layers "F.Cu" "F.Mask" "F.Paste")
			(net "P12V_SSD11")
			(options
				(clearance outline)
				(anchor circle)
			)
			(primitives
				(gr_poly
					(pts
						(arc
							(start -0.3302 -0.4318)
							(mid -0.402042 -0.402042)
							(end -0.4318 -0.3302)
						)
						(arc
							(start -0.4318 0.3302)
							(mid -0.402042 0.402042)
							(end -0.3302 0.4318)
						)
						(arc
							(start 0.3302 0.4318)
							(mid 0.402042 0.402042)
							(end 0.4318 0.3302)
						)
						(arc
							(start 0.4318 -0.3302)
							(mid 0.402042 -0.402042)
							(end 0.3302 -0.4318)
						)
					)
					(width 0)
					(fill yes)
				)
			)
		)
		(pad "2" smd custom
			(at 0 0.762)
			(size 0.2159 0.2159)
			(layers "F.Cu" "F.Mask" "F.Paste")
			(net "GND")
			(options
				(clearance outline)
				(anchor circle)
			)
			(primitives
				(gr_poly
					(pts
						(arc
							(start -0.3302 -0.4318)
							(mid -0.402042 -0.402042)
							(end -0.4318 -0.3302)
						)
						(arc
							(start -0.4318 0.3302)
							(mid -0.402042 0.402042)
							(end -0.3302 0.4318)
						)
						(arc
							(start 0.3302 0.4318)
							(mid 0.402042 0.402042)
							(end 0.4318 0.3302)
						)
						(arc
							(start 0.4318 -0.3302)
							(mid 0.402042 -0.402042)
							(end 0.3302 -0.4318)
						)
					)
					(width 0)
					(fill yes)
				)
			)
		)
	)
	(footprint ""
		(layer "F.Cu")
		(at 225.425 -431.292 -90)
		(property "Reference" "PC1259"
			(at 0 0 270)
			(layer "F.SilkS")
			(hide yes)
			(effects
				(font
					(size 1.27 1.27)
				)
			)
		)
		(property "Value" "SCD1U25V2KX-2-GP"
			(at 1.1811 -2.7051 270)
			(unlocked yes)
			(layer "F.Fab")
			(hide yes)
			(effects
				(font
					(size 1.016 1.016)
					(thickness 0.1524)
				)
			)
		)
		(property "Device Type" "C402H22"
			(at 1.1811 -4.2291 270)
			(unlocked yes)
			(layer "F.Fab")
			(hide yes)
			(effects
				(font
					(size 1.016 1.016)
					(thickness 0.1524)
				)
			)
		)
		(duplicate_pad_numbers_are_jumpers no)
		(fp_rect
			(start -0.4318 0.9525)
			(end 0.4318 -0.9525)
			(stroke
				(width 0)
				(type default)
			)
			(fill no)
			(layer "F.CrtYd")
		)
		(fp_rect
			(start -0.4318 0.9525)
			(end 0.4318 -0.9525)
			(stroke
				(width 0)
				(type default)
			)
			(fill no)
			(layer "F.Fab")
		)
		(pad "1" smd custom
			(at 0 -0.4445 270)
			(size 0.1524 0.1524)
			(layers "F.Cu" "F.Mask" "F.Paste")
			(net "P3V3_VIN")
			(options
				(clearance outline)
				(anchor circle)
			)
			(primitives
				(gr_poly
					(pts
						(arc
							(start 0.3048 -0.2032)
							(mid 0.275042 -0.275042)
							(end 0.2032 -0.3048)
						)
						(arc
							(start -0.2032 -0.3048)
							(mid -0.275042 -0.275042)
							(end -0.3048 -0.2032)
						)
						(arc
							(start -0.3048 0.2032)
							(mid -0.275042 0.275042)
							(end -0.2032 0.3048)
						)
						(arc
							(start 0.2032 0.3048)
							(mid 0.275042 0.275042)
							(end 0.3048 0.2032)
						)
					)
					(width 0)
					(fill yes)
				)
			)
		)
		(pad "2" smd custom
			(at 0 0.4445 270)
			(size 0.1524 0.1524)
			(layers "F.Cu" "F.Mask" "F.Paste")
			(net "GND")
			(options
				(clearance outline)
				(anchor circle)
			)
			(primitives
				(gr_poly
					(pts
						(arc
							(start 0.3048 -0.2032)
							(mid 0.275042 -0.275042)
							(end 0.2032 -0.3048)
						)
						(arc
							(start -0.2032 -0.3048)
							(mid -0.275042 -0.275042)
							(end -0.3048 -0.2032)
						)
						(arc
							(start -0.3048 0.2032)
							(mid -0.275042 0.275042)
							(end -0.2032 0.3048)
						)
						(arc
							(start 0.2032 0.3048)
							(mid 0.275042 0.275042)
							(end 0.3048 0.2032)
						)
					)
					(width 0)
					(fill yes)
				)
			)
		)
	)
	(footprint ""
		(layer "F.Cu")
		(at 227.35159 -348.323154 90)
		(property "Reference" "R9930"
			(at 0 0 90)
			(layer "F.SilkS")
			(hide yes)
			(effects
				(font
					(size 1.27 1.27)
				)
			)
		)
		(property "Value" "4K7R2J-2-GP"
			(at 0.064008 -3.993896 90)
			(unlocked yes)
			(layer "F.Fab")
			(hide yes)
			(effects
				(font
					(size 1.016 1.016)
					(thickness 0.1524)
				)
			)
		)
		(property "Device Type" "R402H16"
			(at 0.064008 -5.517896 90)
			(unlocked yes)
			(layer "F.Fab")
			(hide yes)
			(effects
				(font
					(size 1.016 1.016)
					(thickness 0.1524)
				)
			)
		)
		(duplicate_pad_numbers_are_jumpers no)
		(fp_line
			(start 0.508 -0.9398)
			(end -0.508 -0.9398)
			(stroke
				(width 0.1524)
				(type default)
			)
			(layer "F.SilkS")
		)
		(fp_line
			(start -0.508 -0.9398)
			(end -0.508 0.9398)
			(stroke
				(width 0.1524)
				(type default)
			)
			(layer "F.SilkS")
		)
		(fp_rect
			(start -0.508 0.9398)
			(end 0.508 -0.9398)
			(stroke
				(width 0)
				(type default)
			)
			(fill no)
			(layer "F.CrtYd")
		)
		(fp_rect
			(start -0.508 0.9398)
			(end 0.508 -0.9398)
			(stroke
				(width 0)
				(type default)
			)
			(fill no)
			(layer "F.Fab")
		)
		(pad "1" smd custom
			(at 0 -0.4445 90)
			(size 0.1397 0.1397)
			(layers "F.Cu" "F.Mask" "F.Paste")
			(net "P3V3")
			(options
				(clearance outline)
				(anchor circle)
			)
			(primitives
				(gr_poly
					(pts
						(arc
							(start -0.1778 -0.2794)
							(mid -0.249642 -0.249642)
							(end -0.2794 -0.1778)
						)
						(arc
							(start -0.2794 0.1778)
							(mid -0.249642 0.249642)
							(end -0.1778 0.2794)
						)
						(arc
							(start 0.1778 0.2794)
							(mid 0.249642 0.249642)
							(end 0.2794 0.1778)
						)
						(arc
							(start 0.2794 -0.1778)
							(mid 0.249642 -0.249642)
							(end 0.1778 -0.2794)
						)
					)
					(width 0)
					(fill yes)
				)
			)
		)
		(pad "2" smd custom
			(at 0 0.4445 90)
			(size 0.1397 0.1397)
			(layers "F.Cu" "F.Mask" "F.Paste")
			(net "SSD_ACT_DR1_MOS_N")
			(options
				(clearance outline)
				(anchor circle)
			)
			(primitives
				(gr_poly
					(pts
						(arc
							(start -0.1778 -0.2794)
							(mid -0.249642 -0.249642)
							(end -0.2794 -0.1778)
						)
						(arc
							(start -0.2794 0.1778)
							(mid -0.249642 0.249642)
							(end -0.1778 0.2794)
						)
						(arc
							(start 0.1778 0.2794)
							(mid 0.249642 0.249642)
							(end 0.2794 0.1778)
						)
						(arc
							(start 0.2794 -0.1778)
							(mid 0.249642 -0.249642)
							(end 0.1778 -0.2794)
						)
					)
					(width 0)
					(fill yes)
				)
			)
		)
	)
	(footprint ""
		(layer "F.Cu")
		(at 222.0214 -189.23)
		(property "Reference" "PC1228"
			(at 0 0 0)
			(layer "F.SilkS")
			(hide yes)
			(effects
				(font
					(size 1.27 1.27)
				)
			)
		)
		(property "Value" "SCD01U50V2KX-1GP"
			(at 1.1811 -2.7051 0)
			(unlocked yes)
			(layer "F.Fab")
			(hide yes)
			(effects
				(font
					(size 1.016 1.016)
					(thickness 0.1524)
				)
			)
		)
		(property "Device Type" "C402H22"
			(at 1.1811 -4.2291 0)
			(unlocked yes)
			(layer "F.Fab")
			(hide yes)
			(effects
				(font
					(size 1.016 1.016)
					(thickness 0.1524)
				)
			)
		)
		(duplicate_pad_numbers_are_jumpers no)
		(fp_rect
			(start -0.4318 0.9525)
			(end 0.4318 -0.9525)
			(stroke
				(width 0)
				(type default)
			)
			(fill no)
			(layer "F.CrtYd")
		)
		(fp_rect
			(start -0.4318 0.9525)
			(end 0.4318 -0.9525)
			(stroke
				(width 0)
				(type default)
			)
			(fill no)
			(layer "F.Fab")
		)
		(pad "1" smd custom
			(at 0 -0.4445)
			(size 0.1524 0.1524)
			(layers "F.Cu" "F.Mask" "F.Paste")
			(net "P12V_SSD3")
			(options
				(clearance outline)
				(anchor circle)
			)
			(primitives
				(gr_poly
					(pts
						(arc
							(start 0.3048 -0.2032)
							(mid 0.275042 -0.275042)
							(end 0.2032 -0.3048)
						)
						(arc
							(start -0.2032 -0.3048)
							(mid -0.275042 -0.275042)
							(end -0.3048 -0.2032)
						)
						(arc
							(start -0.3048 0.2032)
							(mid -0.275042 0.275042)
							(end -0.2032 0.3048)
						)
						(arc
							(start 0.2032 0.3048)
							(mid 0.275042 0.275042)
							(end 0.3048 0.2032)
						)
					)
					(width 0)
					(fill yes)
				)
			)
		)
		(pad "2" smd custom
			(at 0 0.4445)
			(size 0.1524 0.1524)
			(layers "F.Cu" "F.Mask" "F.Paste")
			(net "GND")
			(options
				(clearance outline)
				(anchor circle)
			)
			(primitives
				(gr_poly
					(pts
						(arc
							(start 0.3048 -0.2032)
							(mid 0.275042 -0.275042)
							(end 0.2032 -0.3048)
						)
						(arc
							(start -0.2032 -0.3048)
							(mid -0.275042 -0.275042)
							(end -0.3048 -0.2032)
						)
						(arc
							(start -0.3048 0.2032)
							(mid -0.275042 0.275042)
							(end -0.2032 0.3048)
						)
						(arc
							(start 0.2032 0.3048)
							(mid 0.275042 0.275042)
							(end 0.3048 0.2032)
						)
					)
					(width 0)
					(fill yes)
				)
			)
		)
	)
	(footprint ""
		(layer "F.Cu")
		(at 98.806 -222.885 -90)
		(property "Reference" "C9357"
			(at 0 0 270)
			(layer "F.SilkS")
			(hide yes)
			(effects
				(font
					(size 1.27 1.27)
				)
			)
		)
		(property "Value" "SC1KP50V2KX-1GP"
			(at 1.1811 -2.7051 270)
			(unlocked yes)
			(layer "F.Fab")
			(hide yes)
			(effects
				(font
					(size 1.016 1.016)
					(thickness 0.1524)
				)
			)
		)
		(property "Device Type" "C402H22"
			(at 1.1811 -4.2291 270)
			(unlocked yes)
			(layer "F.Fab")
			(hide yes)
			(effects
				(font
					(size 1.016 1.016)
					(thickness 0.1524)
				)
			)
		)
		(duplicate_pad_numbers_are_jumpers no)
		(fp_rect
			(start -0.4318 0.9525)
			(end 0.4318 -0.9525)
			(stroke
				(width 0)
				(type default)
			)
			(fill no)
			(layer "F.CrtYd")
		)
		(fp_rect
			(start -0.4318 0.9525)
			(end 0.4318 -0.9525)
			(stroke
				(width 0)
				(type default)
			)
			(fill no)
			(layer "F.Fab")
		)
		(pad "1" smd custom
			(at 0 -0.4445 270)
			(size 0.1524 0.1524)
			(layers "F.Cu" "F.Mask" "F.Paste")
			(net "SSD_PRSNT7")
			(options
				(clearance outline)
				(anchor circle)
			)
			(primitives
				(gr_poly
					(pts
						(arc
							(start 0.3048 -0.2032)
							(mid 0.275042 -0.275042)
							(end 0.2032 -0.3048)
						)
						(arc
							(start -0.2032 -0.3048)
							(mid -0.275042 -0.275042)
							(end -0.3048 -0.2032)
						)
						(arc
							(start -0.3048 0.2032)
							(mid -0.275042 0.275042)
							(end -0.2032 0.3048)
						)
						(arc
							(start 0.2032 0.3048)
							(mid 0.275042 0.275042)
							(end 0.3048 0.2032)
						)
					)
					(width 0)
					(fill yes)
				)
			)
		)
		(pad "2" smd custom
			(at 0 0.4445 270)
			(size 0.1524 0.1524)
			(layers "F.Cu" "F.Mask" "F.Paste")
			(net "GND")
			(options
				(clearance outline)
				(anchor circle)
			)
			(primitives
				(gr_poly
					(pts
						(arc
							(start 0.3048 -0.2032)
							(mid 0.275042 -0.275042)
							(end 0.2032 -0.3048)
						)
						(arc
							(start -0.2032 -0.3048)
							(mid -0.275042 -0.275042)
							(end -0.3048 -0.2032)
						)
						(arc
							(start -0.3048 0.2032)
							(mid -0.275042 0.275042)
							(end -0.2032 0.3048)
						)
						(arc
							(start 0.2032 0.3048)
							(mid 0.275042 0.275042)
							(end 0.3048 0.2032)
						)
					)
					(width 0)
					(fill yes)
				)
			)
		)
	)
	(footprint ""
		(layer "F.Cu")
		(at 213.3981 -197.5231 180)
		(property "Reference" "R9800"
			(at 0 0 180)
			(layer "F.SilkS")
			(hide yes)
			(effects
				(font
					(size 1.27 1.27)
				)
			)
		)
		(property "Value" "47KR2J-2-GP"
			(at 0.064008 -3.993896 180)
			(unlocked yes)
			(layer "F.Fab")
			(hide yes)
			(effects
				(font
					(size 1.016 1.016)
					(thickness 0.1524)
				)
			)
		)
		(property "Device Type" "R402H16"
			(at 0.064008 -5.517896 180)
			(unlocked yes)
			(layer "F.Fab")
			(hide yes)
			(effects
				(font
					(size 1.016 1.016)
					(thickness 0.1524)
				)
			)
		)
		(duplicate_pad_numbers_are_jumpers no)
		(fp_line
			(start 0.508 -0.9398)
			(end -0.508 -0.9398)
			(stroke
				(width 0.1524)
				(type default)
			)
			(layer "F.SilkS")
		)
		(fp_line
			(start -0.508 -0.9398)
			(end -0.508 0.9398)
			(stroke
				(width 0.1524)
				(type default)
			)
			(layer "F.SilkS")
		)
		(fp_rect
			(start -0.508 0.9398)
			(end 0.508 -0.9398)
			(stroke
				(width 0)
				(type default)
			)
			(fill no)
			(layer "F.CrtYd")
		)
		(fp_rect
			(start -0.508 0.9398)
			(end 0.508 -0.9398)
			(stroke
				(width 0)
				(type default)
			)
			(fill no)
			(layer "F.Fab")
		)
		(pad "1" smd custom
			(at 0 -0.4445 180)
			(size 0.1397 0.1397)
			(layers "F.Cu" "F.Mask" "F.Paste")
			(net "P12V")
			(options
				(clearance outline)
				(anchor circle)
			)
			(primitives
				(gr_poly
					(pts
						(arc
							(start -0.1778 -0.2794)
							(mid -0.249642 -0.249642)
							(end -0.2794 -0.1778)
						)
						(arc
							(start -0.2794 0.1778)
							(mid -0.249642 0.249642)
							(end -0.1778 0.2794)
						)
						(arc
							(start 0.1778 0.2794)
							(mid 0.249642 0.249642)
							(end 0.2794 0.1778)
						)
						(arc
							(start 0.2794 -0.1778)
							(mid 0.249642 -0.249642)
							(end 0.1778 -0.2794)
						)
					)
					(width 0)
					(fill yes)
				)
			)
		)
		(pad "2" smd custom
			(at 0 0.4445 180)
			(size 0.1397 0.1397)
			(layers "F.Cu" "F.Mask" "F.Paste")
			(net "P12V_MOST3_GATE")
			(options
				(clearance outline)
				(anchor circle)
			)
			(primitives
				(gr_poly
					(pts
						(arc
							(start -0.1778 -0.2794)
							(mid -0.249642 -0.249642)
							(end -0.2794 -0.1778)
						)
						(arc
							(start -0.2794 0.1778)
							(mid -0.249642 0.249642)
							(end -0.1778 0.2794)
						)
						(arc
							(start 0.1778 0.2794)
							(mid 0.249642 0.249642)
							(end 0.2794 0.1778)
						)
						(arc
							(start 0.2794 -0.1778)
							(mid 0.249642 -0.249642)
							(end 0.1778 -0.2794)
						)
					)
					(width 0)
					(fill yes)
				)
			)
		)
	)
	(footprint ""
		(layer "F.Cu")
		(at 219.964 -297.434 180)
		(property "Reference" "PC1190"
			(at 0 0 180)
			(layer "F.SilkS")
			(hide yes)
			(effects
				(font
					(size 1.27 1.27)
				)
			)
		)
		(property "Value" "SC22U25V6KX-GP-U"
			(at -2.860802 -5.279644 180)
			(unlocked yes)
			(layer "F.Fab")
			(hide yes)
			(effects
				(font
					(size 1.016 1.016)
					(thickness 0.1524)
				)
			)
		)
		(property "Device Type" "C1206-TO0D3H75"
			(at -2.860802 -6.803644 180)
			(unlocked yes)
			(layer "F.Fab")
			(hide yes)
			(effects
				(font
					(size 1.016 1.016)
					(thickness 0.1524)
				)
			)
		)
		(duplicate_pad_numbers_are_jumpers no)
		(fp_line
			(start 1.3081 2.3749)
			(end -1.3081 2.3749)
			(stroke
				(width 0.1524)
				(type default)
			)
			(layer "F.SilkS")
		)
		(fp_line
			(start 1.3081 -2.3749)
			(end 1.3081 2.3749)
			(stroke
				(width 0.1524)
				(type default)
			)
			(layer "F.SilkS")
		)
		(fp_line
			(start -1.3081 2.3749)
			(end -1.3081 -2.3749)
			(stroke
				(width 0.1524)
				(type default)
			)
			(layer "F.SilkS")
		)
		(fp_line
			(start -1.3081 -2.3749)
			(end 1.3081 -2.3749)
			(stroke
				(width 0.1524)
				(type default)
			)
			(layer "F.SilkS")
		)
		(fp_rect
			(start -0.8001 1.6002)
			(end 0.8001 -1.6002)
			(stroke
				(width 0)
				(type default)
			)
			(fill no)
			(layer "F.CrtYd")
		)
		(fp_poly
			(pts
				(xy -1.5621 2.4511) (xy -1.5621 1.6002) (xy 0.8001 1.6002) (xy 0.8001 -1.6002) (xy -0.8001 -1.6002)
				(xy -0.8001 1.5875) (xy -1.5621 1.5875) (xy -1.5621 -2.4511) (xy 1.5621 -2.4511) (xy 1.5621 2.4511)
			)
			(stroke
				(width 0)
				(type default)
			)
			(fill no)
			(layer "F.CrtYd")
		)
		(fp_rect
			(start -1.5621 2.4511)
			(end 1.5621 -2.4511)
			(stroke
				(width 0)
				(type default)
			)
			(fill no)
			(layer "F.Fab")
		)
		(pad "1" smd rect
			(at 0 -1.392936 180)
			(size 2.1082 1.4478)
			(layers "F.Cu" "F.Mask" "F.Paste")
			(net "P12V_SSD2")
		)
		(pad "2" smd rect
			(at 0 1.392936 180)
			(size 2.1082 1.4478)
			(layers "F.Cu" "F.Mask" "F.Paste")
			(net "GND")
		)
	)
	(footprint ""
		(layer "F.Cu")
		(at 24.003 -53.34 -90)
		(property "Reference" "R9456"
			(at 0 0 270)
			(layer "F.SilkS")
			(hide yes)
			(effects
				(font
					(size 1.27 1.27)
				)
			)
		)
		(property "Value" "330R2F-GP"
			(at 0.064008 -3.993896 270)
			(unlocked yes)
			(layer "F.Fab")
			(hide yes)
			(effects
				(font
					(size 1.016 1.016)
					(thickness 0.1524)
				)
			)
		)
		(property "Device Type" "R402H16"
			(at 0.064008 -5.517896 270)
			(unlocked yes)
			(layer "F.Fab")
			(hide yes)
			(effects
				(font
					(size 1.016 1.016)
					(thickness 0.1524)
				)
			)
		)
		(duplicate_pad_numbers_are_jumpers no)
		(fp_line
			(start -0.508 -0.9398)
			(end -0.508 0.9398)
			(stroke
				(width 0.1524)
				(type default)
			)
			(layer "F.SilkS")
		)
		(fp_line
			(start 0.508 -0.9398)
			(end -0.508 -0.9398)
			(stroke
				(width 0.1524)
				(type default)
			)
			(layer "F.SilkS")
		)
		(fp_rect
			(start -0.508 0.9398)
			(end 0.508 -0.9398)
			(stroke
				(width 0)
				(type default)
			)
			(fill no)
			(layer "F.CrtYd")
		)
		(fp_rect
			(start -0.508 0.9398)
			(end 0.508 -0.9398)
			(stroke
				(width 0)
				(type default)
			)
			(fill no)
			(layer "F.Fab")
		)
		(pad "1" smd custom
			(at 0 -0.4445 270)
			(size 0.1397 0.1397)
			(layers "F.Cu" "F.Mask" "F.Paste")
			(net "P3V3")
			(options
				(clearance outline)
				(anchor circle)
			)
			(primitives
				(gr_poly
					(pts
						(arc
							(start -0.1778 -0.2794)
							(mid -0.249642 -0.249642)
							(end -0.2794 -0.1778)
						)
						(arc
							(start -0.2794 0.1778)
							(mid -0.249642 0.249642)
							(end -0.1778 0.2794)
						)
						(arc
							(start 0.1778 0.2794)
							(mid 0.249642 0.249642)
							(end 0.2794 0.1778)
						)
						(arc
							(start 0.2794 -0.1778)
							(mid 0.249642 -0.249642)
							(end 0.1778 -0.2794)
						)
					)
					(width 0)
					(fill yes)
				)
			)
		)
		(pad "2" smd custom
			(at 0 0.4445 270)
			(size 0.1397 0.1397)
			(layers "F.Cu" "F.Mask" "F.Paste")
			(net "DRV_ATTN_14")
			(options
				(clearance outline)
				(anchor circle)
			)
			(primitives
				(gr_poly
					(pts
						(arc
							(start -0.1778 -0.2794)
							(mid -0.249642 -0.249642)
							(end -0.2794 -0.1778)
						)
						(arc
							(start -0.2794 0.1778)
							(mid -0.249642 0.249642)
							(end -0.1778 0.2794)
						)
						(arc
							(start 0.1778 0.2794)
							(mid 0.249642 0.249642)
							(end 0.2794 0.1778)
						)
						(arc
							(start 0.2794 -0.1778)
							(mid 0.249642 -0.249642)
							(end 0.1778 -0.2794)
						)
					)
					(width 0)
					(fill yes)
				)
			)
		)
	)
	(footprint ""
		(layer "F.Cu")
		(at 102.616 -205.486 90)
		(property "Reference" "R9085"
			(at 0 0 90)
			(layer "F.SilkS")
			(hide yes)
			(effects
				(font
					(size 1.27 1.27)
				)
			)
		)
		(property "Value" "27R2F-GP"
			(at 0.064008 -3.993896 90)
			(unlocked yes)
			(layer "F.Fab")
			(hide yes)
			(effects
				(font
					(size 1.016 1.016)
					(thickness 0.1524)
				)
			)
		)
		(property "Device Type" "R402H16"
			(at 0.064008 -5.517896 90)
			(unlocked yes)
			(layer "F.Fab")
			(hide yes)
			(effects
				(font
					(size 1.016 1.016)
					(thickness 0.1524)
				)
			)
		)
		(duplicate_pad_numbers_are_jumpers no)
		(fp_line
			(start 0.508 -0.9398)
			(end -0.508 -0.9398)
			(stroke
				(width 0.1524)
				(type default)
			)
			(layer "F.SilkS")
		)
		(fp_line
			(start -0.508 -0.9398)
			(end -0.508 0.9398)
			(stroke
				(width 0.1524)
				(type default)
			)
			(layer "F.SilkS")
		)
		(fp_rect
			(start -0.508 0.9398)
			(end 0.508 -0.9398)
			(stroke
				(width 0)
				(type default)
			)
			(fill no)
			(layer "F.CrtYd")
		)
		(fp_rect
			(start -0.508 0.9398)
			(end 0.508 -0.9398)
			(stroke
				(width 0)
				(type default)
			)
			(fill no)
			(layer "F.Fab")
		)
		(pad "1" smd custom
			(at 0 -0.4445 90)
			(size 0.1397 0.1397)
			(layers "F.Cu" "F.Mask" "F.Paste")
			(net "PE_CLK_100M_DR3_2_R_N")
			(options
				(clearance outline)
				(anchor circle)
			)
			(primitives
				(gr_poly
					(pts
						(arc
							(start -0.1778 -0.2794)
							(mid -0.249642 -0.249642)
							(end -0.2794 -0.1778)
						)
						(arc
							(start -0.2794 0.1778)
							(mid -0.249642 0.249642)
							(end -0.1778 0.2794)
						)
						(arc
							(start 0.1778 0.2794)
							(mid 0.249642 0.249642)
							(end 0.2794 0.1778)
						)
						(arc
							(start 0.2794 -0.1778)
							(mid 0.249642 -0.249642)
							(end 0.1778 -0.2794)
						)
					)
					(width 0)
					(fill yes)
				)
			)
		)
		(pad "2" smd custom
			(at 0 0.4445 90)
			(size 0.1397 0.1397)
			(layers "F.Cu" "F.Mask" "F.Paste")
			(net "PE_CLK100M_DR3_2_N")
			(options
				(clearance outline)
				(anchor circle)
			)
			(primitives
				(gr_poly
					(pts
						(arc
							(start -0.1778 -0.2794)
							(mid -0.249642 -0.249642)
							(end -0.2794 -0.1778)
						)
						(arc
							(start -0.2794 0.1778)
							(mid -0.249642 0.249642)
							(end -0.1778 0.2794)
						)
						(arc
							(start 0.1778 0.2794)
							(mid 0.249642 0.249642)
							(end 0.2794 0.1778)
						)
						(arc
							(start 0.2794 -0.1778)
							(mid 0.249642 -0.249642)
							(end 0.1778 -0.2794)
						)
					)
					(width 0)
					(fill yes)
				)
			)
		)
	)
	(footprint ""
		(layer "F.Cu")
		(at 24.3078 -190.119 180)
		(property "Reference" "R574"
			(at 0 0 180)
			(layer "F.SilkS")
			(hide yes)
			(effects
				(font
					(size 1.27 1.27)
				)
			)
		)
		(property "Value" "300KR2F-GP"
			(at 0.064008 -3.993896 180)
			(unlocked yes)
			(layer "F.Fab")
			(hide yes)
			(effects
				(font
					(size 1.016 1.016)
					(thickness 0.1524)
				)
			)
		)
		(property "Device Type" "R402H16"
			(at 0.064008 -5.517896 180)
			(unlocked yes)
			(layer "F.Fab")
			(hide yes)
			(effects
				(font
					(size 1.016 1.016)
					(thickness 0.1524)
				)
			)
		)
		(duplicate_pad_numbers_are_jumpers no)
		(fp_line
			(start 0.508 -0.9398)
			(end -0.508 -0.9398)
			(stroke
				(width 0.1524)
				(type default)
			)
			(layer "F.SilkS")
		)
		(fp_line
			(start -0.508 -0.9398)
			(end -0.508 0.9398)
			(stroke
				(width 0.1524)
				(type default)
			)
			(layer "F.SilkS")
		)
		(fp_rect
			(start -0.508 0.9398)
			(end 0.508 -0.9398)
			(stroke
				(width 0)
				(type default)
			)
			(fill no)
			(layer "F.CrtYd")
		)
		(fp_rect
			(start -0.508 0.9398)
			(end 0.508 -0.9398)
			(stroke
				(width 0)
				(type default)
			)
			(fill no)
			(layer "F.Fab")
		)
		(pad "1" smd custom
			(at 0 -0.4445 180)
			(size 0.1397 0.1397)
			(layers "F.Cu" "F.Mask" "F.Paste")
			(net "SW_SSD8_N")
			(options
				(clearance outline)
				(anchor circle)
			)
			(primitives
				(gr_poly
					(pts
						(arc
							(start -0.1778 -0.2794)
							(mid -0.249642 -0.249642)
							(end -0.2794 -0.1778)
						)
						(arc
							(start -0.2794 0.1778)
							(mid -0.249642 0.249642)
							(end -0.1778 0.2794)
						)
						(arc
							(start 0.1778 0.2794)
							(mid 0.249642 0.249642)
							(end 0.2794 0.1778)
						)
						(arc
							(start 0.2794 -0.1778)
							(mid 0.249642 -0.249642)
							(end 0.1778 -0.2794)
						)
					)
					(width 0)
					(fill yes)
				)
			)
		)
		(pad "2" smd custom
			(at 0 0.4445 180)
			(size 0.1397 0.1397)
			(layers "F.Cu" "F.Mask" "F.Paste")
			(net "P12V")
			(options
				(clearance outline)
				(anchor circle)
			)
			(primitives
				(gr_poly
					(pts
						(arc
							(start -0.1778 -0.2794)
							(mid -0.249642 -0.249642)
							(end -0.2794 -0.1778)
						)
						(arc
							(start -0.2794 0.1778)
							(mid -0.249642 0.249642)
							(end -0.1778 0.2794)
						)
						(arc
							(start 0.1778 0.2794)
							(mid 0.249642 0.249642)
							(end 0.2794 0.1778)
						)
						(arc
							(start 0.2794 -0.1778)
							(mid 0.249642 -0.249642)
							(end 0.1778 -0.2794)
						)
					)
					(width 0)
					(fill yes)
				)
			)
		)
	)
	(footprint ""
		(layer "F.Cu")
		(at 19.547332 -365.002826 90)
		(property "Reference" "Q85"
			(at 0 0 90)
			(layer "F.SilkS")
			(hide yes)
			(effects
				(font
					(size 1.27 1.27)
				)
			)
		)
		(property "Value" "2N7002A-7-GP"
			(at 0.127 -8.9662 90)
			(unlocked yes)
			(layer "F.Fab")
			(hide yes)
			(effects
				(font
					(size 1.016 1.016)
					(thickness 0.1524)
				)
			)
		)
		(property "Device Type" "SOT23DGS2D4H48"
			(at 0.127 -10.4902 90)
			(unlocked yes)
			(layer "F.Fab")
			(hide yes)
			(effects
				(font
					(size 1.016 1.016)
					(thickness 0.1524)
				)
			)
		)
		(duplicate_pad_numbers_are_jumpers no)
		(fp_line
			(start 1.651 -1.778)
			(end -1.651 -1.778)
			(stroke
				(width 0.1524)
				(type default)
			)
			(layer "F.SilkS")
		)
		(fp_line
			(start -1.651 -1.778)
			(end -1.651 1.778)
			(stroke
				(width 0.1524)
				(type default)
			)
			(layer "F.SilkS")
		)
		(fp_line
			(start 1.651 1.778)
			(end 1.651 -1.778)
			(stroke
				(width 0.1524)
				(type default)
			)
			(layer "F.SilkS")
		)
		(fp_line
			(start -1.651 1.778)
			(end 1.651 1.778)
			(stroke
				(width 0.1524)
				(type default)
			)
			(layer "F.SilkS")
		)
		(fp_poly
			(pts
				(xy -1.778 1.8796) (xy -1.778 -1.8796) (xy 1.778 -1.8796) (xy 1.778 1.8796)
			)
			(stroke
				(width 0)
				(type default)
			)
			(fill no)
			(layer "F.CrtYd")
		)
		(fp_poly
			(pts
				(xy -1.778 1.8796) (xy -1.778 -1.8796) (xy 1.778 -1.8796) (xy 1.778 1.8796)
			)
			(stroke
				(width 0)
				(type default)
			)
			(fill no)
			(layer "F.Fab")
		)
		(pad "D" smd custom
			(at 0 -0.9525 90)
			(size 0.1905 0.1905)
			(layers "F.Cu" "F.Mask" "F.Paste")
			(net "ATTN_LED_DR11_MOS_N")
			(options
				(clearance outline)
				(anchor circle)
			)
			(primitives
				(gr_poly
					(pts
						(arc
							(start -0.1778 0.5715)
							(mid -0.321484 0.511984)
							(end -0.381 0.3683)
						)
						(arc
							(start -0.381 -0.3683)
							(mid -0.321484 -0.511984)
							(end -0.1778 -0.5715)
						)
						(arc
							(start 0.1778 -0.5715)
							(mid 0.321484 -0.511984)
							(end 0.381 -0.3683)
						)
						(arc
							(start 0.381 0.3683)
							(mid 0.321484 0.511984)
							(end 0.1778 0.5715)
						)
					)
					(width 0)
					(fill yes)
				)
			)
		)
		(pad "G" smd custom
			(at -0.98425 0.9525 90)
			(size 0.1905 0.1905)
			(layers "F.Cu" "F.Mask" "F.Paste")
			(net "SSD11_CLK0_OE_MOS_N")
			(options
				(clearance outline)
				(anchor circle)
			)
			(primitives
				(gr_poly
					(pts
						(arc
							(start -0.1778 0.5715)
							(mid -0.321484 0.511984)
							(end -0.381 0.3683)
						)
						(arc
							(start -0.381 -0.3683)
							(mid -0.321484 -0.511984)
							(end -0.1778 -0.5715)
						)
						(arc
							(start 0.1778 -0.5715)
							(mid 0.321484 -0.511984)
							(end 0.381 -0.3683)
						)
						(arc
							(start 0.381 0.3683)
							(mid 0.321484 0.511984)
							(end 0.1778 0.5715)
						)
					)
					(width 0)
					(fill yes)
				)
			)
		)
		(pad "S" smd custom
			(at 0.98425 0.9525 90)
			(size 0.1905 0.1905)
			(layers "F.Cu" "F.Mask" "F.Paste")
			(net "ATTN_LED_DR11_R")
			(options
				(clearance outline)
				(anchor circle)
			)
			(primitives
				(gr_poly
					(pts
						(arc
							(start -0.1778 0.5715)
							(mid -0.321484 0.511984)
							(end -0.381 0.3683)
						)
						(arc
							(start -0.381 -0.3683)
							(mid -0.321484 -0.511984)
							(end -0.1778 -0.5715)
						)
						(arc
							(start 0.1778 -0.5715)
							(mid 0.321484 -0.511984)
							(end 0.381 -0.3683)
						)
						(arc
							(start 0.381 0.3683)
							(mid 0.321484 0.511984)
							(end 0.1778 0.5715)
						)
					)
					(width 0)
					(fill yes)
				)
			)
		)
	)
	(footprint ""
		(layer "F.Cu")
		(at 91.313 -313.817 180)
		(property "Reference" "R9104"
			(at 0 0 180)
			(layer "F.SilkS")
			(hide yes)
			(effects
				(font
					(size 1.27 1.27)
				)
			)
		)
		(property "Value" "27R2F-GP"
			(at 0.064008 -3.993896 180)
			(unlocked yes)
			(layer "F.Fab")
			(hide yes)
			(effects
				(font
					(size 1.016 1.016)
					(thickness 0.1524)
				)
			)
		)
		(property "Device Type" "R402H16"
			(at 0.064008 -5.517896 180)
			(unlocked yes)
			(layer "F.Fab")
			(hide yes)
			(effects
				(font
					(size 1.016 1.016)
					(thickness 0.1524)
				)
			)
		)
		(duplicate_pad_numbers_are_jumpers no)
		(fp_line
			(start 0.508 -0.9398)
			(end -0.508 -0.9398)
			(stroke
				(width 0.1524)
				(type default)
			)
			(layer "F.SilkS")
		)
		(fp_line
			(start -0.508 -0.9398)
			(end -0.508 0.9398)
			(stroke
				(width 0.1524)
				(type default)
			)
			(layer "F.SilkS")
		)
		(fp_rect
			(start -0.508 0.9398)
			(end 0.508 -0.9398)
			(stroke
				(width 0)
				(type default)
			)
			(fill no)
			(layer "F.CrtYd")
		)
		(fp_rect
			(start -0.508 0.9398)
			(end 0.508 -0.9398)
			(stroke
				(width 0)
				(type default)
			)
			(fill no)
			(layer "F.Fab")
		)
		(pad "1" smd custom
			(at 0 -0.4445 180)
			(size 0.1397 0.1397)
			(layers "F.Cu" "F.Mask" "F.Paste")
			(net "PE_CLK_100M_DR11_2_R_P")
			(options
				(clearance outline)
				(anchor circle)
			)
			(primitives
				(gr_poly
					(pts
						(arc
							(start -0.1778 -0.2794)
							(mid -0.249642 -0.249642)
							(end -0.2794 -0.1778)
						)
						(arc
							(start -0.2794 0.1778)
							(mid -0.249642 0.249642)
							(end -0.1778 0.2794)
						)
						(arc
							(start 0.1778 0.2794)
							(mid 0.249642 0.249642)
							(end 0.2794 0.1778)
						)
						(arc
							(start 0.2794 -0.1778)
							(mid 0.249642 -0.249642)
							(end 0.1778 -0.2794)
						)
					)
					(width 0)
					(fill yes)
				)
			)
		)
		(pad "2" smd custom
			(at 0 0.4445 180)
			(size 0.1397 0.1397)
			(layers "F.Cu" "F.Mask" "F.Paste")
			(net "PE_CLK100M_DR11_2_P")
			(options
				(clearance outline)
				(anchor circle)
			)
			(primitives
				(gr_poly
					(pts
						(arc
							(start -0.1778 -0.2794)
							(mid -0.249642 -0.249642)
							(end -0.2794 -0.1778)
						)
						(arc
							(start -0.2794 0.1778)
							(mid -0.249642 0.249642)
							(end -0.1778 0.2794)
						)
						(arc
							(start 0.1778 0.2794)
							(mid 0.249642 0.249642)
							(end 0.2794 0.1778)
						)
						(arc
							(start 0.2794 -0.1778)
							(mid 0.249642 -0.249642)
							(end 0.1778 -0.2794)
						)
					)
					(width 0)
					(fill yes)
				)
			)
		)
	)
	(footprint ""
		(layer "F.Cu")
		(at 28.1432 -392.0998 90)
		(property "Reference" "SR1103"
			(at 0 0 90)
			(layer "F.SilkS")
			(hide yes)
			(effects
				(font
					(size 1.27 1.27)
				)
			)
		)
		(property "Value" "4K7R2F-GP"
			(at 0.064008 -3.993896 90)
			(unlocked yes)
			(layer "F.Fab")
			(hide yes)
			(effects
				(font
					(size 1.016 1.016)
					(thickness 0.1524)
				)
			)
		)
		(property "Device Type" "R402H16"
			(at 0.064008 -5.517896 90)
			(unlocked yes)
			(layer "F.Fab")
			(hide yes)
			(effects
				(font
					(size 1.016 1.016)
					(thickness 0.1524)
				)
			)
		)
		(duplicate_pad_numbers_are_jumpers no)
		(fp_line
			(start 0.508 -0.9398)
			(end -0.508 -0.9398)
			(stroke
				(width 0.1524)
				(type default)
			)
			(layer "F.SilkS")
		)
		(fp_line
			(start -0.508 -0.9398)
			(end -0.508 0.9398)
			(stroke
				(width 0.1524)
				(type default)
			)
			(layer "F.SilkS")
		)
		(fp_rect
			(start -0.508 0.9398)
			(end 0.508 -0.9398)
			(stroke
				(width 0)
				(type default)
			)
			(fill no)
			(layer "F.CrtYd")
		)
		(fp_rect
			(start -0.508 0.9398)
			(end 0.508 -0.9398)
			(stroke
				(width 0)
				(type default)
			)
			(fill no)
			(layer "F.Fab")
		)
		(pad "1" smd custom
			(at 0 -0.4445 90)
			(size 0.1397 0.1397)
			(layers "F.Cu" "F.Mask" "F.Paste")
			(net "P3V3")
			(options
				(clearance outline)
				(anchor circle)
			)
			(primitives
				(gr_poly
					(pts
						(arc
							(start -0.1778 -0.2794)
							(mid -0.249642 -0.249642)
							(end -0.2794 -0.1778)
						)
						(arc
							(start -0.2794 0.1778)
							(mid -0.249642 0.249642)
							(end -0.1778 0.2794)
						)
						(arc
							(start 0.1778 0.2794)
							(mid 0.249642 0.249642)
							(end 0.2794 0.1778)
						)
						(arc
							(start 0.2794 -0.1778)
							(mid 0.249642 -0.249642)
							(end 0.1778 -0.2794)
						)
					)
					(width 0)
					(fill yes)
				)
			)
		)
		(pad "2" smd custom
			(at 0 0.4445 90)
			(size 0.1397 0.1397)
			(layers "F.Cu" "F.Mask" "F.Paste")
			(net "DUALPORTEN#6")
			(options
				(clearance outline)
				(anchor circle)
			)
			(primitives
				(gr_poly
					(pts
						(arc
							(start -0.1778 -0.2794)
							(mid -0.249642 -0.249642)
							(end -0.2794 -0.1778)
						)
						(arc
							(start -0.2794 0.1778)
							(mid -0.249642 0.249642)
							(end -0.1778 0.2794)
						)
						(arc
							(start 0.1778 0.2794)
							(mid 0.249642 0.249642)
							(end 0.2794 0.1778)
						)
						(arc
							(start 0.2794 -0.1778)
							(mid 0.249642 -0.249642)
							(end 0.1778 -0.2794)
						)
					)
					(width 0)
					(fill yes)
				)
			)
		)
	)
	(footprint ""
		(layer "F.Cu")
		(at 35.0012 -292.2524)
		(property "Reference" "PC1246"
			(at 0 0 0)
			(layer "F.SilkS")
			(hide yes)
			(effects
				(font
					(size 1.27 1.27)
				)
			)
		)
		(property "Value" "SC22U25V6KX-GP-U"
			(at -2.860802 -5.279644 0)
			(unlocked yes)
			(layer "F.Fab")
			(hide yes)
			(effects
				(font
					(size 1.016 1.016)
					(thickness 0.1524)
				)
			)
		)
		(property "Device Type" "C1206-TO0D3H75"
			(at -2.860802 -6.803644 0)
			(unlocked yes)
			(layer "F.Fab")
			(hide yes)
			(effects
				(font
					(size 1.016 1.016)
					(thickness 0.1524)
				)
			)
		)
		(duplicate_pad_numbers_are_jumpers no)
		(fp_line
			(start -1.3081 -2.3749)
			(end 1.3081 -2.3749)
			(stroke
				(width 0.1524)
				(type default)
			)
			(layer "F.SilkS")
		)
		(fp_line
			(start -1.3081 2.3749)
			(end -1.3081 -2.3749)
			(stroke
				(width 0.1524)
				(type default)
			)
			(layer "F.SilkS")
		)
		(fp_line
			(start 1.3081 -2.3749)
			(end 1.3081 2.3749)
			(stroke
				(width 0.1524)
				(type default)
			)
			(layer "F.SilkS")
		)
		(fp_line
			(start 1.3081 2.3749)
			(end -1.3081 2.3749)
			(stroke
				(width 0.1524)
				(type default)
			)
			(layer "F.SilkS")
		)
		(fp_rect
			(start -0.8001 1.6002)
			(end 0.8001 -1.6002)
			(stroke
				(width 0)
				(type default)
			)
			(fill no)
			(layer "F.CrtYd")
		)
		(fp_poly
			(pts
				(xy -1.5621 2.4511) (xy -1.5621 1.6002) (xy 0.8001 1.6002) (xy 0.8001 -1.6002) (xy -0.8001 -1.6002)
				(xy -0.8001 1.5875) (xy -1.5621 1.5875) (xy -1.5621 -2.4511) (xy 1.5621 -2.4511) (xy 1.5621 2.4511)
			)
			(stroke
				(width 0)
				(type default)
			)
			(fill no)
			(layer "F.CrtYd")
		)
		(fp_poly
			(pts
				(xy -1.5621 2.4511) (xy 1.5621 2.4511) (xy 1.5621 -2.4511) (xy -1.5621 -2.4511)
			)
			(stroke
				(width 0)
				(type default)
			)
			(fill no)
			(layer "F.Fab")
		)
		(pad "1" smd rect
			(at 0 -1.392936)
			(size 2.1082 1.4478)
			(layers "F.Cu" "F.Mask" "F.Paste")
			(net "P12V_SSD7")
		)
		(pad "2" smd rect
			(at 0 1.392936)
			(size 2.1082 1.4478)
			(layers "F.Cu" "F.Mask" "F.Paste")
			(net "GND")
		)
	)
	(footprint ""
		(layer "F.Cu")
		(at 22.4028 -470.0016 180)
		(property "Reference" "U207"
			(at 0 0 180)
			(layer "F.SilkS")
			(hide yes)
			(effects
				(font
					(size 1.27 1.27)
				)
			)
		)
		(property "Value" "SN74LVC1G08DCKR-GP"
			(at -2.3368 -8.6868 180)
			(unlocked yes)
			(layer "F.Fab")
			(hide yes)
			(effects
				(font
					(size 1.016 1.016)
					(thickness 0.1524)
				)
			)
		)
		(property "Device Type" "SC70-5H44"
			(at -2.3114 -10.414 180)
			(unlocked yes)
			(layer "F.Fab")
			(hide yes)
			(effects
				(font
					(size 1.016 1.016)
					(thickness 0.1524)
				)
			)
		)
		(duplicate_pad_numbers_are_jumpers no)
		(fp_line
			(start 1.3843 -1.8034)
			(end 1.3843 -1.1176)
			(stroke
				(width 0.3302)
				(type default)
			)
			(layer "F.SilkS")
		)
		(fp_line
			(start 1.27 1.7018)
			(end -1.27 1.7018)
			(stroke
				(width 0.1524)
				(type default)
			)
			(layer "F.SilkS")
		)
		(fp_line
			(start 1.27 -1.7018)
			(end 1.27 1.7018)
			(stroke
				(width 0.1524)
				(type default)
			)
			(layer "F.SilkS")
		)
		(fp_line
			(start 0.6604 -1.8034)
			(end 1.3843 -1.8034)
			(stroke
				(width 0.3302)
				(type default)
			)
			(layer "F.SilkS")
		)
		(fp_line
			(start -1.27 1.7018)
			(end -1.27 -1.7018)
			(stroke
				(width 0.1524)
				(type default)
			)
			(layer "F.SilkS")
		)
		(fp_line
			(start -1.27 -1.7018)
			(end 1.27 -1.7018)
			(stroke
				(width 0.1524)
				(type default)
			)
			(layer "F.SilkS")
		)
		(fp_rect
			(start -1.524 1.9558)
			(end 1.524 -1.9558)
			(stroke
				(width 0)
				(type default)
			)
			(fill no)
			(layer "F.CrtYd")
		)
		(fp_poly
			(pts
				(xy -1.524 -1.9558) (xy 1.524 -1.9558) (xy 1.524 1.9558) (xy -1.524 1.9558)
			)
			(stroke
				(width 0)
				(type default)
			)
			(fill no)
			(layer "F.Fab")
		)
		(pad "1" smd rect
			(at 0.65024 -0.8255 180)
			(size 0.4064 1.2192)
			(layers "F.Cu" "F.Mask" "F.Paste")
			(net "SSD10_CLK0_OE_MOS_N")
		)
		(pad "2" smd rect
			(at 0 -0.8255 180)
			(size 0.4064 1.2192)
			(layers "F.Cu" "F.Mask" "F.Paste")
			(net "ATTN_LED_DR10_N")
		)
		(pad "3" smd rect
			(at -0.65024 -0.8255 180)
			(size 0.4064 1.2192)
			(layers "F.Cu" "F.Mask" "F.Paste")
			(net "GND")
		)
		(pad "4" smd rect
			(at -0.65024 0.8255 180)
			(size 0.4064 1.2192)
			(layers "F.Cu" "F.Mask" "F.Paste")
			(net "ATTN_LED_DR10_AND")
		)
		(pad "5" smd rect
			(at 0.65024 0.8255 180)
			(size 0.4064 1.2192)
			(layers "F.Cu" "F.Mask" "F.Paste")
			(net "P3V3")
		)
	)
	(footprint ""
		(layer "F.Cu")
		(at 81.661 -363.1438 -90)
		(property "Reference" "SR987"
			(at 0 0 270)
			(layer "F.SilkS")
			(hide yes)
			(effects
				(font
					(size 1.27 1.27)
				)
			)
		)
		(property "Value" "2KR2F-3-GP"
			(at 0.064008 -3.993896 270)
			(unlocked yes)
			(layer "F.Fab")
			(hide yes)
			(effects
				(font
					(size 1.016 1.016)
					(thickness 0.1524)
				)
			)
		)
		(property "Device Type" "R402H16"
			(at 0.064008 -5.517896 270)
			(unlocked yes)
			(layer "F.Fab")
			(hide yes)
			(effects
				(font
					(size 1.016 1.016)
					(thickness 0.1524)
				)
			)
		)
		(duplicate_pad_numbers_are_jumpers no)
		(fp_line
			(start -0.508 -0.9398)
			(end -0.508 0.9398)
			(stroke
				(width 0.1524)
				(type default)
			)
			(layer "F.SilkS")
		)
		(fp_line
			(start 0.508 -0.9398)
			(end -0.508 -0.9398)
			(stroke
				(width 0.1524)
				(type default)
			)
			(layer "F.SilkS")
		)
		(fp_rect
			(start -0.508 0.9398)
			(end 0.508 -0.9398)
			(stroke
				(width 0)
				(type default)
			)
			(fill no)
			(layer "F.CrtYd")
		)
		(fp_rect
			(start -0.508 0.9398)
			(end 0.508 -0.9398)
			(stroke
				(width 0)
				(type default)
			)
			(fill no)
			(layer "F.Fab")
		)
		(pad "1" smd custom
			(at 0 -0.4445 270)
			(size 0.1397 0.1397)
			(layers "F.Cu" "F.Mask" "F.Paste")
			(net "P3V3")
			(options
				(clearance outline)
				(anchor circle)
			)
			(primitives
				(gr_poly
					(pts
						(arc
							(start -0.1778 -0.2794)
							(mid -0.249642 -0.249642)
							(end -0.2794 -0.1778)
						)
						(arc
							(start -0.2794 0.1778)
							(mid -0.249642 0.249642)
							(end -0.1778 0.2794)
						)
						(arc
							(start 0.1778 0.2794)
							(mid 0.249642 0.249642)
							(end 0.2794 0.1778)
						)
						(arc
							(start 0.2794 -0.1778)
							(mid 0.249642 -0.249642)
							(end 0.1778 -0.2794)
						)
					)
					(width 0)
					(fill yes)
				)
			)
		)
		(pad "2" smd custom
			(at 0 0.4445 270)
			(size 0.1397 0.1397)
			(layers "F.Cu" "F.Mask" "F.Paste")
			(net "SDA_DR0")
			(options
				(clearance outline)
				(anchor circle)
			)
			(primitives
				(gr_poly
					(pts
						(arc
							(start -0.1778 -0.2794)
							(mid -0.249642 -0.249642)
							(end -0.2794 -0.1778)
						)
						(arc
							(start -0.2794 0.1778)
							(mid -0.249642 0.249642)
							(end -0.1778 0.2794)
						)
						(arc
							(start 0.1778 0.2794)
							(mid 0.249642 0.249642)
							(end 0.2794 0.1778)
						)
						(arc
							(start 0.2794 -0.1778)
							(mid 0.249642 -0.249642)
							(end 0.1778 -0.2794)
						)
					)
					(width 0)
					(fill yes)
				)
			)
		)
	)
	(footprint ""
		(layer "F.Cu")
		(at 24.003 -361.188 -90)
		(property "Reference" "R9436"
			(at 0 0 270)
			(layer "F.SilkS")
			(hide yes)
			(effects
				(font
					(size 1.27 1.27)
				)
			)
		)
		(property "Value" "100R2J-2-GP"
			(at 0.064008 -3.993896 270)
			(unlocked yes)
			(layer "F.Fab")
			(hide yes)
			(effects
				(font
					(size 1.016 1.016)
					(thickness 0.1524)
				)
			)
		)
		(property "Device Type" "R402H14"
			(at 0.064008 -5.517896 270)
			(unlocked yes)
			(layer "F.Fab")
			(hide yes)
			(effects
				(font
					(size 1.016 1.016)
					(thickness 0.1524)
				)
			)
		)
		(duplicate_pad_numbers_are_jumpers no)
		(fp_line
			(start -0.508 -0.9398)
			(end -0.508 0.9398)
			(stroke
				(width 0.1524)
				(type default)
			)
			(layer "F.SilkS")
		)
		(fp_line
			(start 0.508 -0.9398)
			(end -0.508 -0.9398)
			(stroke
				(width 0.1524)
				(type default)
			)
			(layer "F.SilkS")
		)
		(fp_rect
			(start -0.508 0.9398)
			(end 0.508 -0.9398)
			(stroke
				(width 0)
				(type default)
			)
			(fill no)
			(layer "F.CrtYd")
		)
		(fp_rect
			(start -0.508 0.9398)
			(end 0.508 -0.9398)
			(stroke
				(width 0)
				(type default)
			)
			(fill no)
			(layer "F.Fab")
		)
		(pad "1" smd custom
			(at 0 -0.4445 270)
			(size 0.1397 0.1397)
			(layers "F.Cu" "F.Mask" "F.Paste")
			(net "P3V3")
			(options
				(clearance outline)
				(anchor circle)
			)
			(primitives
				(gr_poly
					(pts
						(arc
							(start -0.1778 -0.2794)
							(mid -0.249642 -0.249642)
							(end -0.2794 -0.1778)
						)
						(arc
							(start -0.2794 0.1778)
							(mid -0.249642 0.249642)
							(end -0.1778 0.2794)
						)
						(arc
							(start 0.1778 0.2794)
							(mid 0.249642 0.249642)
							(end 0.2794 0.1778)
						)
						(arc
							(start 0.2794 -0.1778)
							(mid 0.249642 -0.249642)
							(end 0.1778 -0.2794)
						)
					)
					(width 0)
					(fill yes)
				)
			)
		)
		(pad "2" smd custom
			(at 0 0.4445 270)
			(size 0.1397 0.1397)
			(layers "F.Cu" "F.Mask" "F.Paste")
			(net "DRV_ACT_11")
			(options
				(clearance outline)
				(anchor circle)
			)
			(primitives
				(gr_poly
					(pts
						(arc
							(start -0.1778 -0.2794)
							(mid -0.249642 -0.249642)
							(end -0.2794 -0.1778)
						)
						(arc
							(start -0.2794 0.1778)
							(mid -0.249642 0.249642)
							(end -0.1778 0.2794)
						)
						(arc
							(start 0.1778 0.2794)
							(mid 0.249642 0.249642)
							(end 0.2794 0.1778)
						)
						(arc
							(start 0.2794 -0.1778)
							(mid 0.249642 -0.249642)
							(end 0.1778 -0.2794)
						)
					)
					(width 0)
					(fill yes)
				)
			)
		)
	)
	(footprint ""
		(layer "F.Cu")
		(at 77.4954 -102.1842 180)
		(property "Reference" "R9975"
			(at 0 0 180)
			(layer "F.SilkS")
			(hide yes)
			(effects
				(font
					(size 1.27 1.27)
				)
			)
		)
		(property "Value" "56R2F-1-GP"
			(at 0.064008 -3.993896 180)
			(unlocked yes)
			(layer "F.Fab")
			(hide yes)
			(effects
				(font
					(size 1.016 1.016)
					(thickness 0.1524)
				)
			)
		)
		(property "Device Type" "R402H16"
			(at 0.064008 -5.517896 180)
			(unlocked yes)
			(layer "F.Fab")
			(hide yes)
			(effects
				(font
					(size 1.016 1.016)
					(thickness 0.1524)
				)
			)
		)
		(duplicate_pad_numbers_are_jumpers no)
		(fp_line
			(start 0.508 -0.9398)
			(end -0.508 -0.9398)
			(stroke
				(width 0.1524)
				(type default)
			)
			(layer "F.SilkS")
		)
		(fp_line
			(start -0.508 -0.9398)
			(end -0.508 0.9398)
			(stroke
				(width 0.1524)
				(type default)
			)
			(layer "F.SilkS")
		)
		(fp_rect
			(start -0.508 0.9398)
			(end 0.508 -0.9398)
			(stroke
				(width 0)
				(type default)
			)
			(fill no)
			(layer "F.CrtYd")
		)
		(fp_rect
			(start -0.508 0.9398)
			(end 0.508 -0.9398)
			(stroke
				(width 0)
				(type default)
			)
			(fill no)
			(layer "F.Fab")
		)
		(pad "1" smd custom
			(at 0 -0.4445 180)
			(size 0.1397 0.1397)
			(layers "F.Cu" "F.Mask" "F.Paste")
			(net "PE_100M_CLK1_P")
			(options
				(clearance outline)
				(anchor circle)
			)
			(primitives
				(gr_poly
					(pts
						(arc
							(start -0.1778 -0.2794)
							(mid -0.249642 -0.249642)
							(end -0.2794 -0.1778)
						)
						(arc
							(start -0.2794 0.1778)
							(mid -0.249642 0.249642)
							(end -0.1778 0.2794)
						)
						(arc
							(start 0.1778 0.2794)
							(mid 0.249642 0.249642)
							(end 0.2794 0.1778)
						)
						(arc
							(start 0.2794 -0.1778)
							(mid 0.249642 -0.249642)
							(end 0.1778 -0.2794)
						)
					)
					(width 0)
					(fill yes)
				)
			)
		)
		(pad "2" smd custom
			(at 0 0.4445 180)
			(size 0.1397 0.1397)
			(layers "F.Cu" "F.Mask" "F.Paste")
			(net "GND")
			(options
				(clearance outline)
				(anchor circle)
			)
			(primitives
				(gr_poly
					(pts
						(arc
							(start -0.1778 -0.2794)
							(mid -0.249642 -0.249642)
							(end -0.2794 -0.1778)
						)
						(arc
							(start -0.2794 0.1778)
							(mid -0.249642 0.249642)
							(end -0.1778 0.2794)
						)
						(arc
							(start 0.1778 0.2794)
							(mid 0.249642 0.249642)
							(end 0.2794 0.1778)
						)
						(arc
							(start 0.2794 -0.1778)
							(mid 0.249642 -0.249642)
							(end 0.1778 -0.2794)
						)
					)
					(width 0)
					(fill yes)
				)
			)
		)
	)
	(footprint ""
		(layer "F.Cu")
		(at 19.547332 -159.002984 90)
		(property "Reference" "Q95"
			(at 0 0 90)
			(layer "F.SilkS")
			(hide yes)
			(effects
				(font
					(size 1.27 1.27)
				)
			)
		)
		(property "Value" "2N7002A-7-GP"
			(at 0.127 -8.9662 90)
			(unlocked yes)
			(layer "F.Fab")
			(hide yes)
			(effects
				(font
					(size 1.016 1.016)
					(thickness 0.1524)
				)
			)
		)
		(property "Device Type" "SOT23DGS2D4H48"
			(at 0.127 -10.4902 90)
			(unlocked yes)
			(layer "F.Fab")
			(hide yes)
			(effects
				(font
					(size 1.016 1.016)
					(thickness 0.1524)
				)
			)
		)
		(duplicate_pad_numbers_are_jumpers no)
		(fp_line
			(start 1.651 -1.778)
			(end -1.651 -1.778)
			(stroke
				(width 0.1524)
				(type default)
			)
			(layer "F.SilkS")
		)
		(fp_line
			(start -1.651 -1.778)
			(end -1.651 1.778)
			(stroke
				(width 0.1524)
				(type default)
			)
			(layer "F.SilkS")
		)
		(fp_line
			(start 1.651 1.778)
			(end 1.651 -1.778)
			(stroke
				(width 0.1524)
				(type default)
			)
			(layer "F.SilkS")
		)
		(fp_line
			(start -1.651 1.778)
			(end 1.651 1.778)
			(stroke
				(width 0.1524)
				(type default)
			)
			(layer "F.SilkS")
		)
		(fp_poly
			(pts
				(xy -1.778 1.8796) (xy -1.778 -1.8796) (xy 1.778 -1.8796) (xy 1.778 1.8796)
			)
			(stroke
				(width 0)
				(type default)
			)
			(fill no)
			(layer "F.CrtYd")
		)
		(fp_poly
			(pts
				(xy -1.778 1.8796) (xy -1.778 -1.8796) (xy 1.778 -1.8796) (xy 1.778 1.8796)
			)
			(stroke
				(width 0)
				(type default)
			)
			(fill no)
			(layer "F.Fab")
		)
		(pad "D" smd custom
			(at 0 -0.9525 90)
			(size 0.1905 0.1905)
			(layers "F.Cu" "F.Mask" "F.Paste")
			(net "ATTN_LED_DR13_MOS_N")
			(options
				(clearance outline)
				(anchor circle)
			)
			(primitives
				(gr_poly
					(pts
						(arc
							(start -0.1778 0.5715)
							(mid -0.321484 0.511984)
							(end -0.381 0.3683)
						)
						(arc
							(start -0.381 -0.3683)
							(mid -0.321484 -0.511984)
							(end -0.1778 -0.5715)
						)
						(arc
							(start 0.1778 -0.5715)
							(mid 0.321484 -0.511984)
							(end 0.381 -0.3683)
						)
						(arc
							(start 0.381 0.3683)
							(mid 0.321484 0.511984)
							(end 0.1778 0.5715)
						)
					)
					(width 0)
					(fill yes)
				)
			)
		)
		(pad "G" smd custom
			(at -0.98425 0.9525 90)
			(size 0.1905 0.1905)
			(layers "F.Cu" "F.Mask" "F.Paste")
			(net "SSD13_CLK0_OE_MOS_N")
			(options
				(clearance outline)
				(anchor circle)
			)
			(primitives
				(gr_poly
					(pts
						(arc
							(start -0.1778 0.5715)
							(mid -0.321484 0.511984)
							(end -0.381 0.3683)
						)
						(arc
							(start -0.381 -0.3683)
							(mid -0.321484 -0.511984)
							(end -0.1778 -0.5715)
						)
						(arc
							(start 0.1778 -0.5715)
							(mid 0.321484 -0.511984)
							(end 0.381 -0.3683)
						)
						(arc
							(start 0.381 0.3683)
							(mid 0.321484 0.511984)
							(end 0.1778 0.5715)
						)
					)
					(width 0)
					(fill yes)
				)
			)
		)
		(pad "S" smd custom
			(at 0.98425 0.9525 90)
			(size 0.1905 0.1905)
			(layers "F.Cu" "F.Mask" "F.Paste")
			(net "ATTN_LED_DR13_R")
			(options
				(clearance outline)
				(anchor circle)
			)
			(primitives
				(gr_poly
					(pts
						(arc
							(start -0.1778 0.5715)
							(mid -0.321484 0.511984)
							(end -0.381 0.3683)
						)
						(arc
							(start -0.381 -0.3683)
							(mid -0.321484 -0.511984)
							(end -0.1778 -0.5715)
						)
						(arc
							(start 0.1778 -0.5715)
							(mid 0.321484 -0.511984)
							(end 0.381 -0.3683)
						)
						(arc
							(start 0.381 0.3683)
							(mid 0.321484 0.511984)
							(end 0.1778 0.5715)
						)
					)
					(width 0)
					(fill yes)
				)
			)
		)
	)
	(footprint ""
		(layer "F.Cu")
		(at 37.5666 -417.3474 90)
		(property "Reference" "R148"
			(at 0 0 90)
			(layer "F.SilkS")
			(hide yes)
			(effects
				(font
					(size 1.27 1.27)
				)
			)
		)
		(property "Value" "4K7R2J-2-GP"
			(at 0.064008 -3.993896 90)
			(unlocked yes)
			(layer "F.Fab")
			(hide yes)
			(effects
				(font
					(size 1.016 1.016)
					(thickness 0.1524)
				)
			)
		)
		(property "Device Type" "R402H16"
			(at 0.064008 -5.517896 90)
			(unlocked yes)
			(layer "F.Fab")
			(hide yes)
			(effects
				(font
					(size 1.016 1.016)
					(thickness 0.1524)
				)
			)
		)
		(duplicate_pad_numbers_are_jumpers no)
		(fp_line
			(start 0.508 -0.9398)
			(end -0.508 -0.9398)
			(stroke
				(width 0.1524)
				(type default)
			)
			(layer "F.SilkS")
		)
		(fp_line
			(start -0.508 -0.9398)
			(end -0.508 0.9398)
			(stroke
				(width 0.1524)
				(type default)
			)
			(layer "F.SilkS")
		)
		(fp_rect
			(start -0.508 0.9398)
			(end 0.508 -0.9398)
			(stroke
				(width 0)
				(type default)
			)
			(fill no)
			(layer "F.CrtYd")
		)
		(fp_rect
			(start -0.508 0.9398)
			(end 0.508 -0.9398)
			(stroke
				(width 0)
				(type default)
			)
			(fill no)
			(layer "F.Fab")
		)
		(pad "1" smd custom
			(at 0 -0.4445 90)
			(size 0.1397 0.1397)
			(layers "F.Cu" "F.Mask" "F.Paste")
			(net "P12V")
			(options
				(clearance outline)
				(anchor circle)
			)
			(primitives
				(gr_poly
					(pts
						(arc
							(start -0.1778 -0.2794)
							(mid -0.249642 -0.249642)
							(end -0.2794 -0.1778)
						)
						(arc
							(start -0.2794 0.1778)
							(mid -0.249642 0.249642)
							(end -0.1778 0.2794)
						)
						(arc
							(start 0.1778 0.2794)
							(mid 0.249642 0.249642)
							(end 0.2794 0.1778)
						)
						(arc
							(start 0.2794 -0.1778)
							(mid 0.249642 -0.249642)
							(end 0.1778 -0.2794)
						)
					)
					(width 0)
					(fill yes)
				)
			)
		)
		(pad "2" smd custom
			(at 0 0.4445 90)
			(size 0.1397 0.1397)
			(layers "F.Cu" "F.Mask" "F.Paste")
			(net "SW_SSD10_R")
			(options
				(clearance outline)
				(anchor circle)
			)
			(primitives
				(gr_poly
					(pts
						(arc
							(start -0.1778 -0.2794)
							(mid -0.249642 -0.249642)
							(end -0.2794 -0.1778)
						)
						(arc
							(start -0.2794 0.1778)
							(mid -0.249642 0.249642)
							(end -0.1778 0.2794)
						)
						(arc
							(start 0.1778 0.2794)
							(mid 0.249642 0.249642)
							(end 0.2794 0.1778)
						)
						(arc
							(start 0.2794 -0.1778)
							(mid 0.249642 -0.249642)
							(end 0.1778 -0.2794)
						)
					)
					(width 0)
					(fill yes)
				)
			)
		)
	)
	(footprint ""
		(layer "F.Cu")
		(at 10.4394 -412.5976)
		(property "Reference" "R579"
			(at 0 0 0)
			(layer "F.SilkS")
			(hide yes)
			(effects
				(font
					(size 1.27 1.27)
				)
			)
		)
		(property "Value" "2R2010J-1-GP"
			(at 0.254 -8.0772 0)
			(unlocked yes)
			(layer "F.Fab")
			(hide yes)
			(effects
				(font
					(size 1.016 1.016)
					(thickness 0.1524)
				)
			)
		)
		(property "Device Type" "R2010H28"
			(at 0.254 -9.6774 0)
			(unlocked yes)
			(layer "F.Fab")
			(hide yes)
			(effects
				(font
					(size 1.016 1.016)
					(thickness 0.1524)
				)
			)
		)
		(duplicate_pad_numbers_are_jumpers no)
		(fp_line
			(start -1.651 -3.302)
			(end -1.651 3.302)
			(stroke
				(width 0.1524)
				(type default)
			)
			(layer "F.SilkS")
		)
		(fp_line
			(start -1.651 3.302)
			(end 1.651 3.302)
			(stroke
				(width 0.1524)
				(type default)
			)
			(layer "F.SilkS")
		)
		(fp_line
			(start 1.651 -3.302)
			(end -1.651 -3.302)
			(stroke
				(width 0.1524)
				(type default)
			)
			(layer "F.SilkS")
		)
		(fp_line
			(start 1.651 3.302)
			(end 1.651 -3.302)
			(stroke
				(width 0.1524)
				(type default)
			)
			(layer "F.SilkS")
		)
		(fp_rect
			(start -1.7272 -3.3782)
			(end 1.7272 3.3782)
			(stroke
				(width 0)
				(type default)
			)
			(fill no)
			(layer "F.CrtYd")
		)
		(fp_poly
			(pts
				(xy 1.7272 3.3782) (xy 1.7272 -3.3782) (xy -1.7272 -3.3782) (xy -1.7272 3.3782)
			)
			(stroke
				(width 0)
				(type default)
			)
			(fill no)
			(layer "F.Fab")
		)
		(pad "1" smd rect
			(at 0 -2.3495)
			(size 2.794 1.143)
			(layers "F.Cu" "F.Mask" "F.Paste")
			(net "PCIE_MATED#_A")
		)
		(pad "2" smd rect
			(at 0 2.3495)
			(size 2.794 1.143)
			(layers "F.Cu" "F.Mask" "F.Paste")
			(net "GND")
		)
	)
	(footprint ""
		(layer "F.Cu")
		(at 35.941 -301.2186 -90)
		(property "Reference" "R9826"
			(at 0 0 270)
			(layer "F.SilkS")
			(hide yes)
			(effects
				(font
					(size 1.27 1.27)
				)
			)
		)
		(property "Value" "2K2R5F-GP"
			(at 0 -8.9535 270)
			(unlocked yes)
			(layer "F.Fab")
			(hide yes)
			(effects
				(font
					(size 1.27 1.016)
					(thickness 0.1524)
				)
			)
		)
		(property "Device Type" "R805H24"
			(at 0 -10.6299 270)
			(unlocked yes)
			(layer "F.Fab")
			(hide yes)
			(effects
				(font
					(size 1.27 1.016)
					(thickness 0.1524)
				)
			)
		)
		(duplicate_pad_numbers_are_jumpers no)
		(fp_line
			(start -0.889 1.7018)
			(end 0.889 1.7018)
			(stroke
				(width 0.1524)
				(type default)
			)
			(layer "F.SilkS")
		)
		(fp_line
			(start 0.889 1.7018)
			(end 0.889 -0.508)
			(stroke
				(width 0.1524)
				(type default)
			)
			(layer "F.SilkS")
		)
		(fp_line
			(start -0.889 0.0762)
			(end -0.889 1.7018)
			(stroke
				(width 0.1524)
				(type default)
			)
			(layer "F.SilkS")
		)
		(fp_line
			(start -0.889 -1.7018)
			(end -0.889 0.2794)
			(stroke
				(width 0.1524)
				(type default)
			)
			(layer "F.SilkS")
		)
		(fp_line
			(start 0.889 -1.7018)
			(end 0.889 -0.381)
			(stroke
				(width 0.1524)
				(type default)
			)
			(layer "F.SilkS")
		)
		(fp_line
			(start 0.889 -1.7018)
			(end -0.889 -1.7018)
			(stroke
				(width 0.1524)
				(type default)
			)
			(layer "F.SilkS")
		)
		(fp_poly
			(pts
				(xy 0.9652 -1.778) (xy 0.9652 1.778) (xy -0.9652 1.778) (xy -0.9652 -1.778)
			)
			(stroke
				(width 0)
				(type default)
			)
			(fill no)
			(layer "F.CrtYd")
		)
		(fp_rect
			(start -0.9652 1.778)
			(end 0.9652 -1.778)
			(stroke
				(width 0)
				(type default)
			)
			(fill no)
			(layer "F.Fab")
		)
		(pad "1" smd rect
			(at 0 -0.9652 270)
			(size 1.397 1.143)
			(layers "F.Cu" "F.Mask" "F.Paste")
			(net "P12V_SSD7")
		)
		(pad "2" smd rect
			(at 0 0.9652 270)
			(size 1.397 1.143)
			(layers "F.Cu" "F.Mask" "F.Paste")
			(net "P12V_MOST7_GATE_D")
		)
	)
	(footprint ""
		(layer "F.Cu")
		(at 107.442 -307.848 -90)
		(property "Reference" "R9452"
			(at 0 0 270)
			(layer "F.SilkS")
			(hide yes)
			(effects
				(font
					(size 1.27 1.27)
				)
			)
		)
		(property "Value" "10R2F-L-GP"
			(at 0.064008 -3.993896 270)
			(unlocked yes)
			(layer "F.Fab")
			(hide yes)
			(effects
				(font
					(size 1.016 1.016)
					(thickness 0.1524)
				)
			)
		)
		(property "Device Type" "R402H14"
			(at 0.064008 -5.517896 270)
			(unlocked yes)
			(layer "F.Fab")
			(hide yes)
			(effects
				(font
					(size 1.016 1.016)
					(thickness 0.1524)
				)
			)
		)
		(duplicate_pad_numbers_are_jumpers no)
		(fp_line
			(start -0.508 -0.9398)
			(end -0.508 0.9398)
			(stroke
				(width 0.1524)
				(type default)
			)
			(layer "F.SilkS")
		)
		(fp_line
			(start 0.508 -0.9398)
			(end -0.508 -0.9398)
			(stroke
				(width 0.1524)
				(type default)
			)
			(layer "F.SilkS")
		)
		(fp_rect
			(start -0.508 0.9398)
			(end 0.508 -0.9398)
			(stroke
				(width 0)
				(type default)
			)
			(fill no)
			(layer "F.CrtYd")
		)
		(fp_rect
			(start -0.508 0.9398)
			(end 0.508 -0.9398)
			(stroke
				(width 0)
				(type default)
			)
			(fill no)
			(layer "F.Fab")
		)
		(pad "1" smd custom
			(at 0 -0.4445 270)
			(size 0.1397 0.1397)
			(layers "F.Cu" "F.Mask" "F.Paste")
			(net "SSD_PRSNT_NET1")
			(options
				(clearance outline)
				(anchor circle)
			)
			(primitives
				(gr_poly
					(pts
						(arc
							(start -0.1778 -0.2794)
							(mid -0.249642 -0.249642)
							(end -0.2794 -0.1778)
						)
						(arc
							(start -0.2794 0.1778)
							(mid -0.249642 0.249642)
							(end -0.1778 0.2794)
						)
						(arc
							(start 0.1778 0.2794)
							(mid 0.249642 0.249642)
							(end 0.2794 0.1778)
						)
						(arc
							(start 0.2794 -0.1778)
							(mid 0.249642 -0.249642)
							(end 0.1778 -0.2794)
						)
					)
					(width 0)
					(fill yes)
				)
			)
		)
		(pad "2" smd custom
			(at 0 0.4445 270)
			(size 0.1397 0.1397)
			(layers "F.Cu" "F.Mask" "F.Paste")
			(net "SSD_PRSNT1")
			(options
				(clearance outline)
				(anchor circle)
			)
			(primitives
				(gr_poly
					(pts
						(arc
							(start -0.1778 -0.2794)
							(mid -0.249642 -0.249642)
							(end -0.2794 -0.1778)
						)
						(arc
							(start -0.2794 0.1778)
							(mid -0.249642 0.249642)
							(end -0.1778 0.2794)
						)
						(arc
							(start 0.1778 0.2794)
							(mid 0.249642 0.249642)
							(end 0.2794 0.1778)
						)
						(arc
							(start 0.2794 -0.1778)
							(mid 0.249642 -0.249642)
							(end 0.1778 -0.2794)
						)
					)
					(width 0)
					(fill yes)
				)
			)
		)
	)
	(footprint ""
		(layer "F.Cu")
		(at 208.534 -94.234)
		(property "Reference" "R9764"
			(at 0 0 0)
			(layer "F.SilkS")
			(hide yes)
			(effects
				(font
					(size 1.27 1.27)
				)
			)
		)
		(property "Value" "4K7R2J-2-GP"
			(at 0.064008 -3.993896 0)
			(unlocked yes)
			(layer "F.Fab")
			(hide yes)
			(effects
				(font
					(size 1.016 1.016)
					(thickness 0.1524)
				)
			)
		)
		(property "Device Type" "R402H16"
			(at 0.064008 -5.517896 0)
			(unlocked yes)
			(layer "F.Fab")
			(hide yes)
			(effects
				(font
					(size 1.016 1.016)
					(thickness 0.1524)
				)
			)
		)
		(duplicate_pad_numbers_are_jumpers no)
		(fp_line
			(start -0.508 -0.9398)
			(end -0.508 0.9398)
			(stroke
				(width 0.1524)
				(type default)
			)
			(layer "F.SilkS")
		)
		(fp_line
			(start 0.508 -0.9398)
			(end -0.508 -0.9398)
			(stroke
				(width 0.1524)
				(type default)
			)
			(layer "F.SilkS")
		)
		(fp_rect
			(start -0.508 0.9398)
			(end 0.508 -0.9398)
			(stroke
				(width 0)
				(type default)
			)
			(fill no)
			(layer "F.CrtYd")
		)
		(fp_rect
			(start -0.508 0.9398)
			(end 0.508 -0.9398)
			(stroke
				(width 0)
				(type default)
			)
			(fill no)
			(layer "F.Fab")
		)
		(pad "1" smd custom
			(at 0 -0.4445)
			(size 0.1397 0.1397)
			(layers "F.Cu" "F.Mask" "F.Paste")
			(net "SSD4_PWREN")
			(options
				(clearance outline)
				(anchor circle)
			)
			(primitives
				(gr_poly
					(pts
						(arc
							(start -0.1778 -0.2794)
							(mid -0.249642 -0.249642)
							(end -0.2794 -0.1778)
						)
						(arc
							(start -0.2794 0.1778)
							(mid -0.249642 0.249642)
							(end -0.1778 0.2794)
						)
						(arc
							(start 0.1778 0.2794)
							(mid 0.249642 0.249642)
							(end 0.2794 0.1778)
						)
						(arc
							(start 0.2794 -0.1778)
							(mid 0.249642 -0.249642)
							(end 0.1778 -0.2794)
						)
					)
					(width 0)
					(fill yes)
				)
			)
		)
		(pad "2" smd custom
			(at 0 0.4445)
			(size 0.1397 0.1397)
			(layers "F.Cu" "F.Mask" "F.Paste")
			(net "GND")
			(options
				(clearance outline)
				(anchor circle)
			)
			(primitives
				(gr_poly
					(pts
						(arc
							(start -0.1778 -0.2794)
							(mid -0.249642 -0.249642)
							(end -0.2794 -0.1778)
						)
						(arc
							(start -0.2794 0.1778)
							(mid -0.249642 0.249642)
							(end -0.1778 0.2794)
						)
						(arc
							(start 0.1778 0.2794)
							(mid 0.249642 0.249642)
							(end 0.2794 0.1778)
						)
						(arc
							(start 0.2794 -0.1778)
							(mid 0.249642 -0.249642)
							(end 0.1778 -0.2794)
						)
					)
					(width 0)
					(fill yes)
				)
			)
		)
	)
	(footprint ""
		(layer "F.Cu")
		(at 206.502 -89.535)
		(property "Reference" "D22"
			(at 0 0 0)
			(layer "F.SilkS")
			(hide yes)
			(effects
				(font
					(size 1.27 1.27)
				)
			)
		)
		(property "Value" "RB551V30-1-GP"
			(at 0 -6.7818 0)
			(unlocked yes)
			(layer "F.Fab")
			(hide yes)
			(effects
				(font
					(size 1.016 1.016)
					(thickness 0.1524)
				)
			)
		)
		(property "Device Type" "SOD323AKH44"
			(at 0 -8.6868 0)
			(unlocked yes)
			(layer "F.Fab")
			(hide yes)
			(effects
				(font
					(size 1.016 1.016)
					(thickness 0.1524)
				)
			)
		)
		(duplicate_pad_numbers_are_jumpers no)
		(fp_line
			(start -0.889 -1.9304)
			(end 0.889 -1.9304)
			(stroke
				(width 0.1524)
				(type default)
			)
			(layer "F.SilkS")
		)
		(fp_line
			(start -0.889 2.159)
			(end -0.889 -1.9304)
			(stroke
				(width 0.1524)
				(type default)
			)
			(layer "F.SilkS")
		)
		(fp_line
			(start 0.762 2.0574)
			(end -0.762 2.0574)
			(stroke
				(width 0.508)
				(type default)
			)
			(layer "F.SilkS")
		)
		(fp_line
			(start 0.889 -1.9304)
			(end 0.889 2.159)
			(stroke
				(width 0.1524)
				(type default)
			)
			(layer "F.SilkS")
		)
		(fp_line
			(start 0.889 2.159)
			(end -0.889 2.159)
			(stroke
				(width 0.1524)
				(type default)
			)
			(layer "F.SilkS")
		)
		(fp_rect
			(start -1.016 2.3114)
			(end 1.016 -2.0066)
			(stroke
				(width 0)
				(type default)
			)
			(fill no)
			(layer "F.CrtYd")
		)
		(fp_poly
			(pts
				(xy -1.016 -2.0066) (xy 1.016 -2.0066) (xy 1.016 2.3114) (xy -1.016 2.3114)
			)
			(stroke
				(width 0)
				(type default)
			)
			(fill no)
			(layer "F.Fab")
		)
		(pad "A" smd rect
			(at 0 -1.143)
			(size 0.5588 1.016)
			(layers "F.Cu" "F.Mask" "F.Paste")
			(net "SW_SSD4_R")
		)
		(pad "K" smd rect
			(at 0 1.143)
			(size 0.5588 1.016)
			(layers "F.Cu" "F.Mask" "F.Paste")
			(net "SW_SSD4_N")
		)
	)
	(footprint ""
		(layer "F.Cu")
		(at 219.9894 -189.4332)
		(property "Reference" "PC1226"
			(at 0 0 0)
			(layer "F.SilkS")
			(hide yes)
			(effects
				(font
					(size 1.27 1.27)
				)
			)
		)
		(property "Value" "SC22U25V6KX-GP-U"
			(at -2.860802 -5.279644 0)
			(unlocked yes)
			(layer "F.Fab")
			(hide yes)
			(effects
				(font
					(size 1.016 1.016)
					(thickness 0.1524)
				)
			)
		)
		(property "Device Type" "C1206-TO0D3H75"
			(at -2.860802 -6.803644 0)
			(unlocked yes)
			(layer "F.Fab")
			(hide yes)
			(effects
				(font
					(size 1.016 1.016)
					(thickness 0.1524)
				)
			)
		)
		(duplicate_pad_numbers_are_jumpers no)
		(fp_line
			(start -1.3081 -2.3749)
			(end 1.3081 -2.3749)
			(stroke
				(width 0.1524)
				(type default)
			)
			(layer "F.SilkS")
		)
		(fp_line
			(start -1.3081 2.3749)
			(end -1.3081 -2.3749)
			(stroke
				(width 0.1524)
				(type default)
			)
			(layer "F.SilkS")
		)
		(fp_line
			(start 1.3081 -2.3749)
			(end 1.3081 2.3749)
			(stroke
				(width 0.1524)
				(type default)
			)
			(layer "F.SilkS")
		)
		(fp_line
			(start 1.3081 2.3749)
			(end -1.3081 2.3749)
			(stroke
				(width 0.1524)
				(type default)
			)
			(layer "F.SilkS")
		)
		(fp_rect
			(start -0.8001 1.6002)
			(end 0.8001 -1.6002)
			(stroke
				(width 0)
				(type default)
			)
			(fill no)
			(layer "F.CrtYd")
		)
		(fp_poly
			(pts
				(xy -1.5621 2.4511) (xy -1.5621 1.6002) (xy 0.8001 1.6002) (xy 0.8001 -1.6002) (xy -0.8001 -1.6002)
				(xy -0.8001 1.5875) (xy -1.5621 1.5875) (xy -1.5621 -2.4511) (xy 1.5621 -2.4511) (xy 1.5621 2.4511)
			)
			(stroke
				(width 0)
				(type default)
			)
			(fill no)
			(layer "F.CrtYd")
		)
		(fp_rect
			(start -1.5621 2.4511)
			(end 1.5621 -2.4511)
			(stroke
				(width 0)
				(type default)
			)
			(fill no)
			(layer "F.Fab")
		)
		(pad "1" smd rect
			(at 0 -1.392936)
			(size 2.1082 1.4478)
			(layers "F.Cu" "F.Mask" "F.Paste")
			(net "P12V_SSD3")
		)
		(pad "2" smd rect
			(at 0 1.392936)
			(size 2.1082 1.4478)
			(layers "F.Cu" "F.Mask" "F.Paste")
			(net "GND")
		)
	)
	(footprint ""
		(layer "F.Cu")
		(at 39.116 -205.74)
		(property "Reference" "R9753"
			(at 0 0 0)
			(layer "F.SilkS")
			(hide yes)
			(effects
				(font
					(size 1.27 1.27)
				)
			)
		)
		(property "Value" "4K7R2J-2-GP"
			(at 0.064008 -3.993896 0)
			(unlocked yes)
			(layer "F.Fab")
			(hide yes)
			(effects
				(font
					(size 1.016 1.016)
					(thickness 0.1524)
				)
			)
		)
		(property "Device Type" "R402H16"
			(at 0.064008 -5.517896 0)
			(unlocked yes)
			(layer "F.Fab")
			(hide yes)
			(effects
				(font
					(size 1.016 1.016)
					(thickness 0.1524)
				)
			)
		)
		(duplicate_pad_numbers_are_jumpers no)
		(fp_line
			(start -0.508 -0.9398)
			(end -0.508 0.9398)
			(stroke
				(width 0.1524)
				(type default)
			)
			(layer "F.SilkS")
		)
		(fp_line
			(start 0.508 -0.9398)
			(end -0.508 -0.9398)
			(stroke
				(width 0.1524)
				(type default)
			)
			(layer "F.SilkS")
		)
		(fp_rect
			(start -0.508 0.9398)
			(end 0.508 -0.9398)
			(stroke
				(width 0)
				(type default)
			)
			(fill no)
			(layer "F.CrtYd")
		)
		(fp_rect
			(start -0.508 0.9398)
			(end 0.508 -0.9398)
			(stroke
				(width 0)
				(type default)
			)
			(fill no)
			(layer "F.Fab")
		)
		(pad "1" smd custom
			(at 0 -0.4445)
			(size 0.1397 0.1397)
			(layers "F.Cu" "F.Mask" "F.Paste")
			(net "P3V3")
			(options
				(clearance outline)
				(anchor circle)
			)
			(primitives
				(gr_poly
					(pts
						(arc
							(start -0.1778 -0.2794)
							(mid -0.249642 -0.249642)
							(end -0.2794 -0.1778)
						)
						(arc
							(start -0.2794 0.1778)
							(mid -0.249642 0.249642)
							(end -0.1778 0.2794)
						)
						(arc
							(start 0.1778 0.2794)
							(mid 0.249642 0.249642)
							(end 0.2794 0.1778)
						)
						(arc
							(start 0.2794 -0.1778)
							(mid 0.249642 -0.249642)
							(end 0.1778 -0.2794)
						)
					)
					(width 0)
					(fill yes)
				)
			)
		)
		(pad "2" smd custom
			(at 0 0.4445)
			(size 0.1397 0.1397)
			(layers "F.Cu" "F.Mask" "F.Paste")
			(net "SSD12_PWREN")
			(options
				(clearance outline)
				(anchor circle)
			)
			(primitives
				(gr_poly
					(pts
						(arc
							(start -0.1778 -0.2794)
							(mid -0.249642 -0.249642)
							(end -0.2794 -0.1778)
						)
						(arc
							(start -0.2794 0.1778)
							(mid -0.249642 0.249642)
							(end -0.1778 0.2794)
						)
						(arc
							(start 0.1778 0.2794)
							(mid 0.249642 0.249642)
							(end 0.2794 0.1778)
						)
						(arc
							(start 0.2794 -0.1778)
							(mid 0.249642 -0.249642)
							(end 0.1778 -0.2794)
						)
					)
					(width 0)
					(fill yes)
				)
			)
		)
	)
	(footprint ""
		(layer "F.Cu")
		(at 234.061 -239.008158 90)
		(property "Reference" "R9795"
			(at 0 0 90)
			(layer "F.SilkS")
			(hide yes)
			(effects
				(font
					(size 1.27 1.27)
				)
			)
		)
		(property "Value" "0R2J-2-GP"
			(at 0.064008 -3.993896 90)
			(unlocked yes)
			(layer "F.Fab")
			(hide yes)
			(effects
				(font
					(size 1.016 1.016)
					(thickness 0.1524)
				)
			)
		)
		(property "Device Type" "R402H16"
			(at 0.064008 -5.517896 90)
			(unlocked yes)
			(layer "F.Fab")
			(hide yes)
			(effects
				(font
					(size 1.016 1.016)
					(thickness 0.1524)
				)
			)
		)
		(duplicate_pad_numbers_are_jumpers no)
		(fp_line
			(start 0.508 -0.9398)
			(end -0.508 -0.9398)
			(stroke
				(width 0.1524)
				(type default)
			)
			(layer "F.SilkS")
		)
		(fp_line
			(start -0.508 -0.9398)
			(end -0.508 0.9398)
			(stroke
				(width 0.1524)
				(type default)
			)
			(layer "F.SilkS")
		)
		(fp_rect
			(start -0.508 0.9398)
			(end 0.508 -0.9398)
			(stroke
				(width 0)
				(type default)
			)
			(fill no)
			(layer "F.CrtYd")
		)
		(fp_rect
			(start -0.508 0.9398)
			(end 0.508 -0.9398)
			(stroke
				(width 0)
				(type default)
			)
			(fill no)
			(layer "F.Fab")
		)
		(pad "1" smd custom
			(at 0 -0.4445 90)
			(size 0.1397 0.1397)
			(layers "F.Cu" "F.Mask" "F.Paste")
			(net "ATTN_LED_DR2_AND")
			(options
				(clearance outline)
				(anchor circle)
			)
			(primitives
				(gr_poly
					(pts
						(arc
							(start -0.1778 -0.2794)
							(mid -0.249642 -0.249642)
							(end -0.2794 -0.1778)
						)
						(arc
							(start -0.2794 0.1778)
							(mid -0.249642 0.249642)
							(end -0.1778 0.2794)
						)
						(arc
							(start 0.1778 0.2794)
							(mid 0.249642 0.249642)
							(end 0.2794 0.1778)
						)
						(arc
							(start 0.2794 -0.1778)
							(mid 0.249642 -0.249642)
							(end 0.1778 -0.2794)
						)
					)
					(width 0)
					(fill yes)
				)
			)
		)
		(pad "2" smd custom
			(at 0 0.4445 90)
			(size 0.1397 0.1397)
			(layers "F.Cu" "F.Mask" "F.Paste")
			(net "ATTN_LED_DR2_AND_R")
			(options
				(clearance outline)
				(anchor circle)
			)
			(primitives
				(gr_poly
					(pts
						(arc
							(start -0.1778 -0.2794)
							(mid -0.249642 -0.249642)
							(end -0.2794 -0.1778)
						)
						(arc
							(start -0.2794 0.1778)
							(mid -0.249642 0.249642)
							(end -0.1778 0.2794)
						)
						(arc
							(start 0.1778 0.2794)
							(mid 0.249642 0.249642)
							(end 0.2794 0.1778)
						)
						(arc
							(start 0.2794 -0.1778)
							(mid 0.249642 -0.249642)
							(end 0.1778 -0.2794)
						)
					)
					(width 0)
					(fill yes)
				)
			)
		)
	)
	(footprint ""
		(layer "F.Cu")
		(at 96.266 -439.674)
		(property "Reference" "R9511"
			(at 0 0 0)
			(layer "F.SilkS")
			(hide yes)
			(effects
				(font
					(size 1.27 1.27)
				)
			)
		)
		(property "Value" "4K7R2F-GP"
			(at 0.064008 -3.993896 0)
			(unlocked yes)
			(layer "F.Fab")
			(hide yes)
			(effects
				(font
					(size 1.016 1.016)
					(thickness 0.1524)
				)
			)
		)
		(property "Device Type" "R402H16"
			(at 0.064008 -5.517896 0)
			(unlocked yes)
			(layer "F.Fab")
			(hide yes)
			(effects
				(font
					(size 1.016 1.016)
					(thickness 0.1524)
				)
			)
		)
		(duplicate_pad_numbers_are_jumpers no)
		(fp_line
			(start -0.508 -0.9398)
			(end -0.508 0.9398)
			(stroke
				(width 0.1524)
				(type default)
			)
			(layer "F.SilkS")
		)
		(fp_line
			(start 0.508 -0.9398)
			(end -0.508 -0.9398)
			(stroke
				(width 0.1524)
				(type default)
			)
			(layer "F.SilkS")
		)
		(fp_rect
			(start -0.508 0.9398)
			(end 0.508 -0.9398)
			(stroke
				(width 0)
				(type default)
			)
			(fill no)
			(layer "F.CrtYd")
		)
		(fp_rect
			(start -0.508 0.9398)
			(end 0.508 -0.9398)
			(stroke
				(width 0)
				(type default)
			)
			(fill no)
			(layer "F.Fab")
		)
		(pad "1" smd custom
			(at 0 -0.4445)
			(size 0.1397 0.1397)
			(layers "F.Cu" "F.Mask" "F.Paste")
			(net "P3V3")
			(options
				(clearance outline)
				(anchor circle)
			)
			(primitives
				(gr_poly
					(pts
						(arc
							(start -0.1778 -0.2794)
							(mid -0.249642 -0.249642)
							(end -0.2794 -0.1778)
						)
						(arc
							(start -0.2794 0.1778)
							(mid -0.249642 0.249642)
							(end -0.1778 0.2794)
						)
						(arc
							(start 0.1778 0.2794)
							(mid 0.249642 0.249642)
							(end 0.2794 0.1778)
						)
						(arc
							(start 0.2794 -0.1778)
							(mid 0.249642 -0.249642)
							(end 0.1778 -0.2794)
						)
					)
					(width 0)
					(fill yes)
				)
			)
		)
		(pad "2" smd custom
			(at 0 0.4445)
			(size 0.1397 0.1397)
			(layers "F.Cu" "F.Mask" "F.Paste")
			(net "CLK_BUFFER_EU1_VOE_N")
			(options
				(clearance outline)
				(anchor circle)
			)
			(primitives
				(gr_poly
					(pts
						(arc
							(start -0.1778 -0.2794)
							(mid -0.249642 -0.249642)
							(end -0.2794 -0.1778)
						)
						(arc
							(start -0.2794 0.1778)
							(mid -0.249642 0.249642)
							(end -0.1778 0.2794)
						)
						(arc
							(start 0.1778 0.2794)
							(mid 0.249642 0.249642)
							(end 0.2794 0.1778)
						)
						(arc
							(start 0.2794 -0.1778)
							(mid 0.249642 -0.249642)
							(end 0.1778 -0.2794)
						)
					)
					(width 0)
					(fill yes)
				)
			)
		)
	)
	(footprint ""
		(layer "F.Cu")
		(at 43.50004 -41.099994)
		(property "Reference" "LED9"
			(at 0 0 0)
			(layer "F.SilkS")
			(hide yes)
			(effects
				(font
					(size 1.27 1.27)
				)
			)
		)
		(property "Value" "LED-RB-4-GP"
			(at 5.88899 1.80848 0)
			(unlocked yes)
			(layer "F.Fab")
			(hide yes)
			(effects
				(font
					(size 1.016 1.016)
					(thickness 0.1524)
				)
			)
		)
		(property "Device Type" "LED1613-4PH20"
			(at 5.88899 0.28448 0)
			(unlocked yes)
			(layer "F.Fab")
			(hide yes)
			(effects
				(font
					(size 1.016 1.016)
					(thickness 0.1524)
				)
			)
		)
		(duplicate_pad_numbers_are_jumpers no)
		(fp_line
			(start -1.4478 -0.9652)
			(end 1.4478 -0.9652)
			(stroke
				(width 0.1524)
				(type default)
			)
			(layer "F.SilkS")
		)
		(fp_line
			(start -1.4478 0.9652)
			(end -1.4478 -0.9652)
			(stroke
				(width 0.1524)
				(type default)
			)
			(layer "F.SilkS")
		)
		(fp_line
			(start -1.4478 0.9652)
			(end -1.4478 -0.9652)
			(stroke
				(width 0.508)
				(type default)
			)
			(layer "F.SilkS")
		)
		(fp_line
			(start 1.4478 -0.9652)
			(end 1.4478 0.9652)
			(stroke
				(width 0.1524)
				(type default)
			)
			(layer "F.SilkS")
		)
		(fp_line
			(start 1.4478 0.9652)
			(end -1.4478 0.9652)
			(stroke
				(width 0.1524)
				(type default)
			)
			(layer "F.SilkS")
		)
		(fp_rect
			(start -0.8001 0.6477)
			(end 0.8001 -0.6477)
			(stroke
				(width 0)
				(type default)
			)
			(fill no)
			(layer "F.CrtYd")
		)
		(fp_poly
			(pts
				(xy -1.7018 1.2192) (xy -1.7018 -0.06223) (xy -0.8001 -0.06223) (xy -0.8001 0.6477) (xy 0.8001 0.6477)
				(xy 0.8001 -0.6477) (xy -0.8001 -0.6477) (xy -0.8001 -0.0635) (xy -1.7018 -0.0635) (xy -1.7018 -1.2192)
				(xy 1.7018 -1.2192) (xy 1.7018 1.2192)
			)
			(stroke
				(width 0)
				(type default)
			)
			(fill no)
			(layer "F.CrtYd")
		)
		(fp_rect
			(start -1.7018 1.2192)
			(end 1.7018 -1.2192)
			(stroke
				(width 0)
				(type default)
			)
			(fill no)
			(layer "F.Fab")
		)
		(pad "1" smd rect
			(at -0.73025 0.4064)
			(size 0.9144 0.6096)
			(layers "F.Cu" "F.Mask" "F.Paste")
			(net "SSD_ACT_DR9_MOS_N")
		)
		(pad "2" smd rect
			(at -0.73025 -0.4064)
			(size 0.9144 0.6096)
			(layers "F.Cu" "F.Mask" "F.Paste")
			(net "ATTN_LED_DR9_MOS_N")
		)
		(pad "3" smd rect
			(at 0.73025 -0.4064)
			(size 0.9144 0.6096)
			(layers "F.Cu" "F.Mask" "F.Paste")
			(net "DRV_ATTN_9")
		)
		(pad "4" smd rect
			(at 0.73025 0.4064)
			(size 0.9144 0.6096)
			(layers "F.Cu" "F.Mask" "F.Paste")
			(net "DRV_ACT_9")
		)
	)
	(footprint ""
		(layer "F.Cu")
		(at 89.662 -418.338 180)
		(property "Reference" "R9609"
			(at 0 0 180)
			(layer "F.SilkS")
			(hide yes)
			(effects
				(font
					(size 1.27 1.27)
				)
			)
		)
		(property "Value" "10R2F-L-GP"
			(at 0.064008 -3.993896 180)
			(unlocked yes)
			(layer "F.Fab")
			(hide yes)
			(effects
				(font
					(size 1.016 1.016)
					(thickness 0.1524)
				)
			)
		)
		(property "Device Type" "R402H14"
			(at 0.064008 -5.517896 180)
			(unlocked yes)
			(layer "F.Fab")
			(hide yes)
			(effects
				(font
					(size 1.016 1.016)
					(thickness 0.1524)
				)
			)
		)
		(duplicate_pad_numbers_are_jumpers no)
		(fp_line
			(start 0.508 -0.9398)
			(end -0.508 -0.9398)
			(stroke
				(width 0.1524)
				(type default)
			)
			(layer "F.SilkS")
		)
		(fp_line
			(start -0.508 -0.9398)
			(end -0.508 0.9398)
			(stroke
				(width 0.1524)
				(type default)
			)
			(layer "F.SilkS")
		)
		(fp_rect
			(start -0.508 0.9398)
			(end 0.508 -0.9398)
			(stroke
				(width 0)
				(type default)
			)
			(fill no)
			(layer "F.CrtYd")
		)
		(fp_rect
			(start -0.508 0.9398)
			(end 0.508 -0.9398)
			(stroke
				(width 0)
				(type default)
			)
			(fill no)
			(layer "F.Fab")
		)
		(pad "1" smd custom
			(at 0 -0.4445 180)
			(size 0.1397 0.1397)
			(layers "F.Cu" "F.Mask" "F.Paste")
			(net "SSD10_CLK0_OE_N")
			(options
				(clearance outline)
				(anchor circle)
			)
			(primitives
				(gr_poly
					(pts
						(arc
							(start -0.1778 -0.2794)
							(mid -0.249642 -0.249642)
							(end -0.2794 -0.1778)
						)
						(arc
							(start -0.2794 0.1778)
							(mid -0.249642 0.249642)
							(end -0.1778 0.2794)
						)
						(arc
							(start 0.1778 0.2794)
							(mid 0.249642 0.249642)
							(end 0.2794 0.1778)
						)
						(arc
							(start 0.2794 -0.1778)
							(mid 0.249642 -0.249642)
							(end 0.1778 -0.2794)
						)
					)
					(width 0)
					(fill yes)
				)
			)
		)
		(pad "2" smd custom
			(at 0 0.4445 180)
			(size 0.1397 0.1397)
			(layers "F.Cu" "F.Mask" "F.Paste")
			(net "SSD10_CLK0_OE_R_N")
			(options
				(clearance outline)
				(anchor circle)
			)
			(primitives
				(gr_poly
					(pts
						(arc
							(start -0.1778 -0.2794)
							(mid -0.249642 -0.249642)
							(end -0.2794 -0.1778)
						)
						(arc
							(start -0.2794 0.1778)
							(mid -0.249642 0.249642)
							(end -0.1778 0.2794)
						)
						(arc
							(start 0.1778 0.2794)
							(mid 0.249642 0.249642)
							(end 0.2794 0.1778)
						)
						(arc
							(start 0.2794 -0.1778)
							(mid 0.249642 -0.249642)
							(end 0.1778 -0.2794)
						)
					)
					(width 0)
					(fill yes)
				)
			)
		)
	)
	(footprint ""
		(layer "F.Cu")
		(at 229.235 -439.166)
		(property "Reference" "R9234"
			(at 0 0 0)
			(layer "F.SilkS")
			(hide yes)
			(effects
				(font
					(size 1.27 1.27)
				)
			)
		)
		(property "Value" "0R2J-2-GP"
			(at 0.064008 -3.993896 0)
			(unlocked yes)
			(layer "F.Fab")
			(hide yes)
			(effects
				(font
					(size 1.016 1.016)
					(thickness 0.1524)
				)
			)
		)
		(property "Device Type" "R402H16"
			(at 0.064008 -5.517896 0)
			(unlocked yes)
			(layer "F.Fab")
			(hide yes)
			(effects
				(font
					(size 1.016 1.016)
					(thickness 0.1524)
				)
			)
		)
		(duplicate_pad_numbers_are_jumpers no)
		(fp_line
			(start -0.508 -0.9398)
			(end -0.508 0.9398)
			(stroke
				(width 0.1524)
				(type default)
			)
			(layer "F.SilkS")
		)
		(fp_line
			(start 0.508 -0.9398)
			(end -0.508 -0.9398)
			(stroke
				(width 0.1524)
				(type default)
			)
			(layer "F.SilkS")
		)
		(fp_rect
			(start -0.508 0.9398)
			(end 0.508 -0.9398)
			(stroke
				(width 0)
				(type default)
			)
			(fill no)
			(layer "F.CrtYd")
		)
		(fp_rect
			(start -0.508 0.9398)
			(end 0.508 -0.9398)
			(stroke
				(width 0)
				(type default)
			)
			(fill no)
			(layer "F.Fab")
		)
		(pad "1" smd custom
			(at 0 -0.4445)
			(size 0.1397 0.1397)
			(layers "F.Cu" "F.Mask" "F.Paste")
			(net "P3V3_PG")
			(options
				(clearance outline)
				(anchor circle)
			)
			(primitives
				(gr_poly
					(pts
						(arc
							(start -0.1778 -0.2794)
							(mid -0.249642 -0.249642)
							(end -0.2794 -0.1778)
						)
						(arc
							(start -0.2794 0.1778)
							(mid -0.249642 0.249642)
							(end -0.1778 0.2794)
						)
						(arc
							(start 0.1778 0.2794)
							(mid 0.249642 0.249642)
							(end 0.2794 0.1778)
						)
						(arc
							(start 0.2794 -0.1778)
							(mid 0.249642 -0.249642)
							(end 0.1778 -0.2794)
						)
					)
					(width 0)
					(fill yes)
				)
			)
		)
		(pad "2" smd custom
			(at 0 0.4445)
			(size 0.1397 0.1397)
			(layers "F.Cu" "F.Mask" "F.Paste")
			(net "TPS53312_P3V3_PG")
			(options
				(clearance outline)
				(anchor circle)
			)
			(primitives
				(gr_poly
					(pts
						(arc
							(start -0.1778 -0.2794)
							(mid -0.249642 -0.249642)
							(end -0.2794 -0.1778)
						)
						(arc
							(start -0.2794 0.1778)
							(mid -0.249642 0.249642)
							(end -0.1778 0.2794)
						)
						(arc
							(start 0.1778 0.2794)
							(mid 0.249642 0.249642)
							(end 0.2794 0.1778)
						)
						(arc
							(start 0.2794 -0.1778)
							(mid 0.249642 -0.249642)
							(end 0.1778 -0.2794)
						)
					)
					(width 0)
					(fill yes)
				)
			)
		)
	)
	(footprint ""
		(layer "F.Cu")
		(at 16.231362 -53.56733 180)
		(property "Reference" "R9955"
			(at 0 0 180)
			(layer "F.SilkS")
			(hide yes)
			(effects
				(font
					(size 1.27 1.27)
				)
			)
		)
		(property "Value" "4K7R2J-2-GP"
			(at 0.064008 -3.993896 180)
			(unlocked yes)
			(layer "F.Fab")
			(hide yes)
			(effects
				(font
					(size 1.016 1.016)
					(thickness 0.1524)
				)
			)
		)
		(property "Device Type" "R402H16"
			(at 0.064008 -5.517896 180)
			(unlocked yes)
			(layer "F.Fab")
			(hide yes)
			(effects
				(font
					(size 1.016 1.016)
					(thickness 0.1524)
				)
			)
		)
		(duplicate_pad_numbers_are_jumpers no)
		(fp_line
			(start 0.508 -0.9398)
			(end -0.508 -0.9398)
			(stroke
				(width 0.1524)
				(type default)
			)
			(layer "F.SilkS")
		)
		(fp_line
			(start -0.508 -0.9398)
			(end -0.508 0.9398)
			(stroke
				(width 0.1524)
				(type default)
			)
			(layer "F.SilkS")
		)
		(fp_rect
			(start -0.508 0.9398)
			(end 0.508 -0.9398)
			(stroke
				(width 0)
				(type default)
			)
			(fill no)
			(layer "F.CrtYd")
		)
		(fp_rect
			(start -0.508 0.9398)
			(end 0.508 -0.9398)
			(stroke
				(width 0)
				(type default)
			)
			(fill no)
			(layer "F.Fab")
		)
		(pad "1" smd custom
			(at 0 -0.4445 180)
			(size 0.1397 0.1397)
			(layers "F.Cu" "F.Mask" "F.Paste")
			(net "P3V3")
			(options
				(clearance outline)
				(anchor circle)
			)
			(primitives
				(gr_poly
					(pts
						(arc
							(start -0.1778 -0.2794)
							(mid -0.249642 -0.249642)
							(end -0.2794 -0.1778)
						)
						(arc
							(start -0.2794 0.1778)
							(mid -0.249642 0.249642)
							(end -0.1778 0.2794)
						)
						(arc
							(start 0.1778 0.2794)
							(mid 0.249642 0.249642)
							(end 0.2794 0.1778)
						)
						(arc
							(start 0.2794 -0.1778)
							(mid 0.249642 -0.249642)
							(end 0.1778 -0.2794)
						)
					)
					(width 0)
					(fill yes)
				)
			)
		)
		(pad "2" smd custom
			(at 0 0.4445 180)
			(size 0.1397 0.1397)
			(layers "F.Cu" "F.Mask" "F.Paste")
			(net "ATTN_LED_DR14_MOS_N")
			(options
				(clearance outline)
				(anchor circle)
			)
			(primitives
				(gr_poly
					(pts
						(arc
							(start -0.1778 -0.2794)
							(mid -0.249642 -0.249642)
							(end -0.2794 -0.1778)
						)
						(arc
							(start -0.2794 0.1778)
							(mid -0.249642 0.249642)
							(end -0.1778 0.2794)
						)
						(arc
							(start 0.1778 0.2794)
							(mid 0.249642 0.249642)
							(end 0.2794 0.1778)
						)
						(arc
							(start 0.2794 -0.1778)
							(mid 0.249642 -0.249642)
							(end 0.1778 -0.2794)
						)
					)
					(width 0)
					(fill yes)
				)
			)
		)
	)
	(footprint ""
		(layer "F.Cu")
		(at 220.726 -138.04011)
		(property "Reference" "Q44"
			(at 0 0 0)
			(layer "F.SilkS")
			(hide yes)
			(effects
				(font
					(size 1.27 1.27)
				)
			)
		)
		(property "Value" "2N7002A-7-GP"
			(at 0.127 -8.9662 0)
			(unlocked yes)
			(layer "F.Fab")
			(hide yes)
			(effects
				(font
					(size 1.016 1.016)
					(thickness 0.1524)
				)
			)
		)
		(property "Device Type" "SOT23DGS2D4H48"
			(at 0.127 -10.4902 0)
			(unlocked yes)
			(layer "F.Fab")
			(hide yes)
			(effects
				(font
					(size 1.016 1.016)
					(thickness 0.1524)
				)
			)
		)
		(duplicate_pad_numbers_are_jumpers no)
		(fp_line
			(start -1.651 -1.778)
			(end -1.651 1.778)
			(stroke
				(width 0.1524)
				(type default)
			)
			(layer "F.SilkS")
		)
		(fp_line
			(start -1.651 1.778)
			(end 1.651 1.778)
			(stroke
				(width 0.1524)
				(type default)
			)
			(layer "F.SilkS")
		)
		(fp_line
			(start 1.651 -1.778)
			(end -1.651 -1.778)
			(stroke
				(width 0.1524)
				(type default)
			)
			(layer "F.SilkS")
		)
		(fp_line
			(start 1.651 1.778)
			(end 1.651 -1.778)
			(stroke
				(width 0.1524)
				(type default)
			)
			(layer "F.SilkS")
		)
		(fp_poly
			(pts
				(xy -1.778 1.8796) (xy -1.778 -1.8796) (xy 1.778 -1.8796) (xy 1.778 1.8796)
			)
			(stroke
				(width 0)
				(type default)
			)
			(fill no)
			(layer "F.CrtYd")
		)
		(fp_poly
			(pts
				(xy -1.778 1.8796) (xy -1.778 -1.8796) (xy 1.778 -1.8796) (xy 1.778 1.8796)
			)
			(stroke
				(width 0)
				(type default)
			)
			(fill no)
			(layer "F.Fab")
		)
		(pad "D" smd custom
			(at 0 -0.9525)
			(size 0.1905 0.1905)
			(layers "F.Cu" "F.Mask" "F.Paste")
			(net "SSD3_CLK0_OE_MOS_N")
			(options
				(clearance outline)
				(anchor circle)
			)
			(primitives
				(gr_poly
					(pts
						(arc
							(start -0.1778 0.5715)
							(mid -0.321484 0.511984)
							(end -0.381 0.3683)
						)
						(arc
							(start -0.381 -0.3683)
							(mid -0.321484 -0.511984)
							(end -0.1778 -0.5715)
						)
						(arc
							(start 0.1778 -0.5715)
							(mid 0.321484 -0.511984)
							(end 0.381 -0.3683)
						)
						(arc
							(start 0.381 0.3683)
							(mid 0.321484 0.511984)
							(end 0.1778 0.5715)
						)
					)
					(width 0)
					(fill yes)
				)
			)
		)
		(pad "G" smd custom
			(at -0.98425 0.9525)
			(size 0.1905 0.1905)
			(layers "F.Cu" "F.Mask" "F.Paste")
			(net "SSD3_CLK0_OE_R_N")
			(options
				(clearance outline)
				(anchor circle)
			)
			(primitives
				(gr_poly
					(pts
						(arc
							(start -0.1778 0.5715)
							(mid -0.321484 0.511984)
							(end -0.381 0.3683)
						)
						(arc
							(start -0.381 -0.3683)
							(mid -0.321484 -0.511984)
							(end -0.1778 -0.5715)
						)
						(arc
							(start 0.1778 -0.5715)
							(mid 0.321484 -0.511984)
							(end 0.381 -0.3683)
						)
						(arc
							(start 0.381 0.3683)
							(mid 0.321484 0.511984)
							(end 0.1778 0.5715)
						)
					)
					(width 0)
					(fill yes)
				)
			)
		)
		(pad "S" smd custom
			(at 0.98425 0.9525)
			(size 0.1905 0.1905)
			(layers "F.Cu" "F.Mask" "F.Paste")
			(net "GND")
			(options
				(clearance outline)
				(anchor circle)
			)
			(primitives
				(gr_poly
					(pts
						(arc
							(start -0.1778 0.5715)
							(mid -0.321484 0.511984)
							(end -0.381 0.3683)
						)
						(arc
							(start -0.381 -0.3683)
							(mid -0.321484 -0.511984)
							(end -0.1778 -0.5715)
						)
						(arc
							(start 0.1778 -0.5715)
							(mid 0.321484 -0.511984)
							(end 0.381 -0.3683)
						)
						(arc
							(start 0.381 0.3683)
							(mid 0.321484 0.511984)
							(end 0.1778 0.5715)
						)
					)
					(width 0)
					(fill yes)
				)
			)
		)
	)
	(footprint ""
		(layer "F.Cu")
		(at 234.061 -452.628 -90)
		(property "Reference" "R120"
			(at 0 0 270)
			(layer "F.SilkS")
			(hide yes)
			(effects
				(font
					(size 1.27 1.27)
				)
			)
		)
		(property "Value" "100R2J-2-GP"
			(at 0.064008 -3.993896 270)
			(unlocked yes)
			(layer "F.Fab")
			(hide yes)
			(effects
				(font
					(size 1.016 1.016)
					(thickness 0.1524)
				)
			)
		)
		(property "Device Type" "R402H14"
			(at 0.064008 -5.517896 270)
			(unlocked yes)
			(layer "F.Fab")
			(hide yes)
			(effects
				(font
					(size 1.016 1.016)
					(thickness 0.1524)
				)
			)
		)
		(duplicate_pad_numbers_are_jumpers no)
		(fp_line
			(start -0.508 -0.9398)
			(end -0.508 0.9398)
			(stroke
				(width 0.1524)
				(type default)
			)
			(layer "F.SilkS")
		)
		(fp_line
			(start 0.508 -0.9398)
			(end -0.508 -0.9398)
			(stroke
				(width 0.1524)
				(type default)
			)
			(layer "F.SilkS")
		)
		(fp_rect
			(start -0.508 0.9398)
			(end 0.508 -0.9398)
			(stroke
				(width 0)
				(type default)
			)
			(fill no)
			(layer "F.CrtYd")
		)
		(fp_rect
			(start -0.508 0.9398)
			(end 0.508 -0.9398)
			(stroke
				(width 0)
				(type default)
			)
			(fill no)
			(layer "F.Fab")
		)
		(pad "1" smd custom
			(at 0 -0.4445 270)
			(size 0.1397 0.1397)
			(layers "F.Cu" "F.Mask" "F.Paste")
			(net "P3V3")
			(options
				(clearance outline)
				(anchor circle)
			)
			(primitives
				(gr_poly
					(pts
						(arc
							(start -0.1778 -0.2794)
							(mid -0.249642 -0.249642)
							(end -0.2794 -0.1778)
						)
						(arc
							(start -0.2794 0.1778)
							(mid -0.249642 0.249642)
							(end -0.1778 0.2794)
						)
						(arc
							(start 0.1778 0.2794)
							(mid 0.249642 0.249642)
							(end 0.2794 0.1778)
						)
						(arc
							(start 0.2794 -0.1778)
							(mid 0.249642 -0.249642)
							(end 0.1778 -0.2794)
						)
					)
					(width 0)
					(fill yes)
				)
			)
		)
		(pad "2" smd custom
			(at 0 0.4445 270)
			(size 0.1397 0.1397)
			(layers "F.Cu" "F.Mask" "F.Paste")
			(net "DRV_ACT_0")
			(options
				(clearance outline)
				(anchor circle)
			)
			(primitives
				(gr_poly
					(pts
						(arc
							(start -0.1778 -0.2794)
							(mid -0.249642 -0.249642)
							(end -0.2794 -0.1778)
						)
						(arc
							(start -0.2794 0.1778)
							(mid -0.249642 0.249642)
							(end -0.1778 0.2794)
						)
						(arc
							(start 0.1778 0.2794)
							(mid 0.249642 0.249642)
							(end 0.2794 0.1778)
						)
						(arc
							(start 0.2794 -0.1778)
							(mid 0.249642 -0.249642)
							(end 0.1778 -0.2794)
						)
					)
					(width 0)
					(fill yes)
				)
			)
		)
	)
	(footprint ""
		(layer "F.Cu")
		(at 11.43 -269.875 180)
		(property "Reference" "R9035"
			(at 0 0 180)
			(layer "F.SilkS")
			(hide yes)
			(effects
				(font
					(size 1.27 1.27)
				)
			)
		)
		(property "Value" "0R2J-2-GP"
			(at 0.064008 -3.993896 180)
			(unlocked yes)
			(layer "F.Fab")
			(hide yes)
			(effects
				(font
					(size 1.016 1.016)
					(thickness 0.1524)
				)
			)
		)
		(property "Device Type" "R402H16"
			(at 0.064008 -5.517896 180)
			(unlocked yes)
			(layer "F.Fab")
			(hide yes)
			(effects
				(font
					(size 1.016 1.016)
					(thickness 0.1524)
				)
			)
		)
		(duplicate_pad_numbers_are_jumpers no)
		(fp_line
			(start 0.508 -0.9398)
			(end -0.508 -0.9398)
			(stroke
				(width 0.1524)
				(type default)
			)
			(layer "F.SilkS")
		)
		(fp_line
			(start -0.508 -0.9398)
			(end -0.508 0.9398)
			(stroke
				(width 0.1524)
				(type default)
			)
			(layer "F.SilkS")
		)
		(fp_rect
			(start -0.508 0.9398)
			(end 0.508 -0.9398)
			(stroke
				(width 0)
				(type default)
			)
			(fill no)
			(layer "F.CrtYd")
		)
		(fp_rect
			(start -0.508 0.9398)
			(end 0.508 -0.9398)
			(stroke
				(width 0)
				(type default)
			)
			(fill no)
			(layer "F.Fab")
		)
		(pad "1" smd custom
			(at 0 -0.4445 180)
			(size 0.1397 0.1397)
			(layers "F.Cu" "F.Mask" "F.Paste")
			(net "TRAY_ID_R")
			(options
				(clearance outline)
				(anchor circle)
			)
			(primitives
				(gr_poly
					(pts
						(arc
							(start -0.1778 -0.2794)
							(mid -0.249642 -0.249642)
							(end -0.2794 -0.1778)
						)
						(arc
							(start -0.2794 0.1778)
							(mid -0.249642 0.249642)
							(end -0.1778 0.2794)
						)
						(arc
							(start 0.1778 0.2794)
							(mid 0.249642 0.249642)
							(end 0.2794 0.1778)
						)
						(arc
							(start 0.2794 -0.1778)
							(mid 0.249642 -0.249642)
							(end 0.1778 -0.2794)
						)
					)
					(width 0)
					(fill yes)
				)
			)
		)
		(pad "2" smd custom
			(at 0 0.4445 180)
			(size 0.1397 0.1397)
			(layers "F.Cu" "F.Mask" "F.Paste")
			(net "TRAY_ID")
			(options
				(clearance outline)
				(anchor circle)
			)
			(primitives
				(gr_poly
					(pts
						(arc
							(start -0.1778 -0.2794)
							(mid -0.249642 -0.249642)
							(end -0.2794 -0.1778)
						)
						(arc
							(start -0.2794 0.1778)
							(mid -0.249642 0.249642)
							(end -0.1778 0.2794)
						)
						(arc
							(start 0.1778 0.2794)
							(mid 0.249642 0.249642)
							(end 0.2794 0.1778)
						)
						(arc
							(start 0.2794 -0.1778)
							(mid 0.249642 -0.249642)
							(end 0.1778 -0.2794)
						)
					)
					(width 0)
					(fill yes)
				)
			)
		)
	)
	(footprint ""
		(layer "F.Cu")
		(at 94.488 -218.44 180)
		(property "Reference" "C8861"
			(at 0 0 180)
			(layer "F.SilkS")
			(hide yes)
			(effects
				(font
					(size 1.27 1.27)
				)
			)
		)
		(property "Value" "SCD1U16V2KX-3GP"
			(at 1.1811 -2.7051 180)
			(unlocked yes)
			(layer "F.Fab")
			(hide yes)
			(effects
				(font
					(size 1.016 1.016)
					(thickness 0.1524)
				)
			)
		)
		(property "Device Type" "C402H22"
			(at 1.1811 -4.2291 180)
			(unlocked yes)
			(layer "F.Fab")
			(hide yes)
			(effects
				(font
					(size 1.016 1.016)
					(thickness 0.1524)
				)
			)
		)
		(duplicate_pad_numbers_are_jumpers no)
		(fp_rect
			(start -0.4318 0.9525)
			(end 0.4318 -0.9525)
			(stroke
				(width 0)
				(type default)
			)
			(fill no)
			(layer "F.CrtYd")
		)
		(fp_rect
			(start -0.4318 0.9525)
			(end 0.4318 -0.9525)
			(stroke
				(width 0)
				(type default)
			)
			(fill no)
			(layer "F.Fab")
		)
		(pad "1" smd custom
			(at 0 -0.4445 180)
			(size 0.1524 0.1524)
			(layers "F.Cu" "F.Mask" "F.Paste")
			(net "VDD_IO_3")
			(options
				(clearance outline)
				(anchor circle)
			)
			(primitives
				(gr_poly
					(pts
						(arc
							(start 0.3048 -0.2032)
							(mid 0.275042 -0.275042)
							(end 0.2032 -0.3048)
						)
						(arc
							(start -0.2032 -0.3048)
							(mid -0.275042 -0.275042)
							(end -0.3048 -0.2032)
						)
						(arc
							(start -0.3048 0.2032)
							(mid -0.275042 0.275042)
							(end -0.2032 0.3048)
						)
						(arc
							(start 0.2032 0.3048)
							(mid 0.275042 0.275042)
							(end 0.3048 0.2032)
						)
					)
					(width 0)
					(fill yes)
				)
			)
		)
		(pad "2" smd custom
			(at 0 0.4445 180)
			(size 0.1524 0.1524)
			(layers "F.Cu" "F.Mask" "F.Paste")
			(net "GND")
			(options
				(clearance outline)
				(anchor circle)
			)
			(primitives
				(gr_poly
					(pts
						(arc
							(start 0.3048 -0.2032)
							(mid 0.275042 -0.275042)
							(end 0.2032 -0.3048)
						)
						(arc
							(start -0.2032 -0.3048)
							(mid -0.275042 -0.275042)
							(end -0.3048 -0.2032)
						)
						(arc
							(start -0.3048 0.2032)
							(mid -0.275042 0.275042)
							(end -0.2032 0.3048)
						)
						(arc
							(start 0.2032 0.3048)
							(mid 0.275042 0.275042)
							(end 0.3048 0.2032)
						)
					)
					(width 0)
					(fill yes)
				)
			)
		)
	)
	(footprint ""
		(layer "F.Cu")
		(at 234.061 -33.008062 90)
		(property "Reference" "R9807"
			(at 0 0 90)
			(layer "F.SilkS")
			(hide yes)
			(effects
				(font
					(size 1.27 1.27)
				)
			)
		)
		(property "Value" "0R2J-2-GP"
			(at 0.064008 -3.993896 90)
			(unlocked yes)
			(layer "F.Fab")
			(hide yes)
			(effects
				(font
					(size 1.016 1.016)
					(thickness 0.1524)
				)
			)
		)
		(property "Device Type" "R402H16"
			(at 0.064008 -5.517896 90)
			(unlocked yes)
			(layer "F.Fab")
			(hide yes)
			(effects
				(font
					(size 1.016 1.016)
					(thickness 0.1524)
				)
			)
		)
		(duplicate_pad_numbers_are_jumpers no)
		(fp_line
			(start 0.508 -0.9398)
			(end -0.508 -0.9398)
			(stroke
				(width 0.1524)
				(type default)
			)
			(layer "F.SilkS")
		)
		(fp_line
			(start -0.508 -0.9398)
			(end -0.508 0.9398)
			(stroke
				(width 0.1524)
				(type default)
			)
			(layer "F.SilkS")
		)
		(fp_rect
			(start -0.508 0.9398)
			(end 0.508 -0.9398)
			(stroke
				(width 0)
				(type default)
			)
			(fill no)
			(layer "F.CrtYd")
		)
		(fp_rect
			(start -0.508 0.9398)
			(end 0.508 -0.9398)
			(stroke
				(width 0)
				(type default)
			)
			(fill no)
			(layer "F.Fab")
		)
		(pad "1" smd custom
			(at 0 -0.4445 90)
			(size 0.1397 0.1397)
			(layers "F.Cu" "F.Mask" "F.Paste")
			(net "ATTN_LED_DR4_AND")
			(options
				(clearance outline)
				(anchor circle)
			)
			(primitives
				(gr_poly
					(pts
						(arc
							(start -0.1778 -0.2794)
							(mid -0.249642 -0.249642)
							(end -0.2794 -0.1778)
						)
						(arc
							(start -0.2794 0.1778)
							(mid -0.249642 0.249642)
							(end -0.1778 0.2794)
						)
						(arc
							(start 0.1778 0.2794)
							(mid 0.249642 0.249642)
							(end 0.2794 0.1778)
						)
						(arc
							(start 0.2794 -0.1778)
							(mid 0.249642 -0.249642)
							(end 0.1778 -0.2794)
						)
					)
					(width 0)
					(fill yes)
				)
			)
		)
		(pad "2" smd custom
			(at 0 0.4445 90)
			(size 0.1397 0.1397)
			(layers "F.Cu" "F.Mask" "F.Paste")
			(net "ATTN_LED_DR4_AND_R")
			(options
				(clearance outline)
				(anchor circle)
			)
			(primitives
				(gr_poly
					(pts
						(arc
							(start -0.1778 -0.2794)
							(mid -0.249642 -0.249642)
							(end -0.2794 -0.1778)
						)
						(arc
							(start -0.2794 0.1778)
							(mid -0.249642 0.249642)
							(end -0.1778 0.2794)
						)
						(arc
							(start 0.1778 0.2794)
							(mid 0.249642 0.249642)
							(end 0.2794 0.1778)
						)
						(arc
							(start 0.2794 -0.1778)
							(mid 0.249642 -0.249642)
							(end 0.1778 -0.2794)
						)
					)
					(width 0)
					(fill yes)
				)
			)
		)
	)
	(footprint ""
		(layer "F.Cu")
		(at 217.043 -290.5506 180)
		(property "Reference" "SR1096"
			(at 0 0 180)
			(layer "F.SilkS")
			(hide yes)
			(effects
				(font
					(size 1.27 1.27)
				)
			)
		)
		(property "Value" "4K7R2F-GP"
			(at 0.064008 -3.993896 180)
			(unlocked yes)
			(layer "F.Fab")
			(hide yes)
			(effects
				(font
					(size 1.016 1.016)
					(thickness 0.1524)
				)
			)
		)
		(property "Device Type" "R402H16"
			(at 0.064008 -5.517896 180)
			(unlocked yes)
			(layer "F.Fab")
			(hide yes)
			(effects
				(font
					(size 1.016 1.016)
					(thickness 0.1524)
				)
			)
		)
		(duplicate_pad_numbers_are_jumpers no)
		(fp_line
			(start 0.508 -0.9398)
			(end -0.508 -0.9398)
			(stroke
				(width 0.1524)
				(type default)
			)
			(layer "F.SilkS")
		)
		(fp_line
			(start -0.508 -0.9398)
			(end -0.508 0.9398)
			(stroke
				(width 0.1524)
				(type default)
			)
			(layer "F.SilkS")
		)
		(fp_rect
			(start -0.508 0.9398)
			(end 0.508 -0.9398)
			(stroke
				(width 0)
				(type default)
			)
			(fill no)
			(layer "F.CrtYd")
		)
		(fp_rect
			(start -0.508 0.9398)
			(end 0.508 -0.9398)
			(stroke
				(width 0)
				(type default)
			)
			(fill no)
			(layer "F.Fab")
		)
		(pad "1" smd custom
			(at 0 -0.4445 180)
			(size 0.1397 0.1397)
			(layers "F.Cu" "F.Mask" "F.Paste")
			(net "DUALPORTEN#2")
			(options
				(clearance outline)
				(anchor circle)
			)
			(primitives
				(gr_poly
					(pts
						(arc
							(start -0.1778 -0.2794)
							(mid -0.249642 -0.249642)
							(end -0.2794 -0.1778)
						)
						(arc
							(start -0.2794 0.1778)
							(mid -0.249642 0.249642)
							(end -0.1778 0.2794)
						)
						(arc
							(start 0.1778 0.2794)
							(mid 0.249642 0.249642)
							(end 0.2794 0.1778)
						)
						(arc
							(start 0.2794 -0.1778)
							(mid 0.249642 -0.249642)
							(end 0.1778 -0.2794)
						)
					)
					(width 0)
					(fill yes)
				)
			)
		)
		(pad "2" smd custom
			(at 0 0.4445 180)
			(size 0.1397 0.1397)
			(layers "F.Cu" "F.Mask" "F.Paste")
			(net "GND")
			(options
				(clearance outline)
				(anchor circle)
			)
			(primitives
				(gr_poly
					(pts
						(arc
							(start -0.1778 -0.2794)
							(mid -0.249642 -0.249642)
							(end -0.2794 -0.1778)
						)
						(arc
							(start -0.2794 0.1778)
							(mid -0.249642 0.249642)
							(end -0.1778 0.2794)
						)
						(arc
							(start 0.1778 0.2794)
							(mid 0.249642 0.249642)
							(end 0.2794 0.1778)
						)
						(arc
							(start 0.2794 -0.1778)
							(mid 0.249642 -0.249642)
							(end 0.1778 -0.2794)
						)
					)
					(width 0)
					(fill yes)
				)
			)
		)
	)
	(footprint ""
		(layer "F.Cu")
		(at 222.544894 -40.553894)
		(property "Reference" "Q50"
			(at 0 0 0)
			(layer "F.SilkS")
			(hide yes)
			(effects
				(font
					(size 1.27 1.27)
				)
			)
		)
		(property "Value" "2N7002A-7-GP"
			(at 0.127 -8.9662 0)
			(unlocked yes)
			(layer "F.Fab")
			(hide yes)
			(effects
				(font
					(size 1.016 1.016)
					(thickness 0.1524)
				)
			)
		)
		(property "Device Type" "SOT23DGS2D4H48"
			(at 0.127 -10.4902 0)
			(unlocked yes)
			(layer "F.Fab")
			(hide yes)
			(effects
				(font
					(size 1.016 1.016)
					(thickness 0.1524)
				)
			)
		)
		(duplicate_pad_numbers_are_jumpers no)
		(fp_line
			(start -1.651 -1.778)
			(end -1.651 1.778)
			(stroke
				(width 0.1524)
				(type default)
			)
			(layer "F.SilkS")
		)
		(fp_line
			(start -1.651 1.778)
			(end 1.651 1.778)
			(stroke
				(width 0.1524)
				(type default)
			)
			(layer "F.SilkS")
		)
		(fp_line
			(start 1.651 -1.778)
			(end -1.651 -1.778)
			(stroke
				(width 0.1524)
				(type default)
			)
			(layer "F.SilkS")
		)
		(fp_line
			(start 1.651 1.778)
			(end 1.651 -1.778)
			(stroke
				(width 0.1524)
				(type default)
			)
			(layer "F.SilkS")
		)
		(fp_poly
			(pts
				(xy -1.778 1.8796) (xy -1.778 -1.8796) (xy 1.778 -1.8796) (xy 1.778 1.8796)
			)
			(stroke
				(width 0)
				(type default)
			)
			(fill no)
			(layer "F.CrtYd")
		)
		(fp_poly
			(pts
				(xy -1.778 1.8796) (xy -1.778 -1.8796) (xy 1.778 -1.8796) (xy 1.778 1.8796)
			)
			(stroke
				(width 0)
				(type default)
			)
			(fill no)
			(layer "F.Fab")
		)
		(pad "D" smd custom
			(at 0 -0.9525)
			(size 0.1905 0.1905)
			(layers "F.Cu" "F.Mask" "F.Paste")
			(net "ATTN_LED_DR4_MOS_N")
			(options
				(clearance outline)
				(anchor circle)
			)
			(primitives
				(gr_poly
					(pts
						(arc
							(start -0.1778 0.5715)
							(mid -0.321484 0.511984)
							(end -0.381 0.3683)
						)
						(arc
							(start -0.381 -0.3683)
							(mid -0.321484 -0.511984)
							(end -0.1778 -0.5715)
						)
						(arc
							(start 0.1778 -0.5715)
							(mid 0.321484 -0.511984)
							(end 0.381 -0.3683)
						)
						(arc
							(start 0.381 0.3683)
							(mid 0.321484 0.511984)
							(end 0.1778 0.5715)
						)
					)
					(width 0)
					(fill yes)
				)
			)
		)
		(pad "G" smd custom
			(at -0.98425 0.9525)
			(size 0.1905 0.1905)
			(layers "F.Cu" "F.Mask" "F.Paste")
			(net "SSD4_CLK0_OE_MOS_N")
			(options
				(clearance outline)
				(anchor circle)
			)
			(primitives
				(gr_poly
					(pts
						(arc
							(start -0.1778 0.5715)
							(mid -0.321484 0.511984)
							(end -0.381 0.3683)
						)
						(arc
							(start -0.381 -0.3683)
							(mid -0.321484 -0.511984)
							(end -0.1778 -0.5715)
						)
						(arc
							(start 0.1778 -0.5715)
							(mid 0.321484 -0.511984)
							(end 0.381 -0.3683)
						)
						(arc
							(start 0.381 0.3683)
							(mid 0.321484 0.511984)
							(end 0.1778 0.5715)
						)
					)
					(width 0)
					(fill yes)
				)
			)
		)
		(pad "S" smd custom
			(at 0.98425 0.9525)
			(size 0.1905 0.1905)
			(layers "F.Cu" "F.Mask" "F.Paste")
			(net "ATTN_LED_DR4_R")
			(options
				(clearance outline)
				(anchor circle)
			)
			(primitives
				(gr_poly
					(pts
						(arc
							(start -0.1778 0.5715)
							(mid -0.321484 0.511984)
							(end -0.381 0.3683)
						)
						(arc
							(start -0.381 -0.3683)
							(mid -0.321484 -0.511984)
							(end -0.1778 -0.5715)
						)
						(arc
							(start 0.1778 -0.5715)
							(mid 0.321484 -0.511984)
							(end 0.381 -0.3683)
						)
						(arc
							(start 0.381 0.3683)
							(mid 0.321484 0.511984)
							(end 0.1778 0.5715)
						)
					)
					(width 0)
					(fill yes)
				)
			)
		)
	)
	(footprint ""
		(layer "F.Cu")
		(at 222.123 -348.103952)
		(property "Reference" "Q35"
			(at 0 0 0)
			(layer "F.SilkS")
			(hide yes)
			(effects
				(font
					(size 1.27 1.27)
				)
			)
		)
		(property "Value" "2N7002A-7-GP"
			(at 0.127 -8.9662 0)
			(unlocked yes)
			(layer "F.Fab")
			(hide yes)
			(effects
				(font
					(size 1.016 1.016)
					(thickness 0.1524)
				)
			)
		)
		(property "Device Type" "SOT23DGS2D4H48"
			(at 0.127 -10.4902 0)
			(unlocked yes)
			(layer "F.Fab")
			(hide yes)
			(effects
				(font
					(size 1.016 1.016)
					(thickness 0.1524)
				)
			)
		)
		(duplicate_pad_numbers_are_jumpers no)
		(fp_line
			(start -1.651 -1.778)
			(end -1.651 1.778)
			(stroke
				(width 0.1524)
				(type default)
			)
			(layer "F.SilkS")
		)
		(fp_line
			(start -1.651 1.778)
			(end 1.651 1.778)
			(stroke
				(width 0.1524)
				(type default)
			)
			(layer "F.SilkS")
		)
		(fp_line
			(start 1.651 -1.778)
			(end -1.651 -1.778)
			(stroke
				(width 0.1524)
				(type default)
			)
			(layer "F.SilkS")
		)
		(fp_line
			(start 1.651 1.778)
			(end 1.651 -1.778)
			(stroke
				(width 0.1524)
				(type default)
			)
			(layer "F.SilkS")
		)
		(fp_poly
			(pts
				(xy -1.778 1.8796) (xy -1.778 -1.8796) (xy 1.778 -1.8796) (xy 1.778 1.8796)
			)
			(stroke
				(width 0)
				(type default)
			)
			(fill no)
			(layer "F.CrtYd")
		)
		(fp_poly
			(pts
				(xy -1.778 1.8796) (xy -1.778 -1.8796) (xy 1.778 -1.8796) (xy 1.778 1.8796)
			)
			(stroke
				(width 0)
				(type default)
			)
			(fill no)
			(layer "F.Fab")
		)
		(pad "D" smd custom
			(at 0 -0.9525)
			(size 0.1905 0.1905)
			(layers "F.Cu" "F.Mask" "F.Paste")
			(net "ATTN_LED_DR1_MOS_N")
			(options
				(clearance outline)
				(anchor circle)
			)
			(primitives
				(gr_poly
					(pts
						(arc
							(start -0.1778 0.5715)
							(mid -0.321484 0.511984)
							(end -0.381 0.3683)
						)
						(arc
							(start -0.381 -0.3683)
							(mid -0.321484 -0.511984)
							(end -0.1778 -0.5715)
						)
						(arc
							(start 0.1778 -0.5715)
							(mid 0.321484 -0.511984)
							(end 0.381 -0.3683)
						)
						(arc
							(start 0.381 0.3683)
							(mid 0.321484 0.511984)
							(end 0.1778 0.5715)
						)
					)
					(width 0)
					(fill yes)
				)
			)
		)
		(pad "G" smd custom
			(at -0.98425 0.9525)
			(size 0.1905 0.1905)
			(layers "F.Cu" "F.Mask" "F.Paste")
			(net "SSD1_CLK0_OE_MOS_N")
			(options
				(clearance outline)
				(anchor circle)
			)
			(primitives
				(gr_poly
					(pts
						(arc
							(start -0.1778 0.5715)
							(mid -0.321484 0.511984)
							(end -0.381 0.3683)
						)
						(arc
							(start -0.381 -0.3683)
							(mid -0.321484 -0.511984)
							(end -0.1778 -0.5715)
						)
						(arc
							(start 0.1778 -0.5715)
							(mid 0.321484 -0.511984)
							(end 0.381 -0.3683)
						)
						(arc
							(start 0.381 0.3683)
							(mid 0.321484 0.511984)
							(end 0.1778 0.5715)
						)
					)
					(width 0)
					(fill yes)
				)
			)
		)
		(pad "S" smd custom
			(at 0.98425 0.9525)
			(size 0.1905 0.1905)
			(layers "F.Cu" "F.Mask" "F.Paste")
			(net "ATTN_LED_DR1_R")
			(options
				(clearance outline)
				(anchor circle)
			)
			(primitives
				(gr_poly
					(pts
						(arc
							(start -0.1778 0.5715)
							(mid -0.321484 0.511984)
							(end -0.381 0.3683)
						)
						(arc
							(start -0.381 -0.3683)
							(mid -0.321484 -0.511984)
							(end -0.1778 -0.5715)
						)
						(arc
							(start 0.1778 -0.5715)
							(mid 0.321484 -0.511984)
							(end 0.381 -0.3683)
						)
						(arc
							(start 0.381 0.3683)
							(mid 0.321484 0.511984)
							(end 0.1778 0.5715)
						)
					)
					(width 0)
					(fill yes)
				)
			)
		)
	)
	(footprint ""
		(layer "F.Cu")
		(at 96.52 -110.236 180)
		(property "Reference" "R9133"
			(at 0 0 180)
			(layer "F.SilkS")
			(hide yes)
			(effects
				(font
					(size 1.27 1.27)
				)
			)
		)
		(property "Value" "27R2F-GP"
			(at 0.064008 -3.993896 180)
			(unlocked yes)
			(layer "F.Fab")
			(hide yes)
			(effects
				(font
					(size 1.016 1.016)
					(thickness 0.1524)
				)
			)
		)
		(property "Device Type" "R402H16"
			(at 0.064008 -5.517896 180)
			(unlocked yes)
			(layer "F.Fab")
			(hide yes)
			(effects
				(font
					(size 1.016 1.016)
					(thickness 0.1524)
				)
			)
		)
		(duplicate_pad_numbers_are_jumpers no)
		(fp_line
			(start 0.508 -0.9398)
			(end -0.508 -0.9398)
			(stroke
				(width 0.1524)
				(type default)
			)
			(layer "F.SilkS")
		)
		(fp_line
			(start -0.508 -0.9398)
			(end -0.508 0.9398)
			(stroke
				(width 0.1524)
				(type default)
			)
			(layer "F.SilkS")
		)
		(fp_rect
			(start -0.508 0.9398)
			(end 0.508 -0.9398)
			(stroke
				(width 0)
				(type default)
			)
			(fill no)
			(layer "F.CrtYd")
		)
		(fp_rect
			(start -0.508 0.9398)
			(end 0.508 -0.9398)
			(stroke
				(width 0)
				(type default)
			)
			(fill no)
			(layer "F.Fab")
		)
		(pad "1" smd custom
			(at 0 -0.4445 180)
			(size 0.1397 0.1397)
			(layers "F.Cu" "F.Mask" "F.Paste")
			(net "PE_CLK_100M_DR8_1_R_P")
			(options
				(clearance outline)
				(anchor circle)
			)
			(primitives
				(gr_poly
					(pts
						(arc
							(start -0.1778 -0.2794)
							(mid -0.249642 -0.249642)
							(end -0.2794 -0.1778)
						)
						(arc
							(start -0.2794 0.1778)
							(mid -0.249642 0.249642)
							(end -0.1778 0.2794)
						)
						(arc
							(start 0.1778 0.2794)
							(mid 0.249642 0.249642)
							(end 0.2794 0.1778)
						)
						(arc
							(start 0.2794 -0.1778)
							(mid 0.249642 -0.249642)
							(end 0.1778 -0.2794)
						)
					)
					(width 0)
					(fill yes)
				)
			)
		)
		(pad "2" smd custom
			(at 0 0.4445 180)
			(size 0.1397 0.1397)
			(layers "F.Cu" "F.Mask" "F.Paste")
			(net "PE_CLK100M_DR8_1_P")
			(options
				(clearance outline)
				(anchor circle)
			)
			(primitives
				(gr_poly
					(pts
						(arc
							(start -0.1778 -0.2794)
							(mid -0.249642 -0.249642)
							(end -0.2794 -0.1778)
						)
						(arc
							(start -0.2794 0.1778)
							(mid -0.249642 0.249642)
							(end -0.1778 0.2794)
						)
						(arc
							(start 0.1778 0.2794)
							(mid 0.249642 0.249642)
							(end 0.2794 0.1778)
						)
						(arc
							(start 0.2794 -0.1778)
							(mid 0.249642 -0.249642)
							(end 0.1778 -0.2794)
						)
					)
					(width 0)
					(fill yes)
				)
			)
		)
	)
	(footprint ""
		(layer "F.Cu")
		(at 89.535 -31.877 180)
		(property "Reference" "R382"
			(at 0 0 180)
			(layer "F.SilkS")
			(hide yes)
			(effects
				(font
					(size 1.27 1.27)
				)
			)
		)
		(property "Value" "0R2J-2-GP"
			(at 0.064008 -3.993896 180)
			(unlocked yes)
			(layer "F.Fab")
			(hide yes)
			(effects
				(font
					(size 1.016 1.016)
					(thickness 0.1524)
				)
			)
		)
		(property "Device Type" "R402H16"
			(at 0.064008 -5.517896 180)
			(unlocked yes)
			(layer "F.Fab")
			(hide yes)
			(effects
				(font
					(size 1.016 1.016)
					(thickness 0.1524)
				)
			)
		)
		(duplicate_pad_numbers_are_jumpers no)
		(fp_line
			(start 0.508 -0.9398)
			(end -0.508 -0.9398)
			(stroke
				(width 0.1524)
				(type default)
			)
			(layer "F.SilkS")
		)
		(fp_line
			(start -0.508 -0.9398)
			(end -0.508 0.9398)
			(stroke
				(width 0.1524)
				(type default)
			)
			(layer "F.SilkS")
		)
		(fp_rect
			(start -0.508 0.9398)
			(end 0.508 -0.9398)
			(stroke
				(width 0)
				(type default)
			)
			(fill no)
			(layer "F.CrtYd")
		)
		(fp_rect
			(start -0.508 0.9398)
			(end 0.508 -0.9398)
			(stroke
				(width 0)
				(type default)
			)
			(fill no)
			(layer "F.Fab")
		)
		(pad "1" smd custom
			(at 0 -0.4445 180)
			(size 0.1397 0.1397)
			(layers "F.Cu" "F.Mask" "F.Paste")
			(net "VOL_SEN_SDA")
			(options
				(clearance outline)
				(anchor circle)
			)
			(primitives
				(gr_poly
					(pts
						(arc
							(start -0.1778 -0.2794)
							(mid -0.249642 -0.249642)
							(end -0.2794 -0.1778)
						)
						(arc
							(start -0.2794 0.1778)
							(mid -0.249642 0.249642)
							(end -0.1778 0.2794)
						)
						(arc
							(start 0.1778 0.2794)
							(mid 0.249642 0.249642)
							(end 0.2794 0.1778)
						)
						(arc
							(start 0.2794 -0.1778)
							(mid 0.249642 -0.249642)
							(end 0.1778 -0.2794)
						)
					)
					(width 0)
					(fill yes)
				)
			)
		)
		(pad "2" smd custom
			(at 0 0.4445 180)
			(size 0.1397 0.1397)
			(layers "F.Cu" "F.Mask" "F.Paste")
			(net "I2C_B_SDA")
			(options
				(clearance outline)
				(anchor circle)
			)
			(primitives
				(gr_poly
					(pts
						(arc
							(start -0.1778 -0.2794)
							(mid -0.249642 -0.249642)
							(end -0.2794 -0.1778)
						)
						(arc
							(start -0.2794 0.1778)
							(mid -0.249642 0.249642)
							(end -0.1778 0.2794)
						)
						(arc
							(start 0.1778 0.2794)
							(mid 0.249642 0.249642)
							(end 0.2794 0.1778)
						)
						(arc
							(start 0.2794 -0.1778)
							(mid 0.249642 -0.249642)
							(end 0.1778 -0.2794)
						)
					)
					(width 0)
					(fill yes)
				)
			)
		)
	)
	(footprint ""
		(layer "F.Cu")
		(at 55.2958 -450.1134 -90)
		(property "Reference" "R9816"
			(at 0 0 270)
			(layer "F.SilkS")
			(hide yes)
			(effects
				(font
					(size 1.27 1.27)
				)
			)
		)
		(property "Value" "0R2J-2-GP"
			(at 0.064008 -3.993896 270)
			(unlocked yes)
			(layer "F.Fab")
			(hide yes)
			(effects
				(font
					(size 1.016 1.016)
					(thickness 0.1524)
				)
			)
		)
		(property "Device Type" "R402H16"
			(at 0.064008 -5.517896 270)
			(unlocked yes)
			(layer "F.Fab")
			(hide yes)
			(effects
				(font
					(size 1.016 1.016)
					(thickness 0.1524)
				)
			)
		)
		(duplicate_pad_numbers_are_jumpers no)
		(fp_line
			(start -0.508 -0.9398)
			(end -0.508 0.9398)
			(stroke
				(width 0.1524)
				(type default)
			)
			(layer "F.SilkS")
		)
		(fp_line
			(start 0.508 -0.9398)
			(end -0.508 -0.9398)
			(stroke
				(width 0.1524)
				(type default)
			)
			(layer "F.SilkS")
		)
		(fp_rect
			(start -0.508 0.9398)
			(end 0.508 -0.9398)
			(stroke
				(width 0)
				(type default)
			)
			(fill no)
			(layer "F.CrtYd")
		)
		(fp_rect
			(start -0.508 0.9398)
			(end 0.508 -0.9398)
			(stroke
				(width 0)
				(type default)
			)
			(fill no)
			(layer "F.Fab")
		)
		(pad "1" smd custom
			(at 0 -0.4445 270)
			(size 0.1397 0.1397)
			(layers "F.Cu" "F.Mask" "F.Paste")
			(net "ATTN_LED_DR5_R")
			(options
				(clearance outline)
				(anchor circle)
			)
			(primitives
				(gr_poly
					(pts
						(arc
							(start -0.1778 -0.2794)
							(mid -0.249642 -0.249642)
							(end -0.2794 -0.1778)
						)
						(arc
							(start -0.2794 0.1778)
							(mid -0.249642 0.249642)
							(end -0.1778 0.2794)
						)
						(arc
							(start 0.1778 0.2794)
							(mid 0.249642 0.249642)
							(end 0.2794 0.1778)
						)
						(arc
							(start 0.2794 -0.1778)
							(mid 0.249642 -0.249642)
							(end 0.1778 -0.2794)
						)
					)
					(width 0)
					(fill yes)
				)
			)
		)
		(pad "2" smd custom
			(at 0 0.4445 270)
			(size 0.1397 0.1397)
			(layers "F.Cu" "F.Mask" "F.Paste")
			(net "ATTN_LED_DR5_N")
			(options
				(clearance outline)
				(anchor circle)
			)
			(primitives
				(gr_poly
					(pts
						(arc
							(start -0.1778 -0.2794)
							(mid -0.249642 -0.249642)
							(end -0.2794 -0.1778)
						)
						(arc
							(start -0.2794 0.1778)
							(mid -0.249642 0.249642)
							(end -0.1778 0.2794)
						)
						(arc
							(start 0.1778 0.2794)
							(mid 0.249642 0.249642)
							(end 0.2794 0.1778)
						)
						(arc
							(start 0.2794 -0.1778)
							(mid 0.249642 -0.249642)
							(end 0.1778 -0.2794)
						)
					)
					(width 0)
					(fill yes)
				)
			)
		)
	)
	(footprint ""
		(layer "F.Cu")
		(at 99.187 -318.643)
		(property "Reference" "R9600"
			(at 0 0 0)
			(layer "F.SilkS")
			(hide yes)
			(effects
				(font
					(size 1.27 1.27)
				)
			)
		)
		(property "Value" "10R2F-L-GP"
			(at 0.064008 -3.993896 0)
			(unlocked yes)
			(layer "F.Fab")
			(hide yes)
			(effects
				(font
					(size 1.016 1.016)
					(thickness 0.1524)
				)
			)
		)
		(property "Device Type" "R402H14"
			(at 0.064008 -5.517896 0)
			(unlocked yes)
			(layer "F.Fab")
			(hide yes)
			(effects
				(font
					(size 1.016 1.016)
					(thickness 0.1524)
				)
			)
		)
		(duplicate_pad_numbers_are_jumpers no)
		(fp_line
			(start -0.508 -0.9398)
			(end -0.508 0.9398)
			(stroke
				(width 0.1524)
				(type default)
			)
			(layer "F.SilkS")
		)
		(fp_line
			(start 0.508 -0.9398)
			(end -0.508 -0.9398)
			(stroke
				(width 0.1524)
				(type default)
			)
			(layer "F.SilkS")
		)
		(fp_rect
			(start -0.508 0.9398)
			(end 0.508 -0.9398)
			(stroke
				(width 0)
				(type default)
			)
			(fill no)
			(layer "F.CrtYd")
		)
		(fp_rect
			(start -0.508 0.9398)
			(end 0.508 -0.9398)
			(stroke
				(width 0)
				(type default)
			)
			(fill no)
			(layer "F.Fab")
		)
		(pad "1" smd custom
			(at 0 -0.4445)
			(size 0.1397 0.1397)
			(layers "F.Cu" "F.Mask" "F.Paste")
			(net "SSD_PRSNT_NET6")
			(options
				(clearance outline)
				(anchor circle)
			)
			(primitives
				(gr_poly
					(pts
						(arc
							(start -0.1778 -0.2794)
							(mid -0.249642 -0.249642)
							(end -0.2794 -0.1778)
						)
						(arc
							(start -0.2794 0.1778)
							(mid -0.249642 0.249642)
							(end -0.1778 0.2794)
						)
						(arc
							(start 0.1778 0.2794)
							(mid 0.249642 0.249642)
							(end 0.2794 0.1778)
						)
						(arc
							(start 0.2794 -0.1778)
							(mid 0.249642 -0.249642)
							(end 0.1778 -0.2794)
						)
					)
					(width 0)
					(fill yes)
				)
			)
		)
		(pad "2" smd custom
			(at 0 0.4445)
			(size 0.1397 0.1397)
			(layers "F.Cu" "F.Mask" "F.Paste")
			(net "SSD_PRSNT6")
			(options
				(clearance outline)
				(anchor circle)
			)
			(primitives
				(gr_poly
					(pts
						(arc
							(start -0.1778 -0.2794)
							(mid -0.249642 -0.249642)
							(end -0.2794 -0.1778)
						)
						(arc
							(start -0.2794 0.1778)
							(mid -0.249642 0.249642)
							(end -0.1778 0.2794)
						)
						(arc
							(start 0.1778 0.2794)
							(mid 0.249642 0.249642)
							(end 0.2794 0.1778)
						)
						(arc
							(start 0.2794 -0.1778)
							(mid 0.249642 -0.249642)
							(end 0.1778 -0.2794)
						)
					)
					(width 0)
					(fill yes)
				)
			)
		)
	)
	(footprint ""
		(layer "F.Cu")
		(at 217.805 -436.88 -90)
		(property "Reference" "PL2"
			(at 0 0 270)
			(layer "F.SilkS")
			(hide yes)
			(effects
				(font
					(size 1.27 1.27)
				)
			)
		)
		(property "Value" "COIL-6D8UH-10-GP"
			(at -4.699 -4.0132 270)
			(unlocked yes)
			(layer "F.Fab")
			(hide yes)
			(effects
				(font
					(size 1.016 1.016)
					(thickness 0.1524)
				)
			)
		)
		(property "Device Type" "L7066-1830-UH119"
			(at -4.699 -5.5372 270)
			(unlocked yes)
			(layer "F.Fab")
			(hide yes)
			(effects
				(font
					(size 1.016 1.016)
					(thickness 0.1524)
				)
			)
		)
		(duplicate_pad_numbers_are_jumpers no)
		(fp_line
			(start -3.556 4.4958)
			(end -3.556 -4.4958)
			(stroke
				(width 0.1524)
				(type default)
			)
			(layer "F.SilkS")
		)
		(fp_line
			(start 3.556 4.4958)
			(end -3.556 4.4958)
			(stroke
				(width 0.1524)
				(type default)
			)
			(layer "F.SilkS")
		)
		(fp_line
			(start -3.556 -4.4958)
			(end 3.556 -4.4958)
			(stroke
				(width 0.1524)
				(type default)
			)
			(layer "F.SilkS")
		)
		(fp_line
			(start 3.556 -4.4958)
			(end 3.556 4.4958)
			(stroke
				(width 0.1524)
				(type default)
			)
			(layer "F.SilkS")
		)
		(fp_rect
			(start -3.302 3.4798)
			(end 3.302 -3.4798)
			(stroke
				(width 0)
				(type default)
			)
			(fill no)
			(layer "F.CrtYd")
		)
		(fp_poly
			(pts
				(xy -3.81 4.572) (xy -3.81 -4.572) (xy 3.81 -4.572) (xy 3.81 -0.5588) (xy 3.302 -0.5588) (xy 3.302 -3.4798)
				(xy -3.302 -3.4798) (xy -3.302 3.4798) (xy 3.302 3.4798) (xy 3.302 -0.5461) (xy 3.81 -0.5461) (xy 3.81 4.572)
			)
			(stroke
				(width 0)
				(type default)
			)
			(fill no)
			(layer "F.CrtYd")
		)
		(fp_rect
			(start -3.81 4.572)
			(end 3.81 -4.572)
			(stroke
				(width 0)
				(type default)
			)
			(fill no)
			(layer "F.Fab")
		)
		(pad "1" smd rect
			(at 0 -2.779522 270)
			(size 3.5052 2.921)
			(layers "F.Cu" "F.Mask" "F.Paste")
			(net "P3V3_SW")
		)
		(pad "2" smd rect
			(at 0 2.779522 270)
			(size 3.5052 2.921)
			(layers "F.Cu" "F.Mask" "F.Paste")
			(net "P3V3_OUT")
		)
	)
	(footprint ""
		(layer "F.Cu")
		(at 72.898 -354.965 180)
		(property "Reference" "R429"
			(at 0 0 180)
			(layer "F.SilkS")
			(hide yes)
			(effects
				(font
					(size 1.27 1.27)
				)
			)
		)
		(property "Value" "0R2J-2-GP"
			(at 0.064008 -3.993896 180)
			(unlocked yes)
			(layer "F.Fab")
			(hide yes)
			(effects
				(font
					(size 1.016 1.016)
					(thickness 0.1524)
				)
			)
		)
		(property "Device Type" "R402H16"
			(at 0.064008 -5.517896 180)
			(unlocked yes)
			(layer "F.Fab")
			(hide yes)
			(effects
				(font
					(size 1.016 1.016)
					(thickness 0.1524)
				)
			)
		)
		(duplicate_pad_numbers_are_jumpers no)
		(fp_line
			(start 0.508 -0.9398)
			(end -0.508 -0.9398)
			(stroke
				(width 0.1524)
				(type default)
			)
			(layer "F.SilkS")
		)
		(fp_line
			(start -0.508 -0.9398)
			(end -0.508 0.9398)
			(stroke
				(width 0.1524)
				(type default)
			)
			(layer "F.SilkS")
		)
		(fp_rect
			(start -0.508 0.9398)
			(end 0.508 -0.9398)
			(stroke
				(width 0)
				(type default)
			)
			(fill no)
			(layer "F.CrtYd")
		)
		(fp_rect
			(start -0.508 0.9398)
			(end 0.508 -0.9398)
			(stroke
				(width 0)
				(type default)
			)
			(fill no)
			(layer "F.Fab")
		)
		(pad "1" smd custom
			(at 0 -0.4445 180)
			(size 0.1397 0.1397)
			(layers "F.Cu" "F.Mask" "F.Paste")
			(net "BMC_I2C_SCL_BUF_9")
			(options
				(clearance outline)
				(anchor circle)
			)
			(primitives
				(gr_poly
					(pts
						(arc
							(start -0.1778 -0.2794)
							(mid -0.249642 -0.249642)
							(end -0.2794 -0.1778)
						)
						(arc
							(start -0.2794 0.1778)
							(mid -0.249642 0.249642)
							(end -0.1778 0.2794)
						)
						(arc
							(start 0.1778 0.2794)
							(mid 0.249642 0.249642)
							(end 0.2794 0.1778)
						)
						(arc
							(start 0.2794 -0.1778)
							(mid 0.249642 -0.249642)
							(end 0.1778 -0.2794)
						)
					)
					(width 0)
					(fill yes)
				)
			)
		)
		(pad "2" smd custom
			(at 0 0.4445 180)
			(size 0.1397 0.1397)
			(layers "F.Cu" "F.Mask" "F.Paste")
			(net "I2C8_SCL_R_SW_EU17")
			(options
				(clearance outline)
				(anchor circle)
			)
			(primitives
				(gr_poly
					(pts
						(arc
							(start -0.1778 -0.2794)
							(mid -0.249642 -0.249642)
							(end -0.2794 -0.1778)
						)
						(arc
							(start -0.2794 0.1778)
							(mid -0.249642 0.249642)
							(end -0.1778 0.2794)
						)
						(arc
							(start 0.1778 0.2794)
							(mid 0.249642 0.249642)
							(end 0.2794 0.1778)
						)
						(arc
							(start 0.2794 -0.1778)
							(mid 0.249642 -0.249642)
							(end 0.1778 -0.2794)
						)
					)
					(width 0)
					(fill yes)
				)
			)
		)
	)
	(footprint ""
		(layer "F.Cu")
		(at 50.8 -7.747 180)
		(property "Reference" "R9774"
			(at 0 0 180)
			(layer "F.SilkS")
			(hide yes)
			(effects
				(font
					(size 1.27 1.27)
				)
			)
		)
		(property "Value" "4K7R2J-2-GP"
			(at 0.064008 -3.993896 180)
			(unlocked yes)
			(layer "F.Fab")
			(hide yes)
			(effects
				(font
					(size 1.016 1.016)
					(thickness 0.1524)
				)
			)
		)
		(property "Device Type" "R402H16"
			(at 0.064008 -5.517896 180)
			(unlocked yes)
			(layer "F.Fab")
			(hide yes)
			(effects
				(font
					(size 1.016 1.016)
					(thickness 0.1524)
				)
			)
		)
		(duplicate_pad_numbers_are_jumpers no)
		(fp_line
			(start 0.508 -0.9398)
			(end -0.508 -0.9398)
			(stroke
				(width 0.1524)
				(type default)
			)
			(layer "F.SilkS")
		)
		(fp_line
			(start -0.508 -0.9398)
			(end -0.508 0.9398)
			(stroke
				(width 0.1524)
				(type default)
			)
			(layer "F.SilkS")
		)
		(fp_rect
			(start -0.508 0.9398)
			(end 0.508 -0.9398)
			(stroke
				(width 0)
				(type default)
			)
			(fill no)
			(layer "F.CrtYd")
		)
		(fp_rect
			(start -0.508 0.9398)
			(end 0.508 -0.9398)
			(stroke
				(width 0)
				(type default)
			)
			(fill no)
			(layer "F.Fab")
		)
		(pad "1" smd custom
			(at 0 -0.4445 180)
			(size 0.1397 0.1397)
			(layers "F.Cu" "F.Mask" "F.Paste")
			(net "SSD14_PWREN")
			(options
				(clearance outline)
				(anchor circle)
			)
			(primitives
				(gr_poly
					(pts
						(arc
							(start -0.1778 -0.2794)
							(mid -0.249642 -0.249642)
							(end -0.2794 -0.1778)
						)
						(arc
							(start -0.2794 0.1778)
							(mid -0.249642 0.249642)
							(end -0.1778 0.2794)
						)
						(arc
							(start 0.1778 0.2794)
							(mid 0.249642 0.249642)
							(end 0.2794 0.1778)
						)
						(arc
							(start 0.2794 -0.1778)
							(mid 0.249642 -0.249642)
							(end 0.1778 -0.2794)
						)
					)
					(width 0)
					(fill yes)
				)
			)
		)
		(pad "2" smd custom
			(at 0 0.4445 180)
			(size 0.1397 0.1397)
			(layers "F.Cu" "F.Mask" "F.Paste")
			(net "GND")
			(options
				(clearance outline)
				(anchor circle)
			)
			(primitives
				(gr_poly
					(pts
						(arc
							(start -0.1778 -0.2794)
							(mid -0.249642 -0.249642)
							(end -0.2794 -0.1778)
						)
						(arc
							(start -0.2794 0.1778)
							(mid -0.249642 0.249642)
							(end -0.1778 0.2794)
						)
						(arc
							(start 0.1778 0.2794)
							(mid 0.249642 0.249642)
							(end 0.2794 0.1778)
						)
						(arc
							(start 0.2794 -0.1778)
							(mid 0.249642 -0.249642)
							(end 0.1778 -0.2794)
						)
					)
					(width 0)
					(fill yes)
				)
			)
		)
	)
	(footprint ""
		(layer "F.Cu")
		(at 222.123 -245.104158)
		(property "Reference" "Q40"
			(at 0 0 0)
			(layer "F.SilkS")
			(hide yes)
			(effects
				(font
					(size 1.27 1.27)
				)
			)
		)
		(property "Value" "2N7002A-7-GP"
			(at 0.127 -8.9662 0)
			(unlocked yes)
			(layer "F.Fab")
			(hide yes)
			(effects
				(font
					(size 1.016 1.016)
					(thickness 0.1524)
				)
			)
		)
		(property "Device Type" "SOT23DGS2D4H48"
			(at 0.127 -10.4902 0)
			(unlocked yes)
			(layer "F.Fab")
			(hide yes)
			(effects
				(font
					(size 1.016 1.016)
					(thickness 0.1524)
				)
			)
		)
		(duplicate_pad_numbers_are_jumpers no)
		(fp_line
			(start -1.651 -1.778)
			(end -1.651 1.778)
			(stroke
				(width 0.1524)
				(type default)
			)
			(layer "F.SilkS")
		)
		(fp_line
			(start -1.651 1.778)
			(end 1.651 1.778)
			(stroke
				(width 0.1524)
				(type default)
			)
			(layer "F.SilkS")
		)
		(fp_line
			(start 1.651 -1.778)
			(end -1.651 -1.778)
			(stroke
				(width 0.1524)
				(type default)
			)
			(layer "F.SilkS")
		)
		(fp_line
			(start 1.651 1.778)
			(end 1.651 -1.778)
			(stroke
				(width 0.1524)
				(type default)
			)
			(layer "F.SilkS")
		)
		(fp_poly
			(pts
				(xy -1.778 1.8796) (xy -1.778 -1.8796) (xy 1.778 -1.8796) (xy 1.778 1.8796)
			)
			(stroke
				(width 0)
				(type default)
			)
			(fill no)
			(layer "F.CrtYd")
		)
		(fp_poly
			(pts
				(xy -1.778 1.8796) (xy -1.778 -1.8796) (xy 1.778 -1.8796) (xy 1.778 1.8796)
			)
			(stroke
				(width 0)
				(type default)
			)
			(fill no)
			(layer "F.Fab")
		)
		(pad "D" smd custom
			(at 0 -0.9525)
			(size 0.1905 0.1905)
			(layers "F.Cu" "F.Mask" "F.Paste")
			(net "ATTN_LED_DR2_MOS_N")
			(options
				(clearance outline)
				(anchor circle)
			)
			(primitives
				(gr_poly
					(pts
						(arc
							(start -0.1778 0.5715)
							(mid -0.321484 0.511984)
							(end -0.381 0.3683)
						)
						(arc
							(start -0.381 -0.3683)
							(mid -0.321484 -0.511984)
							(end -0.1778 -0.5715)
						)
						(arc
							(start 0.1778 -0.5715)
							(mid 0.321484 -0.511984)
							(end 0.381 -0.3683)
						)
						(arc
							(start 0.381 0.3683)
							(mid 0.321484 0.511984)
							(end 0.1778 0.5715)
						)
					)
					(width 0)
					(fill yes)
				)
			)
		)
		(pad "G" smd custom
			(at -0.98425 0.9525)
			(size 0.1905 0.1905)
			(layers "F.Cu" "F.Mask" "F.Paste")
			(net "SSD2_CLK0_OE_MOS_N")
			(options
				(clearance outline)
				(anchor circle)
			)
			(primitives
				(gr_poly
					(pts
						(arc
							(start -0.1778 0.5715)
							(mid -0.321484 0.511984)
							(end -0.381 0.3683)
						)
						(arc
							(start -0.381 -0.3683)
							(mid -0.321484 -0.511984)
							(end -0.1778 -0.5715)
						)
						(arc
							(start 0.1778 -0.5715)
							(mid 0.321484 -0.511984)
							(end 0.381 -0.3683)
						)
						(arc
							(start 0.381 0.3683)
							(mid 0.321484 0.511984)
							(end 0.1778 0.5715)
						)
					)
					(width 0)
					(fill yes)
				)
			)
		)
		(pad "S" smd custom
			(at 0.98425 0.9525)
			(size 0.1905 0.1905)
			(layers "F.Cu" "F.Mask" "F.Paste")
			(net "ATTN_LED_DR2_R")
			(options
				(clearance outline)
				(anchor circle)
			)
			(primitives
				(gr_poly
					(pts
						(arc
							(start -0.1778 0.5715)
							(mid -0.321484 0.511984)
							(end -0.381 0.3683)
						)
						(arc
							(start -0.381 -0.3683)
							(mid -0.321484 -0.511984)
							(end -0.1778 -0.5715)
						)
						(arc
							(start 0.1778 -0.5715)
							(mid 0.321484 -0.511984)
							(end 0.381 -0.3683)
						)
						(arc
							(start 0.381 0.3683)
							(mid 0.321484 0.511984)
							(end 0.1778 0.5715)
						)
					)
					(width 0)
					(fill yes)
				)
			)
		)
	)
	(footprint ""
		(layer "F.Cu")
		(at 87.503 -306.324 180)
		(property "Reference" "C8912"
			(at 0 0 180)
			(layer "F.SilkS")
			(hide yes)
			(effects
				(font
					(size 1.27 1.27)
				)
			)
		)
		(property "Value" "SCD1U16V2KX-3GP"
			(at 1.1811 -2.7051 180)
			(unlocked yes)
			(layer "F.Fab")
			(hide yes)
			(effects
				(font
					(size 1.016 1.016)
					(thickness 0.1524)
				)
			)
		)
		(property "Device Type" "C402H22"
			(at 1.1811 -4.2291 180)
			(unlocked yes)
			(layer "F.Fab")
			(hide yes)
			(effects
				(font
					(size 1.016 1.016)
					(thickness 0.1524)
				)
			)
		)
		(duplicate_pad_numbers_are_jumpers no)
		(fp_rect
			(start -0.4318 0.9525)
			(end 0.4318 -0.9525)
			(stroke
				(width 0)
				(type default)
			)
			(fill no)
			(layer "F.CrtYd")
		)
		(fp_rect
			(start -0.4318 0.9525)
			(end 0.4318 -0.9525)
			(stroke
				(width 0)
				(type default)
			)
			(fill no)
			(layer "F.Fab")
		)
		(pad "1" smd custom
			(at 0 -0.4445 180)
			(size 0.1524 0.1524)
			(layers "F.Cu" "F.Mask" "F.Paste")
			(net "VDDR_2")
			(options
				(clearance outline)
				(anchor circle)
			)
			(primitives
				(gr_poly
					(pts
						(arc
							(start 0.3048 -0.2032)
							(mid 0.275042 -0.275042)
							(end 0.2032 -0.3048)
						)
						(arc
							(start -0.2032 -0.3048)
							(mid -0.275042 -0.275042)
							(end -0.3048 -0.2032)
						)
						(arc
							(start -0.3048 0.2032)
							(mid -0.275042 0.275042)
							(end -0.2032 0.3048)
						)
						(arc
							(start 0.2032 0.3048)
							(mid 0.275042 0.275042)
							(end 0.3048 0.2032)
						)
					)
					(width 0)
					(fill yes)
				)
			)
		)
		(pad "2" smd custom
			(at 0 0.4445 180)
			(size 0.1524 0.1524)
			(layers "F.Cu" "F.Mask" "F.Paste")
			(net "GND")
			(options
				(clearance outline)
				(anchor circle)
			)
			(primitives
				(gr_poly
					(pts
						(arc
							(start 0.3048 -0.2032)
							(mid 0.275042 -0.275042)
							(end 0.2032 -0.3048)
						)
						(arc
							(start -0.2032 -0.3048)
							(mid -0.275042 -0.275042)
							(end -0.3048 -0.2032)
						)
						(arc
							(start -0.3048 0.2032)
							(mid -0.275042 0.275042)
							(end -0.2032 0.3048)
						)
						(arc
							(start 0.2032 0.3048)
							(mid 0.275042 0.275042)
							(end 0.3048 0.2032)
						)
					)
					(width 0)
					(fill yes)
				)
			)
		)
	)
	(footprint ""
		(layer "F.Cu")
		(at 44.677076 -35.474402)
		(property "Reference" "C9527"
			(at 0 0 0)
			(layer "F.SilkS")
			(hide yes)
			(effects
				(font
					(size 1.27 1.27)
				)
			)
		)
		(property "Value" "SCD1U16V2KX-3GP"
			(at 1.1811 -2.7051 0)
			(unlocked yes)
			(layer "F.Fab")
			(hide yes)
			(effects
				(font
					(size 1.016 1.016)
					(thickness 0.1524)
				)
			)
		)
		(property "Device Type" "C402H22"
			(at 1.1811 -4.2291 0)
			(unlocked yes)
			(layer "F.Fab")
			(hide yes)
			(effects
				(font
					(size 1.016 1.016)
					(thickness 0.1524)
				)
			)
		)
		(duplicate_pad_numbers_are_jumpers no)
		(fp_rect
			(start -0.4318 0.9525)
			(end 0.4318 -0.9525)
			(stroke
				(width 0)
				(type default)
			)
			(fill no)
			(layer "F.CrtYd")
		)
		(fp_rect
			(start -0.4318 0.9525)
			(end 0.4318 -0.9525)
			(stroke
				(width 0)
				(type default)
			)
			(fill no)
			(layer "F.Fab")
		)
		(pad "1" smd custom
			(at 0 -0.4445)
			(size 0.1524 0.1524)
			(layers "F.Cu" "F.Mask" "F.Paste")
			(net "P3V3")
			(options
				(clearance outline)
				(anchor circle)
			)
			(primitives
				(gr_poly
					(pts
						(arc
							(start 0.3048 -0.2032)
							(mid 0.275042 -0.275042)
							(end 0.2032 -0.3048)
						)
						(arc
							(start -0.2032 -0.3048)
							(mid -0.275042 -0.275042)
							(end -0.3048 -0.2032)
						)
						(arc
							(start -0.3048 0.2032)
							(mid -0.275042 0.275042)
							(end -0.2032 0.3048)
						)
						(arc
							(start 0.2032 0.3048)
							(mid 0.275042 0.275042)
							(end 0.3048 0.2032)
						)
					)
					(width 0)
					(fill yes)
				)
			)
		)
		(pad "2" smd custom
			(at 0 0.4445)
			(size 0.1524 0.1524)
			(layers "F.Cu" "F.Mask" "F.Paste")
			(net "GND")
			(options
				(clearance outline)
				(anchor circle)
			)
			(primitives
				(gr_poly
					(pts
						(arc
							(start 0.3048 -0.2032)
							(mid 0.275042 -0.275042)
							(end 0.2032 -0.3048)
						)
						(arc
							(start -0.2032 -0.3048)
							(mid -0.275042 -0.275042)
							(end -0.3048 -0.2032)
						)
						(arc
							(start -0.3048 0.2032)
							(mid -0.275042 0.275042)
							(end -0.2032 0.3048)
						)
						(arc
							(start 0.2032 0.3048)
							(mid 0.275042 0.275042)
							(end 0.3048 0.2032)
						)
					)
					(width 0)
					(fill yes)
				)
			)
		)
	)
	(footprint ""
		(layer "F.Cu")
		(at 98.679 -291.719 180)
		(property "Reference" "R9593"
			(at 0 0 180)
			(layer "F.SilkS")
			(hide yes)
			(effects
				(font
					(size 1.27 1.27)
				)
			)
		)
		(property "Value" "10R2F-L-GP"
			(at 0.064008 -3.993896 180)
			(unlocked yes)
			(layer "F.Fab")
			(hide yes)
			(effects
				(font
					(size 1.016 1.016)
					(thickness 0.1524)
				)
			)
		)
		(property "Device Type" "R402H14"
			(at 0.064008 -5.517896 180)
			(unlocked yes)
			(layer "F.Fab")
			(hide yes)
			(effects
				(font
					(size 1.016 1.016)
					(thickness 0.1524)
				)
			)
		)
		(duplicate_pad_numbers_are_jumpers no)
		(fp_line
			(start 0.508 -0.9398)
			(end -0.508 -0.9398)
			(stroke
				(width 0.1524)
				(type default)
			)
			(layer "F.SilkS")
		)
		(fp_line
			(start -0.508 -0.9398)
			(end -0.508 0.9398)
			(stroke
				(width 0.1524)
				(type default)
			)
			(layer "F.SilkS")
		)
		(fp_rect
			(start -0.508 0.9398)
			(end 0.508 -0.9398)
			(stroke
				(width 0)
				(type default)
			)
			(fill no)
			(layer "F.CrtYd")
		)
		(fp_rect
			(start -0.508 0.9398)
			(end 0.508 -0.9398)
			(stroke
				(width 0)
				(type default)
			)
			(fill no)
			(layer "F.Fab")
		)
		(pad "1" smd custom
			(at 0 -0.4445 180)
			(size 0.1397 0.1397)
			(layers "F.Cu" "F.Mask" "F.Paste")
			(net "SSD2_CLK0_OE_N")
			(options
				(clearance outline)
				(anchor circle)
			)
			(primitives
				(gr_poly
					(pts
						(arc
							(start -0.1778 -0.2794)
							(mid -0.249642 -0.249642)
							(end -0.2794 -0.1778)
						)
						(arc
							(start -0.2794 0.1778)
							(mid -0.249642 0.249642)
							(end -0.1778 0.2794)
						)
						(arc
							(start 0.1778 0.2794)
							(mid 0.249642 0.249642)
							(end 0.2794 0.1778)
						)
						(arc
							(start 0.2794 -0.1778)
							(mid 0.249642 -0.249642)
							(end 0.1778 -0.2794)
						)
					)
					(width 0)
					(fill yes)
				)
			)
		)
		(pad "2" smd custom
			(at 0 0.4445 180)
			(size 0.1397 0.1397)
			(layers "F.Cu" "F.Mask" "F.Paste")
			(net "SSD2_CLK0_OE_R_N")
			(options
				(clearance outline)
				(anchor circle)
			)
			(primitives
				(gr_poly
					(pts
						(arc
							(start -0.1778 -0.2794)
							(mid -0.249642 -0.249642)
							(end -0.2794 -0.1778)
						)
						(arc
							(start -0.2794 0.1778)
							(mid -0.249642 0.249642)
							(end -0.1778 0.2794)
						)
						(arc
							(start 0.1778 0.2794)
							(mid 0.249642 0.249642)
							(end 0.2794 0.1778)
						)
						(arc
							(start 0.2794 -0.1778)
							(mid 0.249642 -0.249642)
							(end 0.1778 -0.2794)
						)
					)
					(width 0)
					(fill yes)
				)
			)
		)
	)
	(footprint ""
		(layer "F.Cu")
		(at 217.4748 -84.455 180)
		(property "Reference" "SR1100"
			(at 0 0 180)
			(layer "F.SilkS")
			(hide yes)
			(effects
				(font
					(size 1.27 1.27)
				)
			)
		)
		(property "Value" "4K7R2F-GP"
			(at 0.064008 -3.993896 180)
			(unlocked yes)
			(layer "F.Fab")
			(hide yes)
			(effects
				(font
					(size 1.016 1.016)
					(thickness 0.1524)
				)
			)
		)
		(property "Device Type" "R402H16"
			(at 0.064008 -5.517896 180)
			(unlocked yes)
			(layer "F.Fab")
			(hide yes)
			(effects
				(font
					(size 1.016 1.016)
					(thickness 0.1524)
				)
			)
		)
		(duplicate_pad_numbers_are_jumpers no)
		(fp_line
			(start 0.508 -0.9398)
			(end -0.508 -0.9398)
			(stroke
				(width 0.1524)
				(type default)
			)
			(layer "F.SilkS")
		)
		(fp_line
			(start -0.508 -0.9398)
			(end -0.508 0.9398)
			(stroke
				(width 0.1524)
				(type default)
			)
			(layer "F.SilkS")
		)
		(fp_rect
			(start -0.508 0.9398)
			(end 0.508 -0.9398)
			(stroke
				(width 0)
				(type default)
			)
			(fill no)
			(layer "F.CrtYd")
		)
		(fp_rect
			(start -0.508 0.9398)
			(end 0.508 -0.9398)
			(stroke
				(width 0)
				(type default)
			)
			(fill no)
			(layer "F.Fab")
		)
		(pad "1" smd custom
			(at 0 -0.4445 180)
			(size 0.1397 0.1397)
			(layers "F.Cu" "F.Mask" "F.Paste")
			(net "DUALPORTEN#4")
			(options
				(clearance outline)
				(anchor circle)
			)
			(primitives
				(gr_poly
					(pts
						(arc
							(start -0.1778 -0.2794)
							(mid -0.249642 -0.249642)
							(end -0.2794 -0.1778)
						)
						(arc
							(start -0.2794 0.1778)
							(mid -0.249642 0.249642)
							(end -0.1778 0.2794)
						)
						(arc
							(start 0.1778 0.2794)
							(mid 0.249642 0.249642)
							(end 0.2794 0.1778)
						)
						(arc
							(start 0.2794 -0.1778)
							(mid 0.249642 -0.249642)
							(end 0.1778 -0.2794)
						)
					)
					(width 0)
					(fill yes)
				)
			)
		)
		(pad "2" smd custom
			(at 0 0.4445 180)
			(size 0.1397 0.1397)
			(layers "F.Cu" "F.Mask" "F.Paste")
			(net "GND")
			(options
				(clearance outline)
				(anchor circle)
			)
			(primitives
				(gr_poly
					(pts
						(arc
							(start -0.1778 -0.2794)
							(mid -0.249642 -0.249642)
							(end -0.2794 -0.1778)
						)
						(arc
							(start -0.2794 0.1778)
							(mid -0.249642 0.249642)
							(end -0.1778 0.2794)
						)
						(arc
							(start 0.1778 0.2794)
							(mid 0.249642 0.249642)
							(end 0.2794 0.1778)
						)
						(arc
							(start 0.2794 -0.1778)
							(mid 0.249642 -0.249642)
							(end 0.1778 -0.2794)
						)
					)
					(width 0)
					(fill yes)
				)
			)
		)
	)
	(footprint ""
		(layer "F.Cu")
		(at 88.519 -18.669 180)
		(property "Reference" "R364"
			(at 0 0 180)
			(layer "F.SilkS")
			(hide yes)
			(effects
				(font
					(size 1.27 1.27)
				)
			)
		)
		(property "Value" "4K7R2F-GP"
			(at 0.064008 -3.993896 180)
			(unlocked yes)
			(layer "F.Fab")
			(hide yes)
			(effects
				(font
					(size 1.016 1.016)
					(thickness 0.1524)
				)
			)
		)
		(property "Device Type" "R402H16"
			(at 0.064008 -5.517896 180)
			(unlocked yes)
			(layer "F.Fab")
			(hide yes)
			(effects
				(font
					(size 1.016 1.016)
					(thickness 0.1524)
				)
			)
		)
		(duplicate_pad_numbers_are_jumpers no)
		(fp_line
			(start 0.508 -0.9398)
			(end -0.508 -0.9398)
			(stroke
				(width 0.1524)
				(type default)
			)
			(layer "F.SilkS")
		)
		(fp_line
			(start -0.508 -0.9398)
			(end -0.508 0.9398)
			(stroke
				(width 0.1524)
				(type default)
			)
			(layer "F.SilkS")
		)
		(fp_rect
			(start -0.508 0.9398)
			(end 0.508 -0.9398)
			(stroke
				(width 0)
				(type default)
			)
			(fill no)
			(layer "F.CrtYd")
		)
		(fp_rect
			(start -0.508 0.9398)
			(end 0.508 -0.9398)
			(stroke
				(width 0)
				(type default)
			)
			(fill no)
			(layer "F.Fab")
		)
		(pad "1" smd custom
			(at 0 -0.4445 180)
			(size 0.1397 0.1397)
			(layers "F.Cu" "F.Mask" "F.Paste")
			(net "P3V3")
			(options
				(clearance outline)
				(anchor circle)
			)
			(primitives
				(gr_poly
					(pts
						(arc
							(start -0.1778 -0.2794)
							(mid -0.249642 -0.249642)
							(end -0.2794 -0.1778)
						)
						(arc
							(start -0.2794 0.1778)
							(mid -0.249642 0.249642)
							(end -0.1778 0.2794)
						)
						(arc
							(start 0.1778 0.2794)
							(mid 0.249642 0.249642)
							(end 0.2794 0.1778)
						)
						(arc
							(start 0.2794 -0.1778)
							(mid 0.249642 -0.249642)
							(end 0.1778 -0.2794)
						)
					)
					(width 0)
					(fill yes)
				)
			)
		)
		(pad "2" smd custom
			(at 0 0.4445 180)
			(size 0.1397 0.1397)
			(layers "F.Cu" "F.Mask" "F.Paste")
			(net "VOL_SEN_ADDR")
			(options
				(clearance outline)
				(anchor circle)
			)
			(primitives
				(gr_poly
					(pts
						(arc
							(start -0.1778 -0.2794)
							(mid -0.249642 -0.249642)
							(end -0.2794 -0.1778)
						)
						(arc
							(start -0.2794 0.1778)
							(mid -0.249642 0.249642)
							(end -0.1778 0.2794)
						)
						(arc
							(start 0.1778 0.2794)
							(mid 0.249642 0.249642)
							(end 0.2794 0.1778)
						)
						(arc
							(start 0.2794 -0.1778)
							(mid 0.249642 -0.249642)
							(end 0.1778 -0.2794)
						)
					)
					(width 0)
					(fill yes)
				)
			)
		)
	)
	(footprint ""
		(layer "F.Cu")
		(at 32.131 -391.795 -90)
		(property "Reference" "R400"
			(at 0 0 270)
			(layer "F.SilkS")
			(hide yes)
			(effects
				(font
					(size 1.27 1.27)
				)
			)
		)
		(property "Value" "0R2J-2-GP"
			(at 0.064008 -3.993896 270)
			(unlocked yes)
			(layer "F.Fab")
			(hide yes)
			(effects
				(font
					(size 1.016 1.016)
					(thickness 0.1524)
				)
			)
		)
		(property "Device Type" "R402H16"
			(at 0.064008 -5.517896 270)
			(unlocked yes)
			(layer "F.Fab")
			(hide yes)
			(effects
				(font
					(size 1.016 1.016)
					(thickness 0.1524)
				)
			)
		)
		(duplicate_pad_numbers_are_jumpers no)
		(fp_line
			(start -0.508 -0.9398)
			(end -0.508 0.9398)
			(stroke
				(width 0.1524)
				(type default)
			)
			(layer "F.SilkS")
		)
		(fp_line
			(start 0.508 -0.9398)
			(end -0.508 -0.9398)
			(stroke
				(width 0.1524)
				(type default)
			)
			(layer "F.SilkS")
		)
		(fp_rect
			(start -0.508 0.9398)
			(end 0.508 -0.9398)
			(stroke
				(width 0)
				(type default)
			)
			(fill no)
			(layer "F.CrtYd")
		)
		(fp_rect
			(start -0.508 0.9398)
			(end 0.508 -0.9398)
			(stroke
				(width 0)
				(type default)
			)
			(fill no)
			(layer "F.Fab")
		)
		(pad "1" smd custom
			(at 0 -0.4445 270)
			(size 0.1397 0.1397)
			(layers "F.Cu" "F.Mask" "F.Paste")
			(net "SDA_DR6_R")
			(options
				(clearance outline)
				(anchor circle)
			)
			(primitives
				(gr_poly
					(pts
						(arc
							(start -0.1778 -0.2794)
							(mid -0.249642 -0.249642)
							(end -0.2794 -0.1778)
						)
						(arc
							(start -0.2794 0.1778)
							(mid -0.249642 0.249642)
							(end -0.1778 0.2794)
						)
						(arc
							(start 0.1778 0.2794)
							(mid 0.249642 0.249642)
							(end 0.2794 0.1778)
						)
						(arc
							(start 0.2794 -0.1778)
							(mid 0.249642 -0.249642)
							(end 0.1778 -0.2794)
						)
					)
					(width 0)
					(fill yes)
				)
			)
		)
		(pad "2" smd custom
			(at 0 0.4445 270)
			(size 0.1397 0.1397)
			(layers "F.Cu" "F.Mask" "F.Paste")
			(net "SDA_DR6")
			(options
				(clearance outline)
				(anchor circle)
			)
			(primitives
				(gr_poly
					(pts
						(arc
							(start -0.1778 -0.2794)
							(mid -0.249642 -0.249642)
							(end -0.2794 -0.1778)
						)
						(arc
							(start -0.2794 0.1778)
							(mid -0.249642 0.249642)
							(end -0.1778 0.2794)
						)
						(arc
							(start 0.1778 0.2794)
							(mid 0.249642 0.249642)
							(end 0.2794 0.1778)
						)
						(arc
							(start 0.2794 -0.1778)
							(mid 0.249642 -0.249642)
							(end 0.1778 -0.2794)
						)
					)
					(width 0)
					(fill yes)
				)
			)
		)
	)
	(footprint ""
		(layer "F.Cu")
		(at 225.759264 -42.761916 90)
		(property "Reference" "R9935"
			(at 0 0 90)
			(layer "F.SilkS")
			(hide yes)
			(effects
				(font
					(size 1.27 1.27)
				)
			)
		)
		(property "Value" "4K7R2J-2-GP"
			(at 0.064008 -3.993896 90)
			(unlocked yes)
			(layer "F.Fab")
			(hide yes)
			(effects
				(font
					(size 1.016 1.016)
					(thickness 0.1524)
				)
			)
		)
		(property "Device Type" "R402H16"
			(at 0.064008 -5.517896 90)
			(unlocked yes)
			(layer "F.Fab")
			(hide yes)
			(effects
				(font
					(size 1.016 1.016)
					(thickness 0.1524)
				)
			)
		)
		(duplicate_pad_numbers_are_jumpers no)
		(fp_line
			(start 0.508 -0.9398)
			(end -0.508 -0.9398)
			(stroke
				(width 0.1524)
				(type default)
			)
			(layer "F.SilkS")
		)
		(fp_line
			(start -0.508 -0.9398)
			(end -0.508 0.9398)
			(stroke
				(width 0.1524)
				(type default)
			)
			(layer "F.SilkS")
		)
		(fp_rect
			(start -0.508 0.9398)
			(end 0.508 -0.9398)
			(stroke
				(width 0)
				(type default)
			)
			(fill no)
			(layer "F.CrtYd")
		)
		(fp_rect
			(start -0.508 0.9398)
			(end 0.508 -0.9398)
			(stroke
				(width 0)
				(type default)
			)
			(fill no)
			(layer "F.Fab")
		)
		(pad "1" smd custom
			(at 0 -0.4445 90)
			(size 0.1397 0.1397)
			(layers "F.Cu" "F.Mask" "F.Paste")
			(net "P3V3")
			(options
				(clearance outline)
				(anchor circle)
			)
			(primitives
				(gr_poly
					(pts
						(arc
							(start -0.1778 -0.2794)
							(mid -0.249642 -0.249642)
							(end -0.2794 -0.1778)
						)
						(arc
							(start -0.2794 0.1778)
							(mid -0.249642 0.249642)
							(end -0.1778 0.2794)
						)
						(arc
							(start 0.1778 0.2794)
							(mid 0.249642 0.249642)
							(end 0.2794 0.1778)
						)
						(arc
							(start 0.2794 -0.1778)
							(mid 0.249642 -0.249642)
							(end 0.1778 -0.2794)
						)
					)
					(width 0)
					(fill yes)
				)
			)
		)
		(pad "2" smd custom
			(at 0 0.4445 90)
			(size 0.1397 0.1397)
			(layers "F.Cu" "F.Mask" "F.Paste")
			(net "ATTN_LED_DR4_MOS_N")
			(options
				(clearance outline)
				(anchor circle)
			)
			(primitives
				(gr_poly
					(pts
						(arc
							(start -0.1778 -0.2794)
							(mid -0.249642 -0.249642)
							(end -0.2794 -0.1778)
						)
						(arc
							(start -0.2794 0.1778)
							(mid -0.249642 0.249642)
							(end -0.1778 0.2794)
						)
						(arc
							(start 0.1778 0.2794)
							(mid 0.249642 0.249642)
							(end 0.2794 0.1778)
						)
						(arc
							(start 0.2794 -0.1778)
							(mid 0.249642 -0.249642)
							(end 0.1778 -0.2794)
						)
					)
					(width 0)
					(fill yes)
				)
			)
		)
	)
	(footprint ""
		(layer "F.Cu")
		(at 234.061 -39.497 -90)
		(property "Reference" "R9896"
			(at 0 0 270)
			(layer "F.SilkS")
			(hide yes)
			(effects
				(font
					(size 1.27 1.27)
				)
			)
		)
		(property "Value" "1K82R2F-1-GP"
			(at 0.064008 -3.993896 270)
			(unlocked yes)
			(layer "F.Fab")
			(hide yes)
			(effects
				(font
					(size 1.016 1.016)
					(thickness 0.1524)
				)
			)
		)
		(property "Device Type" "R402H16"
			(at 0.064008 -5.517896 270)
			(unlocked yes)
			(layer "F.Fab")
			(hide yes)
			(effects
				(font
					(size 1.016 1.016)
					(thickness 0.1524)
				)
			)
		)
		(duplicate_pad_numbers_are_jumpers no)
		(fp_line
			(start -0.508 -0.9398)
			(end -0.508 0.9398)
			(stroke
				(width 0.1524)
				(type default)
			)
			(layer "F.SilkS")
		)
		(fp_line
			(start 0.508 -0.9398)
			(end -0.508 -0.9398)
			(stroke
				(width 0.1524)
				(type default)
			)
			(layer "F.SilkS")
		)
		(fp_rect
			(start -0.508 0.9398)
			(end 0.508 -0.9398)
			(stroke
				(width 0)
				(type default)
			)
			(fill no)
			(layer "F.CrtYd")
		)
		(fp_rect
			(start -0.508 0.9398)
			(end 0.508 -0.9398)
			(stroke
				(width 0)
				(type default)
			)
			(fill no)
			(layer "F.Fab")
		)
		(pad "1" smd custom
			(at 0 -0.4445 270)
			(size 0.1397 0.1397)
			(layers "F.Cu" "F.Mask" "F.Paste")
			(net "P12V")
			(options
				(clearance outline)
				(anchor circle)
			)
			(primitives
				(gr_poly
					(pts
						(arc
							(start -0.1778 -0.2794)
							(mid -0.249642 -0.249642)
							(end -0.2794 -0.1778)
						)
						(arc
							(start -0.2794 0.1778)
							(mid -0.249642 0.249642)
							(end -0.1778 0.2794)
						)
						(arc
							(start 0.1778 0.2794)
							(mid 0.249642 0.249642)
							(end 0.2794 0.1778)
						)
						(arc
							(start 0.2794 -0.1778)
							(mid 0.249642 -0.249642)
							(end 0.1778 -0.2794)
						)
					)
					(width 0)
					(fill yes)
				)
			)
		)
		(pad "2" smd custom
			(at 0 0.4445 270)
			(size 0.1397 0.1397)
			(layers "F.Cu" "F.Mask" "F.Paste")
			(net "DRV_ACT_4")
			(options
				(clearance outline)
				(anchor circle)
			)
			(primitives
				(gr_poly
					(pts
						(arc
							(start -0.1778 -0.2794)
							(mid -0.249642 -0.249642)
							(end -0.2794 -0.1778)
						)
						(arc
							(start -0.2794 0.1778)
							(mid -0.249642 0.249642)
							(end -0.1778 0.2794)
						)
						(arc
							(start 0.1778 0.2794)
							(mid 0.249642 0.249642)
							(end 0.2794 0.1778)
						)
						(arc
							(start 0.2794 -0.1778)
							(mid 0.249642 -0.249642)
							(end 0.1778 -0.2794)
						)
					)
					(width 0)
					(fill yes)
				)
			)
		)
	)
	(footprint ""
		(layer "F.Cu")
		(at 22.86 -300.228 180)
		(property "Reference" "R9618"
			(at 0 0 180)
			(layer "F.SilkS")
			(hide yes)
			(effects
				(font
					(size 1.27 1.27)
				)
			)
		)
		(property "Value" "4K7R2J-2-GP"
			(at 0.064008 -3.993896 180)
			(unlocked yes)
			(layer "F.Fab")
			(hide yes)
			(effects
				(font
					(size 1.016 1.016)
					(thickness 0.1524)
				)
			)
		)
		(property "Device Type" "R402H16"
			(at 0.064008 -5.517896 180)
			(unlocked yes)
			(layer "F.Fab")
			(hide yes)
			(effects
				(font
					(size 1.016 1.016)
					(thickness 0.1524)
				)
			)
		)
		(duplicate_pad_numbers_are_jumpers no)
		(fp_line
			(start 0.508 -0.9398)
			(end -0.508 -0.9398)
			(stroke
				(width 0.1524)
				(type default)
			)
			(layer "F.SilkS")
		)
		(fp_line
			(start -0.508 -0.9398)
			(end -0.508 0.9398)
			(stroke
				(width 0.1524)
				(type default)
			)
			(layer "F.SilkS")
		)
		(fp_rect
			(start -0.508 0.9398)
			(end 0.508 -0.9398)
			(stroke
				(width 0)
				(type default)
			)
			(fill no)
			(layer "F.CrtYd")
		)
		(fp_rect
			(start -0.508 0.9398)
			(end 0.508 -0.9398)
			(stroke
				(width 0)
				(type default)
			)
			(fill no)
			(layer "F.Fab")
		)
		(pad "1" smd custom
			(at 0 -0.4445 180)
			(size 0.1397 0.1397)
			(layers "F.Cu" "F.Mask" "F.Paste")
			(net "P3V3")
			(options
				(clearance outline)
				(anchor circle)
			)
			(primitives
				(gr_poly
					(pts
						(arc
							(start -0.1778 -0.2794)
							(mid -0.249642 -0.249642)
							(end -0.2794 -0.1778)
						)
						(arc
							(start -0.2794 0.1778)
							(mid -0.249642 0.249642)
							(end -0.1778 0.2794)
						)
						(arc
							(start 0.1778 0.2794)
							(mid 0.249642 0.249642)
							(end 0.2794 0.1778)
						)
						(arc
							(start 0.2794 -0.1778)
							(mid 0.249642 -0.249642)
							(end 0.1778 -0.2794)
						)
					)
					(width 0)
					(fill yes)
				)
			)
		)
		(pad "2" smd custom
			(at 0 0.4445 180)
			(size 0.1397 0.1397)
			(layers "F.Cu" "F.Mask" "F.Paste")
			(net "SSD7_PWREN")
			(options
				(clearance outline)
				(anchor circle)
			)
			(primitives
				(gr_poly
					(pts
						(arc
							(start -0.1778 -0.2794)
							(mid -0.249642 -0.249642)
							(end -0.2794 -0.1778)
						)
						(arc
							(start -0.2794 0.1778)
							(mid -0.249642 0.249642)
							(end -0.1778 0.2794)
						)
						(arc
							(start 0.1778 0.2794)
							(mid 0.249642 0.249642)
							(end 0.2794 0.1778)
						)
						(arc
							(start 0.2794 -0.1778)
							(mid 0.249642 -0.249642)
							(end 0.1778 -0.2794)
						)
					)
					(width 0)
					(fill yes)
				)
			)
		)
	)
	(footprint ""
		(layer "F.Cu")
		(at 100.33 -92.964)
		(property "Reference" "R9126"
			(at 0 0 0)
			(layer "F.SilkS")
			(hide yes)
			(effects
				(font
					(size 1.27 1.27)
				)
			)
		)
		(property "Value" "27R2F-GP"
			(at 0.064008 -3.993896 0)
			(unlocked yes)
			(layer "F.Fab")
			(hide yes)
			(effects
				(font
					(size 1.016 1.016)
					(thickness 0.1524)
				)
			)
		)
		(property "Device Type" "R402H16"
			(at 0.064008 -5.517896 0)
			(unlocked yes)
			(layer "F.Fab")
			(hide yes)
			(effects
				(font
					(size 1.016 1.016)
					(thickness 0.1524)
				)
			)
		)
		(duplicate_pad_numbers_are_jumpers no)
		(fp_line
			(start -0.508 -0.9398)
			(end -0.508 0.9398)
			(stroke
				(width 0.1524)
				(type default)
			)
			(layer "F.SilkS")
		)
		(fp_line
			(start 0.508 -0.9398)
			(end -0.508 -0.9398)
			(stroke
				(width 0.1524)
				(type default)
			)
			(layer "F.SilkS")
		)
		(fp_rect
			(start -0.508 0.9398)
			(end 0.508 -0.9398)
			(stroke
				(width 0)
				(type default)
			)
			(fill no)
			(layer "F.CrtYd")
		)
		(fp_rect
			(start -0.508 0.9398)
			(end 0.508 -0.9398)
			(stroke
				(width 0)
				(type default)
			)
			(fill no)
			(layer "F.Fab")
		)
		(pad "1" smd custom
			(at 0 -0.4445)
			(size 0.1397 0.1397)
			(layers "F.Cu" "F.Mask" "F.Paste")
			(net "PE_CLK_100M_DR14_1_R_N")
			(options
				(clearance outline)
				(anchor circle)
			)
			(primitives
				(gr_poly
					(pts
						(arc
							(start -0.1778 -0.2794)
							(mid -0.249642 -0.249642)
							(end -0.2794 -0.1778)
						)
						(arc
							(start -0.2794 0.1778)
							(mid -0.249642 0.249642)
							(end -0.1778 0.2794)
						)
						(arc
							(start 0.1778 0.2794)
							(mid 0.249642 0.249642)
							(end 0.2794 0.1778)
						)
						(arc
							(start 0.2794 -0.1778)
							(mid 0.249642 -0.249642)
							(end 0.1778 -0.2794)
						)
					)
					(width 0)
					(fill yes)
				)
			)
		)
		(pad "2" smd custom
			(at 0 0.4445)
			(size 0.1397 0.1397)
			(layers "F.Cu" "F.Mask" "F.Paste")
			(net "PE_CLK100M_DR14_1_N")
			(options
				(clearance outline)
				(anchor circle)
			)
			(primitives
				(gr_poly
					(pts
						(arc
							(start -0.1778 -0.2794)
							(mid -0.249642 -0.249642)
							(end -0.2794 -0.1778)
						)
						(arc
							(start -0.2794 0.1778)
							(mid -0.249642 0.249642)
							(end -0.1778 0.2794)
						)
						(arc
							(start 0.1778 0.2794)
							(mid 0.249642 0.249642)
							(end 0.2794 0.1778)
						)
						(arc
							(start 0.2794 -0.1778)
							(mid 0.249642 -0.249642)
							(end 0.1778 -0.2794)
						)
					)
					(width 0)
					(fill yes)
				)
			)
		)
	)
	(footprint ""
		(layer "F.Cu")
		(at 249.8852 -360.6292)
		(property "Reference" "PC1290"
			(at 0 0 0)
			(layer "F.SilkS")
			(hide yes)
			(effects
				(font
					(size 1.27 1.27)
				)
			)
		)
		(property "Value" "SC10U25V6KX-4GP"
			(at -0.0762 -5.1308 0)
			(unlocked yes)
			(layer "F.Fab")
			(hide yes)
			(effects
				(font
					(size 1.016 1.016)
					(thickness 0.1524)
				)
			)
		)
		(property "Device Type" "C1206H71"
			(at -0.127 -6.6548 0)
			(unlocked yes)
			(layer "F.Fab")
			(hide yes)
			(effects
				(font
					(size 1.016 1.016)
					(thickness 0.1524)
				)
			)
		)
		(duplicate_pad_numbers_are_jumpers no)
		(fp_line
			(start -1.016 -2.2352)
			(end 1.016 -2.2352)
			(stroke
				(width 0.1524)
				(type default)
			)
			(layer "F.SilkS")
		)
		(fp_line
			(start -1.016 -0.8382)
			(end -1.016 -2.2352)
			(stroke
				(width 0.1524)
				(type default)
			)
			(layer "F.SilkS")
		)
		(fp_line
			(start -1.016 2.2352)
			(end -1.016 0.8382)
			(stroke
				(width 0.1524)
				(type default)
			)
			(layer "F.SilkS")
		)
		(fp_line
			(start 1.016 -2.2352)
			(end 1.016 -0.8382)
			(stroke
				(width 0.1524)
				(type default)
			)
			(layer "F.SilkS")
		)
		(fp_line
			(start 1.016 0.8382)
			(end 1.016 2.2352)
			(stroke
				(width 0.1524)
				(type default)
			)
			(layer "F.SilkS")
		)
		(fp_line
			(start 1.016 2.2352)
			(end -1.016 2.2352)
			(stroke
				(width 0.1524)
				(type default)
			)
			(layer "F.SilkS")
		)
		(fp_rect
			(start -1.0922 2.3114)
			(end 1.0922 -2.3114)
			(stroke
				(width 0)
				(type default)
			)
			(fill no)
			(layer "F.CrtYd")
		)
		(fp_poly
			(pts
				(xy 1.0922 -2.3114) (xy 1.0922 2.3114) (xy -1.0922 2.3114) (xy -1.0922 -2.3114)
			)
			(stroke
				(width 0)
				(type default)
			)
			(fill no)
			(layer "F.Fab")
		)
		(pad "1" smd rect
			(at 0 -1.397)
			(size 1.651 1.27)
			(layers "F.Cu" "F.Mask" "F.Paste")
			(net "P12V")
		)
		(pad "2" smd rect
			(at 0 1.397)
			(size 1.651 1.27)
			(layers "F.Cu" "F.Mask" "F.Paste")
			(net "GND")
		)
	)
	(footprint ""
		(layer "F.Cu")
		(at 229.67696 -241.118898)
		(property "Reference" "C9520"
			(at 0 0 0)
			(layer "F.SilkS")
			(hide yes)
			(effects
				(font
					(size 1.27 1.27)
				)
			)
		)
		(property "Value" "SCD1U16V2KX-3GP"
			(at 1.1811 -2.7051 0)
			(unlocked yes)
			(layer "F.Fab")
			(hide yes)
			(effects
				(font
					(size 1.016 1.016)
					(thickness 0.1524)
				)
			)
		)
		(property "Device Type" "C402H22"
			(at 1.1811 -4.2291 0)
			(unlocked yes)
			(layer "F.Fab")
			(hide yes)
			(effects
				(font
					(size 1.016 1.016)
					(thickness 0.1524)
				)
			)
		)
		(duplicate_pad_numbers_are_jumpers no)
		(fp_rect
			(start -0.4318 0.9525)
			(end 0.4318 -0.9525)
			(stroke
				(width 0)
				(type default)
			)
			(fill no)
			(layer "F.CrtYd")
		)
		(fp_rect
			(start -0.4318 0.9525)
			(end 0.4318 -0.9525)
			(stroke
				(width 0)
				(type default)
			)
			(fill no)
			(layer "F.Fab")
		)
		(pad "1" smd custom
			(at 0 -0.4445)
			(size 0.1524 0.1524)
			(layers "F.Cu" "F.Mask" "F.Paste")
			(net "P3V3")
			(options
				(clearance outline)
				(anchor circle)
			)
			(primitives
				(gr_poly
					(pts
						(arc
							(start 0.3048 -0.2032)
							(mid 0.275042 -0.275042)
							(end 0.2032 -0.3048)
						)
						(arc
							(start -0.2032 -0.3048)
							(mid -0.275042 -0.275042)
							(end -0.3048 -0.2032)
						)
						(arc
							(start -0.3048 0.2032)
							(mid -0.275042 0.275042)
							(end -0.2032 0.3048)
						)
						(arc
							(start 0.2032 0.3048)
							(mid 0.275042 0.275042)
							(end 0.3048 0.2032)
						)
					)
					(width 0)
					(fill yes)
				)
			)
		)
		(pad "2" smd custom
			(at 0 0.4445)
			(size 0.1524 0.1524)
			(layers "F.Cu" "F.Mask" "F.Paste")
			(net "GND")
			(options
				(clearance outline)
				(anchor circle)
			)
			(primitives
				(gr_poly
					(pts
						(arc
							(start 0.3048 -0.2032)
							(mid 0.275042 -0.275042)
							(end 0.2032 -0.3048)
						)
						(arc
							(start -0.2032 -0.3048)
							(mid -0.275042 -0.275042)
							(end -0.3048 -0.2032)
						)
						(arc
							(start -0.3048 0.2032)
							(mid -0.275042 0.275042)
							(end -0.2032 0.3048)
						)
						(arc
							(start 0.2032 0.3048)
							(mid 0.275042 0.275042)
							(end 0.3048 0.2032)
						)
					)
					(width 0)
					(fill yes)
				)
			)
		)
	)
	(footprint ""
		(layer "F.Cu")
		(at 79.121 -354.076)
		(property "Reference" "SR1156"
			(at 0 0 0)
			(layer "F.SilkS")
			(hide yes)
			(effects
				(font
					(size 1.27 1.27)
				)
			)
		)
		(property "Value" "4K7R2F-GP"
			(at 0.064008 -3.993896 0)
			(unlocked yes)
			(layer "F.Fab")
			(hide yes)
			(effects
				(font
					(size 1.016 1.016)
					(thickness 0.1524)
				)
			)
		)
		(property "Device Type" "R402H16"
			(at 0.064008 -5.517896 0)
			(unlocked yes)
			(layer "F.Fab")
			(hide yes)
			(effects
				(font
					(size 1.016 1.016)
					(thickness 0.1524)
				)
			)
		)
		(duplicate_pad_numbers_are_jumpers no)
		(fp_line
			(start -0.508 -0.9398)
			(end -0.508 0.9398)
			(stroke
				(width 0.1524)
				(type default)
			)
			(layer "F.SilkS")
		)
		(fp_line
			(start 0.508 -0.9398)
			(end -0.508 -0.9398)
			(stroke
				(width 0.1524)
				(type default)
			)
			(layer "F.SilkS")
		)
		(fp_rect
			(start -0.508 0.9398)
			(end 0.508 -0.9398)
			(stroke
				(width 0)
				(type default)
			)
			(fill no)
			(layer "F.CrtYd")
		)
		(fp_rect
			(start -0.508 0.9398)
			(end 0.508 -0.9398)
			(stroke
				(width 0)
				(type default)
			)
			(fill no)
			(layer "F.Fab")
		)
		(pad "1" smd custom
			(at 0 -0.4445)
			(size 0.1397 0.1397)
			(layers "F.Cu" "F.Mask" "F.Paste")
			(net "I2C_SW_EU17_ADDRESS_A1")
			(options
				(clearance outline)
				(anchor circle)
			)
			(primitives
				(gr_poly
					(pts
						(arc
							(start -0.1778 -0.2794)
							(mid -0.249642 -0.249642)
							(end -0.2794 -0.1778)
						)
						(arc
							(start -0.2794 0.1778)
							(mid -0.249642 0.249642)
							(end -0.1778 0.2794)
						)
						(arc
							(start 0.1778 0.2794)
							(mid 0.249642 0.249642)
							(end 0.2794 0.1778)
						)
						(arc
							(start 0.2794 -0.1778)
							(mid 0.249642 -0.249642)
							(end 0.1778 -0.2794)
						)
					)
					(width 0)
					(fill yes)
				)
			)
		)
		(pad "2" smd custom
			(at 0 0.4445)
			(size 0.1397 0.1397)
			(layers "F.Cu" "F.Mask" "F.Paste")
			(net "GND")
			(options
				(clearance outline)
				(anchor circle)
			)
			(primitives
				(gr_poly
					(pts
						(arc
							(start -0.1778 -0.2794)
							(mid -0.249642 -0.249642)
							(end -0.2794 -0.1778)
						)
						(arc
							(start -0.2794 0.1778)
							(mid -0.249642 0.249642)
							(end -0.1778 0.2794)
						)
						(arc
							(start 0.1778 0.2794)
							(mid 0.249642 0.249642)
							(end 0.2794 0.1778)
						)
						(arc
							(start 0.2794 -0.1778)
							(mid 0.249642 -0.249642)
							(end 0.1778 -0.2794)
						)
					)
					(width 0)
					(fill yes)
				)
			)
		)
	)
	(footprint ""
		(layer "F.Cu")
		(at 84.455 -425.958 90)
		(property "Reference" "PR9008"
			(at 0 0 90)
			(layer "F.SilkS")
			(hide yes)
			(effects
				(font
					(size 1.27 1.27)
				)
			)
		)
		(property "Value" "4K7R2F-GP"
			(at 0.064008 -3.993896 90)
			(unlocked yes)
			(layer "F.Fab")
			(hide yes)
			(effects
				(font
					(size 1.016 1.016)
					(thickness 0.1524)
				)
			)
		)
		(property "Device Type" "R402H16"
			(at 0.064008 -5.517896 90)
			(unlocked yes)
			(layer "F.Fab")
			(hide yes)
			(effects
				(font
					(size 1.016 1.016)
					(thickness 0.1524)
				)
			)
		)
		(duplicate_pad_numbers_are_jumpers no)
		(fp_line
			(start 0.508 -0.9398)
			(end -0.508 -0.9398)
			(stroke
				(width 0.1524)
				(type default)
			)
			(layer "F.SilkS")
		)
		(fp_line
			(start -0.508 -0.9398)
			(end -0.508 0.9398)
			(stroke
				(width 0.1524)
				(type default)
			)
			(layer "F.SilkS")
		)
		(fp_rect
			(start -0.508 0.9398)
			(end 0.508 -0.9398)
			(stroke
				(width 0)
				(type default)
			)
			(fill no)
			(layer "F.CrtYd")
		)
		(fp_rect
			(start -0.508 0.9398)
			(end 0.508 -0.9398)
			(stroke
				(width 0)
				(type default)
			)
			(fill no)
			(layer "F.Fab")
		)
		(pad "1" smd custom
			(at 0 -0.4445 90)
			(size 0.1397 0.1397)
			(layers "F.Cu" "F.Mask" "F.Paste")
			(net "VDD_DIFF_1")
			(options
				(clearance outline)
				(anchor circle)
			)
			(primitives
				(gr_poly
					(pts
						(arc
							(start -0.1778 -0.2794)
							(mid -0.249642 -0.249642)
							(end -0.2794 -0.1778)
						)
						(arc
							(start -0.2794 0.1778)
							(mid -0.249642 0.249642)
							(end -0.1778 0.2794)
						)
						(arc
							(start 0.1778 0.2794)
							(mid 0.249642 0.249642)
							(end 0.2794 0.1778)
						)
						(arc
							(start 0.2794 -0.1778)
							(mid 0.249642 -0.249642)
							(end 0.1778 -0.2794)
						)
					)
					(width 0)
					(fill yes)
				)
			)
		)
		(pad "2" smd custom
			(at 0 0.4445 90)
			(size 0.1397 0.1397)
			(layers "F.Cu" "F.Mask" "F.Paste")
			(net "CLK_BUF_EU1_SMB_A1_TRI")
			(options
				(clearance outline)
				(anchor circle)
			)
			(primitives
				(gr_poly
					(pts
						(arc
							(start -0.1778 -0.2794)
							(mid -0.249642 -0.249642)
							(end -0.2794 -0.1778)
						)
						(arc
							(start -0.2794 0.1778)
							(mid -0.249642 0.249642)
							(end -0.1778 0.2794)
						)
						(arc
							(start 0.1778 0.2794)
							(mid 0.249642 0.249642)
							(end 0.2794 0.1778)
						)
						(arc
							(start 0.2794 -0.1778)
							(mid 0.249642 -0.249642)
							(end 0.1778 -0.2794)
						)
					)
					(width 0)
					(fill yes)
				)
			)
		)
	)
	(footprint ""
		(layer "F.Cu")
		(at 52.66055 -6.02615 -90)
		(property "Reference" "R9871"
			(at 0 0 270)
			(layer "F.SilkS")
			(hide yes)
			(effects
				(font
					(size 1.27 1.27)
				)
			)
		)
		(property "Value" "1KR2J-1-GP"
			(at 0.064008 -3.993896 270)
			(unlocked yes)
			(layer "F.Fab")
			(hide yes)
			(effects
				(font
					(size 1.016 1.016)
					(thickness 0.1524)
				)
			)
		)
		(property "Device Type" "R402H16"
			(at 0.064008 -5.517896 270)
			(unlocked yes)
			(layer "F.Fab")
			(hide yes)
			(effects
				(font
					(size 1.016 1.016)
					(thickness 0.1524)
				)
			)
		)
		(duplicate_pad_numbers_are_jumpers no)
		(fp_line
			(start -0.508 -0.9398)
			(end -0.508 0.9398)
			(stroke
				(width 0.1524)
				(type default)
			)
			(layer "F.SilkS")
		)
		(fp_line
			(start 0.508 -0.9398)
			(end -0.508 -0.9398)
			(stroke
				(width 0.1524)
				(type default)
			)
			(layer "F.SilkS")
		)
		(fp_rect
			(start -0.508 0.9398)
			(end 0.508 -0.9398)
			(stroke
				(width 0)
				(type default)
			)
			(fill no)
			(layer "F.CrtYd")
		)
		(fp_rect
			(start -0.508 0.9398)
			(end 0.508 -0.9398)
			(stroke
				(width 0)
				(type default)
			)
			(fill no)
			(layer "F.Fab")
		)
		(pad "1" smd custom
			(at 0 -0.4445 270)
			(size 0.1397 0.1397)
			(layers "F.Cu" "F.Mask" "F.Paste")
			(net "SSD14_PWREN")
			(options
				(clearance outline)
				(anchor circle)
			)
			(primitives
				(gr_poly
					(pts
						(arc
							(start -0.1778 -0.2794)
							(mid -0.249642 -0.249642)
							(end -0.2794 -0.1778)
						)
						(arc
							(start -0.2794 0.1778)
							(mid -0.249642 0.249642)
							(end -0.1778 0.2794)
						)
						(arc
							(start 0.1778 0.2794)
							(mid 0.249642 0.249642)
							(end 0.2794 0.1778)
						)
						(arc
							(start 0.2794 -0.1778)
							(mid 0.249642 -0.249642)
							(end 0.1778 -0.2794)
						)
					)
					(width 0)
					(fill yes)
				)
			)
		)
		(pad "2" smd custom
			(at 0 0.4445 270)
			(size 0.1397 0.1397)
			(layers "F.Cu" "F.Mask" "F.Paste")
			(net "SSD14_PWREN_R")
			(options
				(clearance outline)
				(anchor circle)
			)
			(primitives
				(gr_poly
					(pts
						(arc
							(start -0.1778 -0.2794)
							(mid -0.249642 -0.249642)
							(end -0.2794 -0.1778)
						)
						(arc
							(start -0.2794 0.1778)
							(mid -0.249642 0.249642)
							(end -0.1778 0.2794)
						)
						(arc
							(start 0.1778 0.2794)
							(mid 0.249642 0.249642)
							(end 0.2794 0.1778)
						)
						(arc
							(start 0.2794 -0.1778)
							(mid 0.249642 -0.249642)
							(end 0.1778 -0.2794)
						)
					)
					(width 0)
					(fill yes)
				)
			)
		)
	)
	(footprint ""
		(layer "F.Cu")
		(at 72.136 -154.178)
		(property "Reference" "SR973"
			(at 0 0 0)
			(layer "F.SilkS")
			(hide yes)
			(effects
				(font
					(size 1.27 1.27)
				)
			)
		)
		(property "Value" "2KR2F-3-GP"
			(at 0.064008 -3.993896 0)
			(unlocked yes)
			(layer "F.Fab")
			(hide yes)
			(effects
				(font
					(size 1.016 1.016)
					(thickness 0.1524)
				)
			)
		)
		(property "Device Type" "R402H16"
			(at 0.064008 -5.517896 0)
			(unlocked yes)
			(layer "F.Fab")
			(hide yes)
			(effects
				(font
					(size 1.016 1.016)
					(thickness 0.1524)
				)
			)
		)
		(duplicate_pad_numbers_are_jumpers no)
		(fp_line
			(start -0.508 -0.9398)
			(end -0.508 0.9398)
			(stroke
				(width 0.1524)
				(type default)
			)
			(layer "F.SilkS")
		)
		(fp_line
			(start 0.508 -0.9398)
			(end -0.508 -0.9398)
			(stroke
				(width 0.1524)
				(type default)
			)
			(layer "F.SilkS")
		)
		(fp_rect
			(start -0.508 0.9398)
			(end 0.508 -0.9398)
			(stroke
				(width 0)
				(type default)
			)
			(fill no)
			(layer "F.CrtYd")
		)
		(fp_rect
			(start -0.508 0.9398)
			(end 0.508 -0.9398)
			(stroke
				(width 0)
				(type default)
			)
			(fill no)
			(layer "F.Fab")
		)
		(pad "1" smd custom
			(at 0 -0.4445)
			(size 0.1397 0.1397)
			(layers "F.Cu" "F.Mask" "F.Paste")
			(net "P3V3")
			(options
				(clearance outline)
				(anchor circle)
			)
			(primitives
				(gr_poly
					(pts
						(arc
							(start -0.1778 -0.2794)
							(mid -0.249642 -0.249642)
							(end -0.2794 -0.1778)
						)
						(arc
							(start -0.2794 0.1778)
							(mid -0.249642 0.249642)
							(end -0.1778 0.2794)
						)
						(arc
							(start 0.1778 0.2794)
							(mid 0.249642 0.249642)
							(end 0.2794 0.1778)
						)
						(arc
							(start 0.2794 -0.1778)
							(mid 0.249642 -0.249642)
							(end 0.1778 -0.2794)
						)
					)
					(width 0)
					(fill yes)
				)
			)
		)
		(pad "2" smd custom
			(at 0 0.4445)
			(size 0.1397 0.1397)
			(layers "F.Cu" "F.Mask" "F.Paste")
			(net "SCL_DR12")
			(options
				(clearance outline)
				(anchor circle)
			)
			(primitives
				(gr_poly
					(pts
						(arc
							(start -0.1778 -0.2794)
							(mid -0.249642 -0.249642)
							(end -0.2794 -0.1778)
						)
						(arc
							(start -0.2794 0.1778)
							(mid -0.249642 0.249642)
							(end -0.1778 0.2794)
						)
						(arc
							(start 0.1778 0.2794)
							(mid 0.249642 0.249642)
							(end 0.2794 0.1778)
						)
						(arc
							(start 0.2794 -0.1778)
							(mid 0.249642 -0.249642)
							(end 0.1778 -0.2794)
						)
					)
					(width 0)
					(fill yes)
				)
			)
		)
	)
	(footprint ""
		(layer "F.Cu")
		(at 43.999912 -137.999978 -90)
		(property "Reference" "U51"
			(at 0 0 270)
			(layer "F.SilkS")
			(hide yes)
			(effects
				(font
					(size 1.27 1.27)
				)
			)
		)
		(property "Value" "TMP75AIDGKR-GP"
			(at -0.1143 -9.1948 270)
			(unlocked yes)
			(layer "F.Fab")
			(hide yes)
			(effects
				(font
					(size 1.016 1.016)
					(thickness 0.1524)
				)
			)
		)
		(property "Device Type" "MSOP8-1H44"
			(at -0.1143 -10.795 270)
			(unlocked yes)
			(layer "F.Fab")
			(hide yes)
			(effects
				(font
					(size 1.016 1.016)
					(thickness 0.1524)
				)
			)
		)
		(duplicate_pad_numbers_are_jumpers no)
		(fp_line
			(start -1.778 1.0922)
			(end -1.778 3.048)
			(stroke
				(width 0.508)
				(type default)
			)
			(layer "F.SilkS")
		)
		(fp_line
			(start -1.9558 1.016)
			(end 1.0795 1.016)
			(stroke
				(width 0.1524)
				(type default)
			)
			(layer "F.SilkS")
		)
		(fp_line
			(start 1.0795 1.016)
			(end 1.0795 -1.016)
			(stroke
				(width 0.1524)
				(type default)
			)
			(layer "F.SilkS")
		)
		(fp_line
			(start -1.4478 -0.0381)
			(end -1.9558 0.4699)
			(stroke
				(width 0.1524)
				(type default)
			)
			(layer "F.SilkS")
		)
		(fp_line
			(start -1.9558 -0.5461)
			(end -1.4478 -0.0381)
			(stroke
				(width 0.1524)
				(type default)
			)
			(layer "F.SilkS")
		)
		(fp_line
			(start -1.9558 -1.016)
			(end -1.9558 1.016)
			(stroke
				(width 0.1524)
				(type default)
			)
			(layer "F.SilkS")
		)
		(fp_line
			(start 1.0795 -1.016)
			(end -1.9558 -1.016)
			(stroke
				(width 0.1524)
				(type default)
			)
			(layer "F.SilkS")
		)
		(fp_poly
			(pts
				(xy -1.1557 -1.016) (xy -1.1557 1.016) (xy 1.1557 1.016) (xy 1.1557 -1.016)
			)
			(stroke
				(width 0)
				(type default)
			)
			(fill yes)
			(layer "F.SilkS")
		)
		(fp_rect
			(start -1.4986 2.4511)
			(end 1.4986 -2.4511)
			(stroke
				(width 0)
				(type default)
			)
			(fill no)
			(layer "F.CrtYd")
		)
		(fp_poly
			(pts
				(xy -2.032 3.302) (xy -2.032 -3.302) (xy 2.032 -3.302) (xy 2.032 -2.1209) (xy 1.4986 -2.1209) (xy 1.4986 -2.4511)
				(xy -1.4986 -2.4511) (xy -1.4986 2.4511) (xy 1.4986 2.4511) (xy 1.4986 -2.1082) (xy 2.032 -2.1082)
				(xy 2.032 3.302)
			)
			(stroke
				(width 0)
				(type default)
			)
			(fill no)
			(layer "F.CrtYd")
		)
		(fp_rect
			(start -2.032 3.302)
			(end 2.032 -3.302)
			(stroke
				(width 0)
				(type default)
			)
			(fill no)
			(layer "F.Fab")
		)
		(pad "1" smd rect
			(at -0.97536 2.05486 270)
			(size 0.3556 1.524)
			(layers "F.Cu" "F.Mask" "F.Paste")
			(net "TMP1_SDA")
		)
		(pad "2" smd rect
			(at -0.32512 2.05486 270)
			(size 0.3556 1.524)
			(layers "F.Cu" "F.Mask" "F.Paste")
			(net "TMP1_SCL")
		)
		(pad "3" smd rect
			(at 0.32512 2.05486 270)
			(size 0.3556 1.524)
			(layers "F.Cu" "F.Mask" "F.Paste")
			(net "I2C_B_TMP1_ALERT")
		)
		(pad "4" smd rect
			(at 0.97536 2.05486 270)
			(size 0.3556 1.524)
			(layers "F.Cu" "F.Mask" "F.Paste")
			(net "GND")
		)
		(pad "5" smd rect
			(at 0.97536 -2.05486 270)
			(size 0.3556 1.524)
			(layers "F.Cu" "F.Mask" "F.Paste")
			(net "I2C_B_TMP1_A2")
		)
		(pad "6" smd rect
			(at 0.32512 -2.05486 270)
			(size 0.3556 1.524)
			(layers "F.Cu" "F.Mask" "F.Paste")
			(net "I2C_B_TMP1_A1")
		)
		(pad "7" smd rect
			(at -0.32512 -2.05486 270)
			(size 0.3556 1.524)
			(layers "F.Cu" "F.Mask" "F.Paste")
			(net "I2C_B_TMP1_A0")
		)
		(pad "8" smd rect
			(at -0.97536 -2.05486 270)
			(size 0.3556 1.524)
			(layers "F.Cu" "F.Mask" "F.Paste")
			(net "P3V3")
		)
	)
	(footprint ""
		(layer "F.Cu")
		(at 70.739 -361.569 90)
		(property "Reference" "SR981"
			(at 0 0 90)
			(layer "F.SilkS")
			(hide yes)
			(effects
				(font
					(size 1.27 1.27)
				)
			)
		)
		(property "Value" "2KR2F-3-GP"
			(at 0.064008 -3.993896 90)
			(unlocked yes)
			(layer "F.Fab")
			(hide yes)
			(effects
				(font
					(size 1.016 1.016)
					(thickness 0.1524)
				)
			)
		)
		(property "Device Type" "R402H16"
			(at 0.064008 -5.517896 90)
			(unlocked yes)
			(layer "F.Fab")
			(hide yes)
			(effects
				(font
					(size 1.016 1.016)
					(thickness 0.1524)
				)
			)
		)
		(duplicate_pad_numbers_are_jumpers no)
		(fp_line
			(start 0.508 -0.9398)
			(end -0.508 -0.9398)
			(stroke
				(width 0.1524)
				(type default)
			)
			(layer "F.SilkS")
		)
		(fp_line
			(start -0.508 -0.9398)
			(end -0.508 0.9398)
			(stroke
				(width 0.1524)
				(type default)
			)
			(layer "F.SilkS")
		)
		(fp_rect
			(start -0.508 0.9398)
			(end 0.508 -0.9398)
			(stroke
				(width 0)
				(type default)
			)
			(fill no)
			(layer "F.CrtYd")
		)
		(fp_rect
			(start -0.508 0.9398)
			(end 0.508 -0.9398)
			(stroke
				(width 0)
				(type default)
			)
			(fill no)
			(layer "F.Fab")
		)
		(pad "1" smd custom
			(at 0 -0.4445 90)
			(size 0.1397 0.1397)
			(layers "F.Cu" "F.Mask" "F.Paste")
			(net "P3V3")
			(options
				(clearance outline)
				(anchor circle)
			)
			(primitives
				(gr_poly
					(pts
						(arc
							(start -0.1778 -0.2794)
							(mid -0.249642 -0.249642)
							(end -0.2794 -0.1778)
						)
						(arc
							(start -0.2794 0.1778)
							(mid -0.249642 0.249642)
							(end -0.1778 0.2794)
						)
						(arc
							(start 0.1778 0.2794)
							(mid 0.249642 0.249642)
							(end 0.2794 0.1778)
						)
						(arc
							(start 0.2794 -0.1778)
							(mid 0.249642 -0.249642)
							(end 0.1778 -0.2794)
						)
					)
					(width 0)
					(fill yes)
				)
			)
		)
		(pad "2" smd custom
			(at 0 0.4445 90)
			(size 0.1397 0.1397)
			(layers "F.Cu" "F.Mask" "F.Paste")
			(net "SCL_DR11")
			(options
				(clearance outline)
				(anchor circle)
			)
			(primitives
				(gr_poly
					(pts
						(arc
							(start -0.1778 -0.2794)
							(mid -0.249642 -0.249642)
							(end -0.2794 -0.1778)
						)
						(arc
							(start -0.2794 0.1778)
							(mid -0.249642 0.249642)
							(end -0.1778 0.2794)
						)
						(arc
							(start 0.1778 0.2794)
							(mid 0.249642 0.249642)
							(end 0.2794 0.1778)
						)
						(arc
							(start 0.2794 -0.1778)
							(mid 0.249642 -0.249642)
							(end 0.1778 -0.2794)
						)
					)
					(width 0)
					(fill yes)
				)
			)
		)
	)
	(footprint ""
		(layer "F.Cu")
		(at 49.022 -14.859 180)
		(property "Reference" "C396"
			(at 0 0 180)
			(layer "F.SilkS")
			(hide yes)
			(effects
				(font
					(size 1.27 1.27)
				)
			)
		)
		(property "Value" "SCD1U25V2KX-2-GP"
			(at 1.1811 -2.7051 180)
			(unlocked yes)
			(layer "F.Fab")
			(hide yes)
			(effects
				(font
					(size 1.016 1.016)
					(thickness 0.1524)
				)
			)
		)
		(property "Device Type" "C402H22"
			(at 1.1811 -4.2291 180)
			(unlocked yes)
			(layer "F.Fab")
			(hide yes)
			(effects
				(font
					(size 1.016 1.016)
					(thickness 0.1524)
				)
			)
		)
		(duplicate_pad_numbers_are_jumpers no)
		(fp_rect
			(start -0.4318 0.9525)
			(end 0.4318 -0.9525)
			(stroke
				(width 0)
				(type default)
			)
			(fill no)
			(layer "F.CrtYd")
		)
		(fp_rect
			(start -0.4318 0.9525)
			(end 0.4318 -0.9525)
			(stroke
				(width 0)
				(type default)
			)
			(fill no)
			(layer "F.Fab")
		)
		(pad "1" smd custom
			(at 0 -0.4445 180)
			(size 0.1524 0.1524)
			(layers "F.Cu" "F.Mask" "F.Paste")
			(net "P12V")
			(options
				(clearance outline)
				(anchor circle)
			)
			(primitives
				(gr_poly
					(pts
						(arc
							(start 0.3048 -0.2032)
							(mid 0.275042 -0.275042)
							(end 0.2032 -0.3048)
						)
						(arc
							(start -0.2032 -0.3048)
							(mid -0.275042 -0.275042)
							(end -0.3048 -0.2032)
						)
						(arc
							(start -0.3048 0.2032)
							(mid -0.275042 0.275042)
							(end -0.2032 0.3048)
						)
						(arc
							(start 0.2032 0.3048)
							(mid 0.275042 0.275042)
							(end 0.3048 0.2032)
						)
					)
					(width 0)
					(fill yes)
				)
			)
		)
		(pad "2" smd custom
			(at 0 0.4445 180)
			(size 0.1524 0.1524)
			(layers "F.Cu" "F.Mask" "F.Paste")
			(net "SW_SSD14_N")
			(options
				(clearance outline)
				(anchor circle)
			)
			(primitives
				(gr_poly
					(pts
						(arc
							(start 0.3048 -0.2032)
							(mid 0.275042 -0.275042)
							(end 0.2032 -0.3048)
						)
						(arc
							(start -0.2032 -0.3048)
							(mid -0.275042 -0.275042)
							(end -0.3048 -0.2032)
						)
						(arc
							(start -0.3048 0.2032)
							(mid -0.275042 0.275042)
							(end -0.2032 0.3048)
						)
						(arc
							(start 0.2032 0.3048)
							(mid 0.275042 0.275042)
							(end 0.3048 0.2032)
						)
					)
					(width 0)
					(fill yes)
				)
			)
		)
	)
	(footprint ""
		(layer "F.Cu")
		(at 214.7824 -393.573)
		(property "Reference" "SR1093"
			(at 0 0 0)
			(layer "F.SilkS")
			(hide yes)
			(effects
				(font
					(size 1.27 1.27)
				)
			)
		)
		(property "Value" "4K7R2F-GP"
			(at 0.064008 -3.993896 0)
			(unlocked yes)
			(layer "F.Fab")
			(hide yes)
			(effects
				(font
					(size 1.016 1.016)
					(thickness 0.1524)
				)
			)
		)
		(property "Device Type" "R402H16"
			(at 0.064008 -5.517896 0)
			(unlocked yes)
			(layer "F.Fab")
			(hide yes)
			(effects
				(font
					(size 1.016 1.016)
					(thickness 0.1524)
				)
			)
		)
		(duplicate_pad_numbers_are_jumpers no)
		(fp_line
			(start -0.508 -0.9398)
			(end -0.508 0.9398)
			(stroke
				(width 0.1524)
				(type default)
			)
			(layer "F.SilkS")
		)
		(fp_line
			(start 0.508 -0.9398)
			(end -0.508 -0.9398)
			(stroke
				(width 0.1524)
				(type default)
			)
			(layer "F.SilkS")
		)
		(fp_rect
			(start -0.508 0.9398)
			(end 0.508 -0.9398)
			(stroke
				(width 0)
				(type default)
			)
			(fill no)
			(layer "F.CrtYd")
		)
		(fp_rect
			(start -0.508 0.9398)
			(end 0.508 -0.9398)
			(stroke
				(width 0)
				(type default)
			)
			(fill no)
			(layer "F.Fab")
		)
		(pad "1" smd custom
			(at 0 -0.4445)
			(size 0.1397 0.1397)
			(layers "F.Cu" "F.Mask" "F.Paste")
			(net "P3V3")
			(options
				(clearance outline)
				(anchor circle)
			)
			(primitives
				(gr_poly
					(pts
						(arc
							(start -0.1778 -0.2794)
							(mid -0.249642 -0.249642)
							(end -0.2794 -0.1778)
						)
						(arc
							(start -0.2794 0.1778)
							(mid -0.249642 0.249642)
							(end -0.1778 0.2794)
						)
						(arc
							(start 0.1778 0.2794)
							(mid 0.249642 0.249642)
							(end 0.2794 0.1778)
						)
						(arc
							(start 0.2794 -0.1778)
							(mid 0.249642 -0.249642)
							(end 0.1778 -0.2794)
						)
					)
					(width 0)
					(fill yes)
				)
			)
		)
		(pad "2" smd custom
			(at 0 0.4445)
			(size 0.1397 0.1397)
			(layers "F.Cu" "F.Mask" "F.Paste")
			(net "DUALPORTEN#1")
			(options
				(clearance outline)
				(anchor circle)
			)
			(primitives
				(gr_poly
					(pts
						(arc
							(start -0.1778 -0.2794)
							(mid -0.249642 -0.249642)
							(end -0.2794 -0.1778)
						)
						(arc
							(start -0.2794 0.1778)
							(mid -0.249642 0.249642)
							(end -0.1778 0.2794)
						)
						(arc
							(start 0.1778 0.2794)
							(mid 0.249642 0.249642)
							(end 0.2794 0.1778)
						)
						(arc
							(start 0.2794 -0.1778)
							(mid 0.249642 -0.249642)
							(end 0.1778 -0.2794)
						)
					)
					(width 0)
					(fill yes)
				)
			)
		)
	)
	(footprint ""
		(layer "F.Cu")
		(at 230.124 -429.133)
		(property "Reference" "PR9081"
			(at 0 0 0)
			(layer "F.SilkS")
			(hide yes)
			(effects
				(font
					(size 1.27 1.27)
				)
			)
		)
		(property "Value" "0R2J-2-GP"
			(at 0.064008 -3.993896 0)
			(unlocked yes)
			(layer "F.Fab")
			(hide yes)
			(effects
				(font
					(size 1.016 1.016)
					(thickness 0.1524)
				)
			)
		)
		(property "Device Type" "R402H16"
			(at 0.064008 -5.517896 0)
			(unlocked yes)
			(layer "F.Fab")
			(hide yes)
			(effects
				(font
					(size 1.016 1.016)
					(thickness 0.1524)
				)
			)
		)
		(duplicate_pad_numbers_are_jumpers no)
		(fp_line
			(start -0.508 -0.9398)
			(end -0.508 0.9398)
			(stroke
				(width 0.1524)
				(type default)
			)
			(layer "F.SilkS")
		)
		(fp_line
			(start 0.508 -0.9398)
			(end -0.508 -0.9398)
			(stroke
				(width 0.1524)
				(type default)
			)
			(layer "F.SilkS")
		)
		(fp_rect
			(start -0.508 0.9398)
			(end 0.508 -0.9398)
			(stroke
				(width 0)
				(type default)
			)
			(fill no)
			(layer "F.CrtYd")
		)
		(fp_rect
			(start -0.508 0.9398)
			(end 0.508 -0.9398)
			(stroke
				(width 0)
				(type default)
			)
			(fill no)
			(layer "F.Fab")
		)
		(pad "1" smd custom
			(at 0 -0.4445)
			(size 0.1397 0.1397)
			(layers "F.Cu" "F.Mask" "F.Paste")
			(net "P3V3_VO")
			(options
				(clearance outline)
				(anchor circle)
			)
			(primitives
				(gr_poly
					(pts
						(arc
							(start -0.1778 -0.2794)
							(mid -0.249642 -0.249642)
							(end -0.2794 -0.1778)
						)
						(arc
							(start -0.2794 0.1778)
							(mid -0.249642 0.249642)
							(end -0.1778 0.2794)
						)
						(arc
							(start 0.1778 0.2794)
							(mid 0.249642 0.249642)
							(end 0.2794 0.1778)
						)
						(arc
							(start 0.2794 -0.1778)
							(mid 0.249642 -0.249642)
							(end 0.1778 -0.2794)
						)
					)
					(width 0)
					(fill yes)
				)
			)
		)
		(pad "2" smd custom
			(at 0 0.4445)
			(size 0.1397 0.1397)
			(layers "F.Cu" "F.Mask" "F.Paste")
			(net "P3V3_CC_R")
			(options
				(clearance outline)
				(anchor circle)
			)
			(primitives
				(gr_poly
					(pts
						(arc
							(start -0.1778 -0.2794)
							(mid -0.249642 -0.249642)
							(end -0.2794 -0.1778)
						)
						(arc
							(start -0.2794 0.1778)
							(mid -0.249642 0.249642)
							(end -0.1778 0.2794)
						)
						(arc
							(start 0.1778 0.2794)
							(mid 0.249642 0.249642)
							(end 0.2794 0.1778)
						)
						(arc
							(start 0.2794 -0.1778)
							(mid 0.249642 -0.249642)
							(end 0.1778 -0.2794)
						)
					)
					(width 0)
					(fill yes)
				)
			)
		)
	)
	(footprint ""
		(layer "F.Cu")
		(at 70.000114 -483.497636)
		(property "Reference" "H2"
			(at 0 0 0)
			(layer "F.SilkS")
			(hide yes)
			(effects
				(font
					(size 1.27 1.27)
				)
			)
		)
		(property "Value" "GEN276X162R197X296-6-F-A-GP"
			(at -6.7183 4.1402 0)
			(unlocked yes)
			(layer "F.Fab")
			(hide yes)
			(effects
				(font
					(size 1.016 1.016)
					(thickness 0.1524)
				)
			)
		)
		(property "Device Type" "GEN276X162R197X296-6-F-A"
			(at -6.7183 2.6162 0)
			(unlocked yes)
			(layer "F.Fab")
			(hide yes)
			(effects
				(font
					(size 1.016 1.016)
					(thickness 0.1524)
				)
			)
		)
		(duplicate_pad_numbers_are_jumpers no)
		(fp_poly
			(pts
				(arc
					(start 2.723642 4.777232)
					(mid -0.000169 6.508462)
					(end -2.723896 4.776978)
				)
				(arc
					(start -2.723896 4.776978)
					(mid 0.000173 -5.499012)
					(end 2.723642 4.777232)
				)
			)
			(stroke
				(width 0)
				(type default)
			)
			(fill no)
			(layer "B.CrtYd")
		)
		(fp_poly
			(pts
				(arc
					(start 2.723642 4.777232)
					(mid -0.000169 6.508462)
					(end -2.723896 4.776978)
				)
				(arc
					(start -2.723896 4.776978)
					(mid 0.000173 -5.499012)
					(end 2.723642 4.777232)
				)
			)
			(stroke
				(width 0)
				(type default)
			)
			(fill no)
			(layer "F.CrtYd")
		)
		(fp_poly
			(pts
				(arc
					(start 2.723642 4.777232)
					(mid -0.000169 6.508462)
					(end -2.723896 4.776978)
				)
				(arc
					(start -2.723896 4.776978)
					(mid 0.000173 -5.499012)
					(end 2.723642 4.777232)
				)
			)
			(stroke
				(width 0)
				(type default)
			)
			(fill no)
			(layer "B.Fab")
		)
		(fp_poly
			(pts
				(arc
					(start 2.723642 4.777232)
					(mid -0.000169 6.508462)
					(end -2.723896 4.776978)
				)
				(arc
					(start -2.723896 4.776978)
					(mid 0.000173 -5.499012)
					(end 2.723642 4.777232)
				)
			)
			(stroke
				(width 0)
				(type default)
			)
			(fill no)
			(layer "F.Fab")
		)
		(pad "" np_thru_hole circle
			(at 0 0)
			(size 0.254 0.254)
			(drill 0.0254)
			(layers "*.Cu" "*.Mask")
			(clearance 3.135376)
			(thermal_gap 3.135376)
		)
		(pad "1" thru_hole circle
			(at 2.549906 0)
			(size 0.8636 0.8636)
			(drill 0.508)
			(layers "*.Cu" "*.Mask")
			(remove_unused_layers no)
			(net "GND")
			(clearance 0.8255)
			(thermal_gap 0.8255)
		)
		(pad "2" thru_hole circle
			(at 2.210054 -1.27)
			(size 0.8636 0.8636)
			(drill 0.508)
			(layers "*.Cu" "*.Mask")
			(remove_unused_layers no)
			(net "GND")
			(clearance 0.8255)
			(thermal_gap 0.8255)
		)
		(pad "3" thru_hole circle
			(at 1.27 -2.210054)
			(size 0.8636 0.8636)
			(drill 0.508)
			(layers "*.Cu" "*.Mask")
			(remove_unused_layers no)
			(net "GND")
			(clearance 0.8255)
			(thermal_gap 0.8255)
		)
		(pad "4" thru_hole circle
			(at -1.279906 -2.210054)
			(size 0.8636 0.8636)
			(drill 0.508)
			(layers "*.Cu" "*.Mask")
			(remove_unused_layers no)
			(net "GND")
			(clearance 0.8255)
			(thermal_gap 0.8255)
		)
		(pad "5" thru_hole circle
			(at -2.210054 -1.27)
			(size 0.8636 0.8636)
			(drill 0.508)
			(layers "*.Cu" "*.Mask")
			(remove_unused_layers no)
			(net "GND")
			(clearance 0.8255)
			(thermal_gap 0.8255)
		)
		(pad "6" thru_hole circle
			(at -2.549906 0)
			(size 0.8636 0.8636)
			(drill 0.508)
			(layers "*.Cu" "*.Mask")
			(remove_unused_layers no)
			(net "GND")
			(clearance 0.8255)
			(thermal_gap 0.8255)
		)
		(zone
			(layers "F.Cu" "B.Cu" "In1.Cu" "In2.Cu" "In3.Cu" "In4.Cu" "In5.Cu" "In6.Cu")
			(hatch none 0.5)
			(connect_pads
				(clearance 0)
			)
			(min_thickness 0.25)
			(keepout
				(tracks allowed)
				(vias not_allowed)
				(pads allowed)
				(copperpour not_allowed)
				(footprints allowed)
			)
			(placement
				(enabled no)
				(sheetname "")
			)
			(fill
				(thermal_gap 0.5)
				(thermal_bridge_width 0.5)
				(island_removal_mode 0)
			)
			(polygon
				(pts
					(arc
						(start 74.318114 -483.500684)
						(mid 65.682114 -483.500684)
						(end 74.318114 -483.500684)
					)
				)
			)
		)
		(zone
			(layers "F.Cu" "B.Cu" "In1.Cu" "In2.Cu" "In3.Cu" "In4.Cu" "In5.Cu" "In6.Cu")
			(hatch none 0.5)
			(connect_pads
				(clearance 0)
			)
			(min_thickness 0.25)
			(keepout
				(tracks not_allowed)
				(vias allowed)
				(pads allowed)
				(copperpour not_allowed)
				(footprints allowed)
			)
			(placement
				(enabled no)
				(sheetname "")
			)
			(fill
				(thermal_gap 0.5)
				(thermal_bridge_width 0.5)
				(island_removal_mode 0)
			)
			(polygon
				(pts
					(arc
						(start 72.339454 -481.888292)
						(mid 70.000194 -476.989189)
						(end 67.66052 -481.888292)
					)
					(arc
						(start 67.66052 -481.888292)
						(mid 67.906487 -482.328658)
						(end 67.991736 -482.825806)
					)
					(arc
						(start 67.991736 -483.497636)
						(mid 70.000114 -485.506014)
						(end 72.008238 -483.497636)
					)
					(arc
						(start 72.008238 -482.825806)
						(mid 72.093473 -482.328652)
						(end 72.339454 -481.888292)
					)
				)
			)
		)
	)
	(footprint ""
		(layer "F.Cu")
		(at 27.6098 -208.3562)
		(property "Reference" "PC1252"
			(at 0 0 0)
			(layer "F.SilkS")
			(hide yes)
			(effects
				(font
					(size 1.27 1.27)
				)
			)
		)
		(property "Value" "SCD1U50V3KX-GP"
			(at 0 -2.8194 0)
			(unlocked yes)
			(layer "F.Fab")
			(hide yes)
			(effects
				(font
					(size 1.016 1.016)
					(thickness 0.1524)
				)
			)
		)
		(property "Device Type" "C603H36"
			(at 0 -4.3434 0)
			(unlocked yes)
			(layer "F.Fab")
			(hide yes)
			(effects
				(font
					(size 1.016 1.016)
					(thickness 0.1524)
				)
			)
		)
		(duplicate_pad_numbers_are_jumpers no)
		(fp_line
			(start 0.508 0)
			(end -0.508 0)
			(stroke
				(width 0.2032)
				(type default)
			)
			(layer "F.SilkS")
		)
		(fp_rect
			(start -0.5842 1.3335)
			(end 0.5842 -1.3335)
			(stroke
				(width 0)
				(type default)
			)
			(fill no)
			(layer "F.CrtYd")
		)
		(fp_rect
			(start -0.5842 1.3335)
			(end 0.5842 -1.3335)
			(stroke
				(width 0)
				(type default)
			)
			(fill no)
			(layer "F.Fab")
		)
		(pad "1" smd custom
			(at 0 -0.762)
			(size 0.2159 0.2159)
			(layers "F.Cu" "F.Mask" "F.Paste")
			(net "P12V_SSD12")
			(options
				(clearance outline)
				(anchor circle)
			)
			(primitives
				(gr_poly
					(pts
						(arc
							(start -0.3302 -0.4318)
							(mid -0.402042 -0.402042)
							(end -0.4318 -0.3302)
						)
						(arc
							(start -0.4318 0.3302)
							(mid -0.402042 0.402042)
							(end -0.3302 0.4318)
						)
						(arc
							(start 0.3302 0.4318)
							(mid 0.402042 0.402042)
							(end 0.4318 0.3302)
						)
						(arc
							(start 0.4318 -0.3302)
							(mid 0.402042 -0.402042)
							(end 0.3302 -0.4318)
						)
					)
					(width 0)
					(fill yes)
				)
			)
		)
		(pad "2" smd custom
			(at 0 0.762)
			(size 0.2159 0.2159)
			(layers "F.Cu" "F.Mask" "F.Paste")
			(net "GND")
			(options
				(clearance outline)
				(anchor circle)
			)
			(primitives
				(gr_poly
					(pts
						(arc
							(start -0.3302 -0.4318)
							(mid -0.402042 -0.402042)
							(end -0.4318 -0.3302)
						)
						(arc
							(start -0.4318 0.3302)
							(mid -0.402042 0.402042)
							(end -0.3302 0.4318)
						)
						(arc
							(start 0.3302 0.4318)
							(mid 0.402042 0.402042)
							(end 0.4318 0.3302)
						)
						(arc
							(start 0.4318 -0.3302)
							(mid 0.402042 -0.402042)
							(end 0.3302 -0.4318)
						)
					)
					(width 0)
					(fill yes)
				)
			)
		)
	)
	(footprint ""
		(layer "F.Cu")
		(at 22.247606 -59.10961 180)
		(property "Reference" "R9874"
			(at 0 0 180)
			(layer "F.SilkS")
			(hide yes)
			(effects
				(font
					(size 1.27 1.27)
				)
			)
		)
		(property "Value" "0R2J-2-GP"
			(at 0.064008 -3.993896 180)
			(unlocked yes)
			(layer "F.Fab")
			(hide yes)
			(effects
				(font
					(size 1.016 1.016)
					(thickness 0.1524)
				)
			)
		)
		(property "Device Type" "R402H16"
			(at 0.064008 -5.517896 180)
			(unlocked yes)
			(layer "F.Fab")
			(hide yes)
			(effects
				(font
					(size 1.016 1.016)
					(thickness 0.1524)
				)
			)
		)
		(duplicate_pad_numbers_are_jumpers no)
		(fp_line
			(start 0.508 -0.9398)
			(end -0.508 -0.9398)
			(stroke
				(width 0.1524)
				(type default)
			)
			(layer "F.SilkS")
		)
		(fp_line
			(start -0.508 -0.9398)
			(end -0.508 0.9398)
			(stroke
				(width 0.1524)
				(type default)
			)
			(layer "F.SilkS")
		)
		(fp_rect
			(start -0.508 0.9398)
			(end 0.508 -0.9398)
			(stroke
				(width 0)
				(type default)
			)
			(fill no)
			(layer "F.CrtYd")
		)
		(fp_rect
			(start -0.508 0.9398)
			(end 0.508 -0.9398)
			(stroke
				(width 0)
				(type default)
			)
			(fill no)
			(layer "F.Fab")
		)
		(pad "1" smd custom
			(at 0 -0.4445 180)
			(size 0.1397 0.1397)
			(layers "F.Cu" "F.Mask" "F.Paste")
			(net "ATTN_LED_DR14_R")
			(options
				(clearance outline)
				(anchor circle)
			)
			(primitives
				(gr_poly
					(pts
						(arc
							(start -0.1778 -0.2794)
							(mid -0.249642 -0.249642)
							(end -0.2794 -0.1778)
						)
						(arc
							(start -0.2794 0.1778)
							(mid -0.249642 0.249642)
							(end -0.1778 0.2794)
						)
						(arc
							(start 0.1778 0.2794)
							(mid 0.249642 0.249642)
							(end 0.2794 0.1778)
						)
						(arc
							(start 0.2794 -0.1778)
							(mid 0.249642 -0.249642)
							(end 0.1778 -0.2794)
						)
					)
					(width 0)
					(fill yes)
				)
			)
		)
		(pad "2" smd custom
			(at 0 0.4445 180)
			(size 0.1397 0.1397)
			(layers "F.Cu" "F.Mask" "F.Paste")
			(net "ATTN_LED_DR14_N")
			(options
				(clearance outline)
				(anchor circle)
			)
			(primitives
				(gr_poly
					(pts
						(arc
							(start -0.1778 -0.2794)
							(mid -0.249642 -0.249642)
							(end -0.2794 -0.1778)
						)
						(arc
							(start -0.2794 0.1778)
							(mid -0.249642 0.249642)
							(end -0.1778 0.2794)
						)
						(arc
							(start 0.1778 0.2794)
							(mid 0.249642 0.249642)
							(end 0.2794 0.1778)
						)
						(arc
							(start 0.2794 -0.1778)
							(mid 0.249642 -0.249642)
							(end 0.1778 -0.2794)
						)
					)
					(width 0)
					(fill yes)
				)
			)
		)
	)
	(footprint ""
		(layer "F.Cu")
		(at 22.14245 -301.94885 90)
		(property "Reference" "R9827"
			(at 0 0 90)
			(layer "F.SilkS")
			(hide yes)
			(effects
				(font
					(size 1.27 1.27)
				)
			)
		)
		(property "Value" "1KR2J-1-GP"
			(at 0.064008 -3.993896 90)
			(unlocked yes)
			(layer "F.Fab")
			(hide yes)
			(effects
				(font
					(size 1.016 1.016)
					(thickness 0.1524)
				)
			)
		)
		(property "Device Type" "R402H16"
			(at 0.064008 -5.517896 90)
			(unlocked yes)
			(layer "F.Fab")
			(hide yes)
			(effects
				(font
					(size 1.016 1.016)
					(thickness 0.1524)
				)
			)
		)
		(duplicate_pad_numbers_are_jumpers no)
		(fp_line
			(start 0.508 -0.9398)
			(end -0.508 -0.9398)
			(stroke
				(width 0.1524)
				(type default)
			)
			(layer "F.SilkS")
		)
		(fp_line
			(start -0.508 -0.9398)
			(end -0.508 0.9398)
			(stroke
				(width 0.1524)
				(type default)
			)
			(layer "F.SilkS")
		)
		(fp_rect
			(start -0.508 0.9398)
			(end 0.508 -0.9398)
			(stroke
				(width 0)
				(type default)
			)
			(fill no)
			(layer "F.CrtYd")
		)
		(fp_rect
			(start -0.508 0.9398)
			(end 0.508 -0.9398)
			(stroke
				(width 0)
				(type default)
			)
			(fill no)
			(layer "F.Fab")
		)
		(pad "1" smd custom
			(at 0 -0.4445 90)
			(size 0.1397 0.1397)
			(layers "F.Cu" "F.Mask" "F.Paste")
			(net "SSD7_PWREN")
			(options
				(clearance outline)
				(anchor circle)
			)
			(primitives
				(gr_poly
					(pts
						(arc
							(start -0.1778 -0.2794)
							(mid -0.249642 -0.249642)
							(end -0.2794 -0.1778)
						)
						(arc
							(start -0.2794 0.1778)
							(mid -0.249642 0.249642)
							(end -0.1778 0.2794)
						)
						(arc
							(start 0.1778 0.2794)
							(mid 0.249642 0.249642)
							(end 0.2794 0.1778)
						)
						(arc
							(start 0.2794 -0.1778)
							(mid 0.249642 -0.249642)
							(end 0.1778 -0.2794)
						)
					)
					(width 0)
					(fill yes)
				)
			)
		)
		(pad "2" smd custom
			(at 0 0.4445 90)
			(size 0.1397 0.1397)
			(layers "F.Cu" "F.Mask" "F.Paste")
			(net "SSD7_PWREN_R")
			(options
				(clearance outline)
				(anchor circle)
			)
			(primitives
				(gr_poly
					(pts
						(arc
							(start -0.1778 -0.2794)
							(mid -0.249642 -0.249642)
							(end -0.2794 -0.1778)
						)
						(arc
							(start -0.2794 0.1778)
							(mid -0.249642 0.249642)
							(end -0.1778 0.2794)
						)
						(arc
							(start 0.1778 0.2794)
							(mid 0.249642 0.249642)
							(end 0.2794 0.1778)
						)
						(arc
							(start 0.2794 -0.1778)
							(mid 0.249642 -0.249642)
							(end 0.1778 -0.2794)
						)
					)
					(width 0)
					(fill yes)
				)
			)
		)
	)
	(footprint ""
		(layer "F.Cu")
		(at 217.043 -391.795 -90)
		(property "Reference" "R386"
			(at 0 0 270)
			(layer "F.SilkS")
			(hide yes)
			(effects
				(font
					(size 1.27 1.27)
				)
			)
		)
		(property "Value" "0R2J-2-GP"
			(at 0.064008 -3.993896 270)
			(unlocked yes)
			(layer "F.Fab")
			(hide yes)
			(effects
				(font
					(size 1.016 1.016)
					(thickness 0.1524)
				)
			)
		)
		(property "Device Type" "R402H16"
			(at 0.064008 -5.517896 270)
			(unlocked yes)
			(layer "F.Fab")
			(hide yes)
			(effects
				(font
					(size 1.016 1.016)
					(thickness 0.1524)
				)
			)
		)
		(duplicate_pad_numbers_are_jumpers no)
		(fp_line
			(start -0.508 -0.9398)
			(end -0.508 0.9398)
			(stroke
				(width 0.1524)
				(type default)
			)
			(layer "F.SilkS")
		)
		(fp_line
			(start 0.508 -0.9398)
			(end -0.508 -0.9398)
			(stroke
				(width 0.1524)
				(type default)
			)
			(layer "F.SilkS")
		)
		(fp_rect
			(start -0.508 0.9398)
			(end 0.508 -0.9398)
			(stroke
				(width 0)
				(type default)
			)
			(fill no)
			(layer "F.CrtYd")
		)
		(fp_rect
			(start -0.508 0.9398)
			(end 0.508 -0.9398)
			(stroke
				(width 0)
				(type default)
			)
			(fill no)
			(layer "F.Fab")
		)
		(pad "1" smd custom
			(at 0 -0.4445 270)
			(size 0.1397 0.1397)
			(layers "F.Cu" "F.Mask" "F.Paste")
			(net "SDA_DR1_R")
			(options
				(clearance outline)
				(anchor circle)
			)
			(primitives
				(gr_poly
					(pts
						(arc
							(start -0.1778 -0.2794)
							(mid -0.249642 -0.249642)
							(end -0.2794 -0.1778)
						)
						(arc
							(start -0.2794 0.1778)
							(mid -0.249642 0.249642)
							(end -0.1778 0.2794)
						)
						(arc
							(start 0.1778 0.2794)
							(mid 0.249642 0.249642)
							(end 0.2794 0.1778)
						)
						(arc
							(start 0.2794 -0.1778)
							(mid 0.249642 -0.249642)
							(end 0.1778 -0.2794)
						)
					)
					(width 0)
					(fill yes)
				)
			)
		)
		(pad "2" smd custom
			(at 0 0.4445 270)
			(size 0.1397 0.1397)
			(layers "F.Cu" "F.Mask" "F.Paste")
			(net "SDA_DR1")
			(options
				(clearance outline)
				(anchor circle)
			)
			(primitives
				(gr_poly
					(pts
						(arc
							(start -0.1778 -0.2794)
							(mid -0.249642 -0.249642)
							(end -0.2794 -0.1778)
						)
						(arc
							(start -0.2794 0.1778)
							(mid -0.249642 0.249642)
							(end -0.1778 0.2794)
						)
						(arc
							(start 0.1778 0.2794)
							(mid 0.249642 0.249642)
							(end 0.2794 0.1778)
						)
						(arc
							(start 0.2794 -0.1778)
							(mid 0.249642 -0.249642)
							(end 0.1778 -0.2794)
						)
					)
					(width 0)
					(fill yes)
				)
			)
		)
	)
	(footprint ""
		(layer "F.Cu")
		(at 29.845 -423.164 90)
		(property "Reference" "R409"
			(at 0 0 90)
			(layer "F.SilkS")
			(hide yes)
			(effects
				(font
					(size 1.27 1.27)
				)
			)
		)
		(property "Value" "0R2J-2-GP"
			(at 0.064008 -3.993896 90)
			(unlocked yes)
			(layer "F.Fab")
			(hide yes)
			(effects
				(font
					(size 1.016 1.016)
					(thickness 0.1524)
				)
			)
		)
		(property "Device Type" "R402H16"
			(at 0.064008 -5.517896 90)
			(unlocked yes)
			(layer "F.Fab")
			(hide yes)
			(effects
				(font
					(size 1.016 1.016)
					(thickness 0.1524)
				)
			)
		)
		(duplicate_pad_numbers_are_jumpers no)
		(fp_line
			(start 0.508 -0.9398)
			(end -0.508 -0.9398)
			(stroke
				(width 0.1524)
				(type default)
			)
			(layer "F.SilkS")
		)
		(fp_line
			(start -0.508 -0.9398)
			(end -0.508 0.9398)
			(stroke
				(width 0.1524)
				(type default)
			)
			(layer "F.SilkS")
		)
		(fp_rect
			(start -0.508 0.9398)
			(end 0.508 -0.9398)
			(stroke
				(width 0)
				(type default)
			)
			(fill no)
			(layer "F.CrtYd")
		)
		(fp_rect
			(start -0.508 0.9398)
			(end 0.508 -0.9398)
			(stroke
				(width 0)
				(type default)
			)
			(fill no)
			(layer "F.Fab")
		)
		(pad "1" smd custom
			(at 0 -0.4445 90)
			(size 0.1397 0.1397)
			(layers "F.Cu" "F.Mask" "F.Paste")
			(net "SDA_DR10_R")
			(options
				(clearance outline)
				(anchor circle)
			)
			(primitives
				(gr_poly
					(pts
						(arc
							(start -0.1778 -0.2794)
							(mid -0.249642 -0.249642)
							(end -0.2794 -0.1778)
						)
						(arc
							(start -0.2794 0.1778)
							(mid -0.249642 0.249642)
							(end -0.1778 0.2794)
						)
						(arc
							(start 0.1778 0.2794)
							(mid 0.249642 0.249642)
							(end 0.2794 0.1778)
						)
						(arc
							(start 0.2794 -0.1778)
							(mid 0.249642 -0.249642)
							(end 0.1778 -0.2794)
						)
					)
					(width 0)
					(fill yes)
				)
			)
		)
		(pad "2" smd custom
			(at 0 0.4445 90)
			(size 0.1397 0.1397)
			(layers "F.Cu" "F.Mask" "F.Paste")
			(net "SDA_DR10")
			(options
				(clearance outline)
				(anchor circle)
			)
			(primitives
				(gr_poly
					(pts
						(arc
							(start -0.1778 -0.2794)
							(mid -0.249642 -0.249642)
							(end -0.2794 -0.1778)
						)
						(arc
							(start -0.2794 0.1778)
							(mid -0.249642 0.249642)
							(end -0.1778 0.2794)
						)
						(arc
							(start 0.1778 0.2794)
							(mid 0.249642 0.249642)
							(end 0.2794 0.1778)
						)
						(arc
							(start 0.2794 -0.1778)
							(mid 0.249642 -0.249642)
							(end 0.1778 -0.2794)
						)
					)
					(width 0)
					(fill yes)
				)
			)
		)
	)
	(footprint ""
		(layer "F.Cu")
		(at 226.114102 -350.061784 180)
		(property "Reference" "R9929"
			(at 0 0 180)
			(layer "F.SilkS")
			(hide yes)
			(effects
				(font
					(size 1.27 1.27)
				)
			)
		)
		(property "Value" "4K7R2J-2-GP"
			(at 0.064008 -3.993896 180)
			(unlocked yes)
			(layer "F.Fab")
			(hide yes)
			(effects
				(font
					(size 1.016 1.016)
					(thickness 0.1524)
				)
			)
		)
		(property "Device Type" "R402H16"
			(at 0.064008 -5.517896 180)
			(unlocked yes)
			(layer "F.Fab")
			(hide yes)
			(effects
				(font
					(size 1.016 1.016)
					(thickness 0.1524)
				)
			)
		)
		(duplicate_pad_numbers_are_jumpers no)
		(fp_line
			(start 0.508 -0.9398)
			(end -0.508 -0.9398)
			(stroke
				(width 0.1524)
				(type default)
			)
			(layer "F.SilkS")
		)
		(fp_line
			(start -0.508 -0.9398)
			(end -0.508 0.9398)
			(stroke
				(width 0.1524)
				(type default)
			)
			(layer "F.SilkS")
		)
		(fp_rect
			(start -0.508 0.9398)
			(end 0.508 -0.9398)
			(stroke
				(width 0)
				(type default)
			)
			(fill no)
			(layer "F.CrtYd")
		)
		(fp_rect
			(start -0.508 0.9398)
			(end 0.508 -0.9398)
			(stroke
				(width 0)
				(type default)
			)
			(fill no)
			(layer "F.Fab")
		)
		(pad "1" smd custom
			(at 0 -0.4445 180)
			(size 0.1397 0.1397)
			(layers "F.Cu" "F.Mask" "F.Paste")
			(net "P3V3")
			(options
				(clearance outline)
				(anchor circle)
			)
			(primitives
				(gr_poly
					(pts
						(arc
							(start -0.1778 -0.2794)
							(mid -0.249642 -0.249642)
							(end -0.2794 -0.1778)
						)
						(arc
							(start -0.2794 0.1778)
							(mid -0.249642 0.249642)
							(end -0.1778 0.2794)
						)
						(arc
							(start 0.1778 0.2794)
							(mid 0.249642 0.249642)
							(end 0.2794 0.1778)
						)
						(arc
							(start 0.2794 -0.1778)
							(mid 0.249642 -0.249642)
							(end 0.1778 -0.2794)
						)
					)
					(width 0)
					(fill yes)
				)
			)
		)
		(pad "2" smd custom
			(at 0 0.4445 180)
			(size 0.1397 0.1397)
			(layers "F.Cu" "F.Mask" "F.Paste")
			(net "ATTN_LED_DR1_MOS_N")
			(options
				(clearance outline)
				(anchor circle)
			)
			(primitives
				(gr_poly
					(pts
						(arc
							(start -0.1778 -0.2794)
							(mid -0.249642 -0.249642)
							(end -0.2794 -0.1778)
						)
						(arc
							(start -0.2794 0.1778)
							(mid -0.249642 0.249642)
							(end -0.1778 0.2794)
						)
						(arc
							(start 0.1778 0.2794)
							(mid 0.249642 0.249642)
							(end 0.2794 0.1778)
						)
						(arc
							(start 0.2794 -0.1778)
							(mid 0.249642 -0.249642)
							(end 0.1778 -0.2794)
						)
					)
					(width 0)
					(fill yes)
				)
			)
		)
	)
	(footprint ""
		(layer "F.Cu")
		(at 97.155 -115.062)
		(property "Reference" "R9605"
			(at 0 0 0)
			(layer "F.SilkS")
			(hide yes)
			(effects
				(font
					(size 1.27 1.27)
				)
			)
		)
		(property "Value" "10R2F-L-GP"
			(at 0.064008 -3.993896 0)
			(unlocked yes)
			(layer "F.Fab")
			(hide yes)
			(effects
				(font
					(size 1.016 1.016)
					(thickness 0.1524)
				)
			)
		)
		(property "Device Type" "R402H14"
			(at 0.064008 -5.517896 0)
			(unlocked yes)
			(layer "F.Fab")
			(hide yes)
			(effects
				(font
					(size 1.016 1.016)
					(thickness 0.1524)
				)
			)
		)
		(duplicate_pad_numbers_are_jumpers no)
		(fp_line
			(start -0.508 -0.9398)
			(end -0.508 0.9398)
			(stroke
				(width 0.1524)
				(type default)
			)
			(layer "F.SilkS")
		)
		(fp_line
			(start 0.508 -0.9398)
			(end -0.508 -0.9398)
			(stroke
				(width 0.1524)
				(type default)
			)
			(layer "F.SilkS")
		)
		(fp_rect
			(start -0.508 0.9398)
			(end 0.508 -0.9398)
			(stroke
				(width 0)
				(type default)
			)
			(fill no)
			(layer "F.CrtYd")
		)
		(fp_rect
			(start -0.508 0.9398)
			(end 0.508 -0.9398)
			(stroke
				(width 0)
				(type default)
			)
			(fill no)
			(layer "F.Fab")
		)
		(pad "1" smd custom
			(at 0 -0.4445)
			(size 0.1397 0.1397)
			(layers "F.Cu" "F.Mask" "F.Paste")
			(net "SSD8_CLK0_OE_N")
			(options
				(clearance outline)
				(anchor circle)
			)
			(primitives
				(gr_poly
					(pts
						(arc
							(start -0.1778 -0.2794)
							(mid -0.249642 -0.249642)
							(end -0.2794 -0.1778)
						)
						(arc
							(start -0.2794 0.1778)
							(mid -0.249642 0.249642)
							(end -0.1778 0.2794)
						)
						(arc
							(start 0.1778 0.2794)
							(mid 0.249642 0.249642)
							(end 0.2794 0.1778)
						)
						(arc
							(start 0.2794 -0.1778)
							(mid 0.249642 -0.249642)
							(end 0.1778 -0.2794)
						)
					)
					(width 0)
					(fill yes)
				)
			)
		)
		(pad "2" smd custom
			(at 0 0.4445)
			(size 0.1397 0.1397)
			(layers "F.Cu" "F.Mask" "F.Paste")
			(net "SSD8_CLK0_OE_R_N")
			(options
				(clearance outline)
				(anchor circle)
			)
			(primitives
				(gr_poly
					(pts
						(arc
							(start -0.1778 -0.2794)
							(mid -0.249642 -0.249642)
							(end -0.2794 -0.1778)
						)
						(arc
							(start -0.2794 0.1778)
							(mid -0.249642 0.249642)
							(end -0.1778 0.2794)
						)
						(arc
							(start 0.1778 0.2794)
							(mid 0.249642 0.249642)
							(end 0.2794 0.1778)
						)
						(arc
							(start 0.2794 -0.1778)
							(mid 0.249642 -0.249642)
							(end 0.1778 -0.2794)
						)
					)
					(width 0)
					(fill yes)
				)
			)
		)
	)
	(footprint ""
		(layer "F.Cu")
		(at 39.02075 -102.64775)
		(property "Reference" "R9754"
			(at 0 0 0)
			(layer "F.SilkS")
			(hide yes)
			(effects
				(font
					(size 1.27 1.27)
				)
			)
		)
		(property "Value" "4K7R2J-2-GP"
			(at 0.064008 -3.993896 0)
			(unlocked yes)
			(layer "F.Fab")
			(hide yes)
			(effects
				(font
					(size 1.016 1.016)
					(thickness 0.1524)
				)
			)
		)
		(property "Device Type" "R402H16"
			(at 0.064008 -5.517896 0)
			(unlocked yes)
			(layer "F.Fab")
			(hide yes)
			(effects
				(font
					(size 1.016 1.016)
					(thickness 0.1524)
				)
			)
		)
		(duplicate_pad_numbers_are_jumpers no)
		(fp_line
			(start -0.508 -0.9398)
			(end -0.508 0.9398)
			(stroke
				(width 0.1524)
				(type default)
			)
			(layer "F.SilkS")
		)
		(fp_line
			(start 0.508 -0.9398)
			(end -0.508 -0.9398)
			(stroke
				(width 0.1524)
				(type default)
			)
			(layer "F.SilkS")
		)
		(fp_rect
			(start -0.508 0.9398)
			(end 0.508 -0.9398)
			(stroke
				(width 0)
				(type default)
			)
			(fill no)
			(layer "F.CrtYd")
		)
		(fp_rect
			(start -0.508 0.9398)
			(end 0.508 -0.9398)
			(stroke
				(width 0)
				(type default)
			)
			(fill no)
			(layer "F.Fab")
		)
		(pad "1" smd custom
			(at 0 -0.4445)
			(size 0.1397 0.1397)
			(layers "F.Cu" "F.Mask" "F.Paste")
			(net "P3V3")
			(options
				(clearance outline)
				(anchor circle)
			)
			(primitives
				(gr_poly
					(pts
						(arc
							(start -0.1778 -0.2794)
							(mid -0.249642 -0.249642)
							(end -0.2794 -0.1778)
						)
						(arc
							(start -0.2794 0.1778)
							(mid -0.249642 0.249642)
							(end -0.1778 0.2794)
						)
						(arc
							(start 0.1778 0.2794)
							(mid 0.249642 0.249642)
							(end 0.2794 0.1778)
						)
						(arc
							(start 0.2794 -0.1778)
							(mid 0.249642 -0.249642)
							(end 0.1778 -0.2794)
						)
					)
					(width 0)
					(fill yes)
				)
			)
		)
		(pad "2" smd custom
			(at 0 0.4445)
			(size 0.1397 0.1397)
			(layers "F.Cu" "F.Mask" "F.Paste")
			(net "SSD13_PWREN")
			(options
				(clearance outline)
				(anchor circle)
			)
			(primitives
				(gr_poly
					(pts
						(arc
							(start -0.1778 -0.2794)
							(mid -0.249642 -0.249642)
							(end -0.2794 -0.1778)
						)
						(arc
							(start -0.2794 0.1778)
							(mid -0.249642 0.249642)
							(end -0.1778 0.2794)
						)
						(arc
							(start 0.1778 0.2794)
							(mid 0.249642 0.249642)
							(end 0.2794 0.1778)
						)
						(arc
							(start 0.2794 -0.1778)
							(mid 0.249642 -0.249642)
							(end 0.1778 -0.2794)
						)
					)
					(width 0)
					(fill yes)
				)
			)
		)
	)
	(footprint ""
		(layer "F.Cu")
		(at 102.616 -204.47 90)
		(property "Reference" "R9082"
			(at 0 0 90)
			(layer "F.SilkS")
			(hide yes)
			(effects
				(font
					(size 1.27 1.27)
				)
			)
		)
		(property "Value" "27R2F-GP"
			(at 0.064008 -3.993896 90)
			(unlocked yes)
			(layer "F.Fab")
			(hide yes)
			(effects
				(font
					(size 1.016 1.016)
					(thickness 0.1524)
				)
			)
		)
		(property "Device Type" "R402H16"
			(at 0.064008 -5.517896 90)
			(unlocked yes)
			(layer "F.Fab")
			(hide yes)
			(effects
				(font
					(size 1.016 1.016)
					(thickness 0.1524)
				)
			)
		)
		(duplicate_pad_numbers_are_jumpers no)
		(fp_line
			(start 0.508 -0.9398)
			(end -0.508 -0.9398)
			(stroke
				(width 0.1524)
				(type default)
			)
			(layer "F.SilkS")
		)
		(fp_line
			(start -0.508 -0.9398)
			(end -0.508 0.9398)
			(stroke
				(width 0.1524)
				(type default)
			)
			(layer "F.SilkS")
		)
		(fp_rect
			(start -0.508 0.9398)
			(end 0.508 -0.9398)
			(stroke
				(width 0)
				(type default)
			)
			(fill no)
			(layer "F.CrtYd")
		)
		(fp_rect
			(start -0.508 0.9398)
			(end 0.508 -0.9398)
			(stroke
				(width 0)
				(type default)
			)
			(fill no)
			(layer "F.Fab")
		)
		(pad "1" smd custom
			(at 0 -0.4445 90)
			(size 0.1397 0.1397)
			(layers "F.Cu" "F.Mask" "F.Paste")
			(net "PE_CLK_100M_DR3_2_R_P")
			(options
				(clearance outline)
				(anchor circle)
			)
			(primitives
				(gr_poly
					(pts
						(arc
							(start -0.1778 -0.2794)
							(mid -0.249642 -0.249642)
							(end -0.2794 -0.1778)
						)
						(arc
							(start -0.2794 0.1778)
							(mid -0.249642 0.249642)
							(end -0.1778 0.2794)
						)
						(arc
							(start 0.1778 0.2794)
							(mid 0.249642 0.249642)
							(end 0.2794 0.1778)
						)
						(arc
							(start 0.2794 -0.1778)
							(mid 0.249642 -0.249642)
							(end 0.1778 -0.2794)
						)
					)
					(width 0)
					(fill yes)
				)
			)
		)
		(pad "2" smd custom
			(at 0 0.4445 90)
			(size 0.1397 0.1397)
			(layers "F.Cu" "F.Mask" "F.Paste")
			(net "PE_CLK100M_DR3_2_P")
			(options
				(clearance outline)
				(anchor circle)
			)
			(primitives
				(gr_poly
					(pts
						(arc
							(start -0.1778 -0.2794)
							(mid -0.249642 -0.249642)
							(end -0.2794 -0.1778)
						)
						(arc
							(start -0.2794 0.1778)
							(mid -0.249642 0.249642)
							(end -0.1778 0.2794)
						)
						(arc
							(start 0.1778 0.2794)
							(mid 0.249642 0.249642)
							(end 0.2794 0.1778)
						)
						(arc
							(start 0.2794 -0.1778)
							(mid 0.249642 -0.249642)
							(end 0.1778 -0.2794)
						)
					)
					(width 0)
					(fill yes)
				)
			)
		)
	)
	(footprint ""
		(layer "F.Cu")
		(at 100.33 -110.236 180)
		(property "Reference" "R9130"
			(at 0 0 180)
			(layer "F.SilkS")
			(hide yes)
			(effects
				(font
					(size 1.27 1.27)
				)
			)
		)
		(property "Value" "27R2F-GP"
			(at 0.064008 -3.993896 180)
			(unlocked yes)
			(layer "F.Fab")
			(hide yes)
			(effects
				(font
					(size 1.016 1.016)
					(thickness 0.1524)
				)
			)
		)
		(property "Device Type" "R402H16"
			(at 0.064008 -5.517896 180)
			(unlocked yes)
			(layer "F.Fab")
			(hide yes)
			(effects
				(font
					(size 1.016 1.016)
					(thickness 0.1524)
				)
			)
		)
		(duplicate_pad_numbers_are_jumpers no)
		(fp_line
			(start 0.508 -0.9398)
			(end -0.508 -0.9398)
			(stroke
				(width 0.1524)
				(type default)
			)
			(layer "F.SilkS")
		)
		(fp_line
			(start -0.508 -0.9398)
			(end -0.508 0.9398)
			(stroke
				(width 0.1524)
				(type default)
			)
			(layer "F.SilkS")
		)
		(fp_rect
			(start -0.508 0.9398)
			(end 0.508 -0.9398)
			(stroke
				(width 0)
				(type default)
			)
			(fill no)
			(layer "F.CrtYd")
		)
		(fp_rect
			(start -0.508 0.9398)
			(end 0.508 -0.9398)
			(stroke
				(width 0)
				(type default)
			)
			(fill no)
			(layer "F.Fab")
		)
		(pad "1" smd custom
			(at 0 -0.4445 180)
			(size 0.1397 0.1397)
			(layers "F.Cu" "F.Mask" "F.Paste")
			(net "PE_CLK_100M_DR8_2_R_P")
			(options
				(clearance outline)
				(anchor circle)
			)
			(primitives
				(gr_poly
					(pts
						(arc
							(start -0.1778 -0.2794)
							(mid -0.249642 -0.249642)
							(end -0.2794 -0.1778)
						)
						(arc
							(start -0.2794 0.1778)
							(mid -0.249642 0.249642)
							(end -0.1778 0.2794)
						)
						(arc
							(start 0.1778 0.2794)
							(mid 0.249642 0.249642)
							(end 0.2794 0.1778)
						)
						(arc
							(start 0.2794 -0.1778)
							(mid 0.249642 -0.249642)
							(end 0.1778 -0.2794)
						)
					)
					(width 0)
					(fill yes)
				)
			)
		)
		(pad "2" smd custom
			(at 0 0.4445 180)
			(size 0.1397 0.1397)
			(layers "F.Cu" "F.Mask" "F.Paste")
			(net "PE_CLK100M_DR8_2_P")
			(options
				(clearance outline)
				(anchor circle)
			)
			(primitives
				(gr_poly
					(pts
						(arc
							(start -0.1778 -0.2794)
							(mid -0.249642 -0.249642)
							(end -0.2794 -0.1778)
						)
						(arc
							(start -0.2794 0.1778)
							(mid -0.249642 0.249642)
							(end -0.1778 0.2794)
						)
						(arc
							(start 0.1778 0.2794)
							(mid 0.249642 0.249642)
							(end 0.2794 0.1778)
						)
						(arc
							(start 0.2794 -0.1778)
							(mid 0.249642 -0.249642)
							(end 0.1778 -0.2794)
						)
					)
					(width 0)
					(fill yes)
				)
			)
		)
	)
	(footprint ""
		(layer "F.Cu")
		(at 49.149 -143.383 -90)
		(property "Reference" "R9900"
			(at 0 0 270)
			(layer "F.SilkS")
			(hide yes)
			(effects
				(font
					(size 1.27 1.27)
				)
			)
		)
		(property "Value" "1K82R2F-1-GP"
			(at 0.064008 -3.993896 270)
			(unlocked yes)
			(layer "F.Fab")
			(hide yes)
			(effects
				(font
					(size 1.016 1.016)
					(thickness 0.1524)
				)
			)
		)
		(property "Device Type" "R402H16"
			(at 0.064008 -5.517896 270)
			(unlocked yes)
			(layer "F.Fab")
			(hide yes)
			(effects
				(font
					(size 1.016 1.016)
					(thickness 0.1524)
				)
			)
		)
		(duplicate_pad_numbers_are_jumpers no)
		(fp_line
			(start -0.508 -0.9398)
			(end -0.508 0.9398)
			(stroke
				(width 0.1)
				(type default)
			)
			(layer "F.SilkS")
		)
		(fp_line
			(start 0.508 -0.9398)
			(end -0.508 -0.9398)
			(stroke
				(width 0.1)
				(type default)
			)
			(layer "F.SilkS")
		)
		(fp_rect
			(start -0.508 0.9398)
			(end 0.508 -0.9398)
			(stroke
				(width 0)
				(type default)
			)
			(fill no)
			(layer "F.CrtYd")
		)
		(fp_rect
			(start -0.508 0.9398)
			(end 0.508 -0.9398)
			(stroke
				(width 0)
				(type default)
			)
			(fill no)
			(layer "F.Fab")
		)
		(pad "1" smd custom
			(at 0 -0.4445 270)
			(size 0.1397 0.1397)
			(layers "F.Cu" "F.Mask" "F.Paste")
			(net "P12V")
			(options
				(clearance outline)
				(anchor circle)
			)
			(primitives
				(gr_poly
					(pts
						(arc
							(start -0.1778 -0.2794)
							(mid -0.249642 -0.249642)
							(end -0.2794 -0.1778)
						)
						(arc
							(start -0.2794 0.1778)
							(mid -0.249642 0.249642)
							(end -0.1778 0.2794)
						)
						(arc
							(start 0.1778 0.2794)
							(mid 0.249642 0.249642)
							(end 0.2794 0.1778)
						)
						(arc
							(start 0.2794 -0.1778)
							(mid 0.249642 -0.249642)
							(end 0.1778 -0.2794)
						)
					)
					(width 0)
					(fill yes)
				)
			)
		)
		(pad "2" smd custom
			(at 0 0.4445 270)
			(size 0.1397 0.1397)
			(layers "F.Cu" "F.Mask" "F.Paste")
			(net "DRV_ACT_8")
			(options
				(clearance outline)
				(anchor circle)
			)
			(primitives
				(gr_poly
					(pts
						(arc
							(start -0.1778 -0.2794)
							(mid -0.249642 -0.249642)
							(end -0.2794 -0.1778)
						)
						(arc
							(start -0.2794 0.1778)
							(mid -0.249642 0.249642)
							(end -0.1778 0.2794)
						)
						(arc
							(start 0.1778 0.2794)
							(mid 0.249642 0.249642)
							(end 0.2794 0.1778)
						)
						(arc
							(start 0.2794 -0.1778)
							(mid 0.249642 -0.249642)
							(end 0.1778 -0.2794)
						)
					)
					(width 0)
					(fill yes)
				)
			)
		)
	)
	(footprint ""
		(layer "F.Cu")
		(at 211.582 -461.518 -90)
		(property "Reference" "C341"
			(at 0 0 270)
			(layer "F.SilkS")
			(hide yes)
			(effects
				(font
					(size 1.27 1.27)
				)
			)
		)
		(property "Value" "SCD1U16V2KX-3GP"
			(at 1.1811 -2.7051 270)
			(unlocked yes)
			(layer "F.Fab")
			(hide yes)
			(effects
				(font
					(size 1.016 1.016)
					(thickness 0.1524)
				)
			)
		)
		(property "Device Type" "C402H22"
			(at 1.1811 -4.2291 270)
			(unlocked yes)
			(layer "F.Fab")
			(hide yes)
			(effects
				(font
					(size 1.016 1.016)
					(thickness 0.1524)
				)
			)
		)
		(duplicate_pad_numbers_are_jumpers no)
		(fp_rect
			(start -0.4318 0.9525)
			(end 0.4318 -0.9525)
			(stroke
				(width 0)
				(type default)
			)
			(fill no)
			(layer "F.CrtYd")
		)
		(fp_rect
			(start -0.4318 0.9525)
			(end 0.4318 -0.9525)
			(stroke
				(width 0)
				(type default)
			)
			(fill no)
			(layer "F.Fab")
		)
		(pad "1" smd custom
			(at 0 -0.4445 270)
			(size 0.1524 0.1524)
			(layers "F.Cu" "F.Mask" "F.Paste")
			(net "P3V3")
			(options
				(clearance outline)
				(anchor circle)
			)
			(primitives
				(gr_poly
					(pts
						(arc
							(start 0.3048 -0.2032)
							(mid 0.275042 -0.275042)
							(end 0.2032 -0.3048)
						)
						(arc
							(start -0.2032 -0.3048)
							(mid -0.275042 -0.275042)
							(end -0.3048 -0.2032)
						)
						(arc
							(start -0.3048 0.2032)
							(mid -0.275042 0.275042)
							(end -0.2032 0.3048)
						)
						(arc
							(start 0.2032 0.3048)
							(mid 0.275042 0.275042)
							(end 0.3048 0.2032)
						)
					)
					(width 0)
					(fill yes)
				)
			)
		)
		(pad "2" smd custom
			(at 0 0.4445 270)
			(size 0.1524 0.1524)
			(layers "F.Cu" "F.Mask" "F.Paste")
			(net "GND")
			(options
				(clearance outline)
				(anchor circle)
			)
			(primitives
				(gr_poly
					(pts
						(arc
							(start 0.3048 -0.2032)
							(mid 0.275042 -0.275042)
							(end 0.2032 -0.3048)
						)
						(arc
							(start -0.2032 -0.3048)
							(mid -0.275042 -0.275042)
							(end -0.3048 -0.2032)
						)
						(arc
							(start -0.3048 0.2032)
							(mid -0.275042 0.275042)
							(end -0.2032 0.3048)
						)
						(arc
							(start 0.2032 0.3048)
							(mid 0.275042 0.275042)
							(end 0.3048 0.2032)
						)
					)
					(width 0)
					(fill yes)
				)
			)
		)
	)
	(footprint ""
		(layer "F.Cu")
		(at 220.726 -344.039952)
		(property "Reference" "Q34"
			(at 0 0 0)
			(layer "F.SilkS")
			(hide yes)
			(effects
				(font
					(size 1.27 1.27)
				)
			)
		)
		(property "Value" "2N7002A-7-GP"
			(at 0.127 -8.9662 0)
			(unlocked yes)
			(layer "F.Fab")
			(hide yes)
			(effects
				(font
					(size 1.016 1.016)
					(thickness 0.1524)
				)
			)
		)
		(property "Device Type" "SOT23DGS2D4H48"
			(at 0.127 -10.4902 0)
			(unlocked yes)
			(layer "F.Fab")
			(hide yes)
			(effects
				(font
					(size 1.016 1.016)
					(thickness 0.1524)
				)
			)
		)
		(duplicate_pad_numbers_are_jumpers no)
		(fp_line
			(start -1.651 -1.778)
			(end -1.651 1.778)
			(stroke
				(width 0.1524)
				(type default)
			)
			(layer "F.SilkS")
		)
		(fp_line
			(start -1.651 1.778)
			(end 1.651 1.778)
			(stroke
				(width 0.1524)
				(type default)
			)
			(layer "F.SilkS")
		)
		(fp_line
			(start 1.651 -1.778)
			(end -1.651 -1.778)
			(stroke
				(width 0.1524)
				(type default)
			)
			(layer "F.SilkS")
		)
		(fp_line
			(start 1.651 1.778)
			(end 1.651 -1.778)
			(stroke
				(width 0.1524)
				(type default)
			)
			(layer "F.SilkS")
		)
		(fp_poly
			(pts
				(xy -1.778 1.8796) (xy -1.778 -1.8796) (xy 1.778 -1.8796) (xy 1.778 1.8796)
			)
			(stroke
				(width 0)
				(type default)
			)
			(fill no)
			(layer "F.CrtYd")
		)
		(fp_poly
			(pts
				(xy -1.778 1.8796) (xy -1.778 -1.8796) (xy 1.778 -1.8796) (xy 1.778 1.8796)
			)
			(stroke
				(width 0)
				(type default)
			)
			(fill no)
			(layer "F.Fab")
		)
		(pad "D" smd custom
			(at 0 -0.9525)
			(size 0.1905 0.1905)
			(layers "F.Cu" "F.Mask" "F.Paste")
			(net "SSD1_CLK0_OE_MOS_N")
			(options
				(clearance outline)
				(anchor circle)
			)
			(primitives
				(gr_poly
					(pts
						(arc
							(start -0.1778 0.5715)
							(mid -0.321484 0.511984)
							(end -0.381 0.3683)
						)
						(arc
							(start -0.381 -0.3683)
							(mid -0.321484 -0.511984)
							(end -0.1778 -0.5715)
						)
						(arc
							(start 0.1778 -0.5715)
							(mid 0.321484 -0.511984)
							(end 0.381 -0.3683)
						)
						(arc
							(start 0.381 0.3683)
							(mid 0.321484 0.511984)
							(end 0.1778 0.5715)
						)
					)
					(width 0)
					(fill yes)
				)
			)
		)
		(pad "G" smd custom
			(at -0.98425 0.9525)
			(size 0.1905 0.1905)
			(layers "F.Cu" "F.Mask" "F.Paste")
			(net "SSD1_CLK0_OE_R_N")
			(options
				(clearance outline)
				(anchor circle)
			)
			(primitives
				(gr_poly
					(pts
						(arc
							(start -0.1778 0.5715)
							(mid -0.321484 0.511984)
							(end -0.381 0.3683)
						)
						(arc
							(start -0.381 -0.3683)
							(mid -0.321484 -0.511984)
							(end -0.1778 -0.5715)
						)
						(arc
							(start 0.1778 -0.5715)
							(mid 0.321484 -0.511984)
							(end 0.381 -0.3683)
						)
						(arc
							(start 0.381 0.3683)
							(mid 0.321484 0.511984)
							(end 0.1778 0.5715)
						)
					)
					(width 0)
					(fill yes)
				)
			)
		)
		(pad "S" smd custom
			(at 0.98425 0.9525)
			(size 0.1905 0.1905)
			(layers "F.Cu" "F.Mask" "F.Paste")
			(net "GND")
			(options
				(clearance outline)
				(anchor circle)
			)
			(primitives
				(gr_poly
					(pts
						(arc
							(start -0.1778 0.5715)
							(mid -0.321484 0.511984)
							(end -0.381 0.3683)
						)
						(arc
							(start -0.381 -0.3683)
							(mid -0.321484 -0.511984)
							(end -0.1778 -0.5715)
						)
						(arc
							(start 0.1778 -0.5715)
							(mid 0.321484 -0.511984)
							(end 0.381 -0.3683)
						)
						(arc
							(start 0.381 0.3683)
							(mid 0.321484 0.511984)
							(end 0.1778 0.5715)
						)
					)
					(width 0)
					(fill yes)
				)
			)
		)
	)
	(footprint ""
		(layer "F.Cu")
		(at 53.594 -144.526 -90)
		(property "Reference" "R9837"
			(at 0 0 270)
			(layer "F.SilkS")
			(hide yes)
			(effects
				(font
					(size 1.27 1.27)
				)
			)
		)
		(property "Value" "0R2J-2-GP"
			(at 0.064008 -3.993896 270)
			(unlocked yes)
			(layer "F.Fab")
			(hide yes)
			(effects
				(font
					(size 1.016 1.016)
					(thickness 0.1524)
				)
			)
		)
		(property "Device Type" "R402H16"
			(at 0.064008 -5.517896 270)
			(unlocked yes)
			(layer "F.Fab")
			(hide yes)
			(effects
				(font
					(size 1.016 1.016)
					(thickness 0.1524)
				)
			)
		)
		(duplicate_pad_numbers_are_jumpers no)
		(fp_line
			(start -0.508 -0.9398)
			(end -0.508 0.9398)
			(stroke
				(width 0.1524)
				(type default)
			)
			(layer "F.SilkS")
		)
		(fp_line
			(start 0.508 -0.9398)
			(end -0.508 -0.9398)
			(stroke
				(width 0.1524)
				(type default)
			)
			(layer "F.SilkS")
		)
		(fp_rect
			(start -0.508 0.9398)
			(end 0.508 -0.9398)
			(stroke
				(width 0)
				(type default)
			)
			(fill no)
			(layer "F.CrtYd")
		)
		(fp_rect
			(start -0.508 0.9398)
			(end 0.508 -0.9398)
			(stroke
				(width 0)
				(type default)
			)
			(fill no)
			(layer "F.Fab")
		)
		(pad "1" smd custom
			(at 0 -0.4445 270)
			(size 0.1397 0.1397)
			(layers "F.Cu" "F.Mask" "F.Paste")
			(net "SSD_ACT_DR8_R")
			(options
				(clearance outline)
				(anchor circle)
			)
			(primitives
				(gr_poly
					(pts
						(arc
							(start -0.1778 -0.2794)
							(mid -0.249642 -0.249642)
							(end -0.2794 -0.1778)
						)
						(arc
							(start -0.2794 0.1778)
							(mid -0.249642 0.249642)
							(end -0.1778 0.2794)
						)
						(arc
							(start 0.1778 0.2794)
							(mid 0.249642 0.249642)
							(end 0.2794 0.1778)
						)
						(arc
							(start 0.2794 -0.1778)
							(mid 0.249642 -0.249642)
							(end 0.1778 -0.2794)
						)
					)
					(width 0)
					(fill yes)
				)
			)
		)
		(pad "2" smd custom
			(at 0 0.4445 270)
			(size 0.1397 0.1397)
			(layers "F.Cu" "F.Mask" "F.Paste")
			(net "SSD_ACT_DR8")
			(options
				(clearance outline)
				(anchor circle)
			)
			(primitives
				(gr_poly
					(pts
						(arc
							(start -0.1778 -0.2794)
							(mid -0.249642 -0.249642)
							(end -0.2794 -0.1778)
						)
						(arc
							(start -0.2794 0.1778)
							(mid -0.249642 0.249642)
							(end -0.1778 0.2794)
						)
						(arc
							(start 0.1778 0.2794)
							(mid 0.249642 0.249642)
							(end 0.2794 0.1778)
						)
						(arc
							(start 0.2794 -0.1778)
							(mid 0.249642 -0.249642)
							(end 0.1778 -0.2794)
						)
					)
					(width 0)
					(fill yes)
				)
			)
		)
	)
	(footprint ""
		(layer "F.Cu")
		(at 87.757 -116.586 90)
		(property "Reference" "R9587"
			(at 0 0 90)
			(layer "F.SilkS")
			(hide yes)
			(effects
				(font
					(size 1.27 1.27)
				)
			)
		)
		(property "Value" "4K7R2J-2-GP"
			(at 0.064008 -3.993896 90)
			(unlocked yes)
			(layer "F.Fab")
			(hide yes)
			(effects
				(font
					(size 1.016 1.016)
					(thickness 0.1524)
				)
			)
		)
		(property "Device Type" "R402H16"
			(at 0.064008 -5.517896 90)
			(unlocked yes)
			(layer "F.Fab")
			(hide yes)
			(effects
				(font
					(size 1.016 1.016)
					(thickness 0.1524)
				)
			)
		)
		(duplicate_pad_numbers_are_jumpers no)
		(fp_line
			(start 0.508 -0.9398)
			(end -0.508 -0.9398)
			(stroke
				(width 0.1524)
				(type default)
			)
			(layer "F.SilkS")
		)
		(fp_line
			(start -0.508 -0.9398)
			(end -0.508 0.9398)
			(stroke
				(width 0.1524)
				(type default)
			)
			(layer "F.SilkS")
		)
		(fp_rect
			(start -0.508 0.9398)
			(end 0.508 -0.9398)
			(stroke
				(width 0)
				(type default)
			)
			(fill no)
			(layer "F.CrtYd")
		)
		(fp_rect
			(start -0.508 0.9398)
			(end 0.508 -0.9398)
			(stroke
				(width 0)
				(type default)
			)
			(fill no)
			(layer "F.Fab")
		)
		(pad "1" smd custom
			(at 0 -0.4445 90)
			(size 0.1397 0.1397)
			(layers "F.Cu" "F.Mask" "F.Paste")
			(net "P3V3")
			(options
				(clearance outline)
				(anchor circle)
			)
			(primitives
				(gr_poly
					(pts
						(arc
							(start -0.1778 -0.2794)
							(mid -0.249642 -0.249642)
							(end -0.2794 -0.1778)
						)
						(arc
							(start -0.2794 0.1778)
							(mid -0.249642 0.249642)
							(end -0.1778 0.2794)
						)
						(arc
							(start 0.1778 0.2794)
							(mid 0.249642 0.249642)
							(end 0.2794 0.1778)
						)
						(arc
							(start 0.2794 -0.1778)
							(mid 0.249642 -0.249642)
							(end 0.1778 -0.2794)
						)
					)
					(width 0)
					(fill yes)
				)
			)
		)
		(pad "2" smd custom
			(at 0 0.4445 90)
			(size 0.1397 0.1397)
			(layers "F.Cu" "F.Mask" "F.Paste")
			(net "SSD13_CLK0_OE_N")
			(options
				(clearance outline)
				(anchor circle)
			)
			(primitives
				(gr_poly
					(pts
						(arc
							(start -0.1778 -0.2794)
							(mid -0.249642 -0.249642)
							(end -0.2794 -0.1778)
						)
						(arc
							(start -0.2794 0.1778)
							(mid -0.249642 0.249642)
							(end -0.1778 0.2794)
						)
						(arc
							(start 0.1778 0.2794)
							(mid 0.249642 0.249642)
							(end 0.2794 0.1778)
						)
						(arc
							(start 0.2794 -0.1778)
							(mid 0.249642 -0.249642)
							(end 0.1778 -0.2794)
						)
					)
					(width 0)
					(fill yes)
				)
			)
		)
	)
	(footprint ""
		(layer "F.Cu")
		(at 99.314 -110.236 180)
		(property "Reference" "R9131"
			(at 0 0 180)
			(layer "F.SilkS")
			(hide yes)
			(effects
				(font
					(size 1.27 1.27)
				)
			)
		)
		(property "Value" "27R2F-GP"
			(at 0.064008 -3.993896 180)
			(unlocked yes)
			(layer "F.Fab")
			(hide yes)
			(effects
				(font
					(size 1.016 1.016)
					(thickness 0.1524)
				)
			)
		)
		(property "Device Type" "R402H16"
			(at 0.064008 -5.517896 180)
			(unlocked yes)
			(layer "F.Fab")
			(hide yes)
			(effects
				(font
					(size 1.016 1.016)
					(thickness 0.1524)
				)
			)
		)
		(duplicate_pad_numbers_are_jumpers no)
		(fp_line
			(start 0.508 -0.9398)
			(end -0.508 -0.9398)
			(stroke
				(width 0.1524)
				(type default)
			)
			(layer "F.SilkS")
		)
		(fp_line
			(start -0.508 -0.9398)
			(end -0.508 0.9398)
			(stroke
				(width 0.1524)
				(type default)
			)
			(layer "F.SilkS")
		)
		(fp_rect
			(start -0.508 0.9398)
			(end 0.508 -0.9398)
			(stroke
				(width 0)
				(type default)
			)
			(fill no)
			(layer "F.CrtYd")
		)
		(fp_rect
			(start -0.508 0.9398)
			(end 0.508 -0.9398)
			(stroke
				(width 0)
				(type default)
			)
			(fill no)
			(layer "F.Fab")
		)
		(pad "1" smd custom
			(at 0 -0.4445 180)
			(size 0.1397 0.1397)
			(layers "F.Cu" "F.Mask" "F.Paste")
			(net "PE_CLK_100M_DR8_2_R_N")
			(options
				(clearance outline)
				(anchor circle)
			)
			(primitives
				(gr_poly
					(pts
						(arc
							(start -0.1778 -0.2794)
							(mid -0.249642 -0.249642)
							(end -0.2794 -0.1778)
						)
						(arc
							(start -0.2794 0.1778)
							(mid -0.249642 0.249642)
							(end -0.1778 0.2794)
						)
						(arc
							(start 0.1778 0.2794)
							(mid 0.249642 0.249642)
							(end 0.2794 0.1778)
						)
						(arc
							(start 0.2794 -0.1778)
							(mid 0.249642 -0.249642)
							(end 0.1778 -0.2794)
						)
					)
					(width 0)
					(fill yes)
				)
			)
		)
		(pad "2" smd custom
			(at 0 0.4445 180)
			(size 0.1397 0.1397)
			(layers "F.Cu" "F.Mask" "F.Paste")
			(net "PE_CLK100M_DR8_2_N")
			(options
				(clearance outline)
				(anchor circle)
			)
			(primitives
				(gr_poly
					(pts
						(arc
							(start -0.1778 -0.2794)
							(mid -0.249642 -0.249642)
							(end -0.2794 -0.1778)
						)
						(arc
							(start -0.2794 0.1778)
							(mid -0.249642 0.249642)
							(end -0.1778 0.2794)
						)
						(arc
							(start 0.1778 0.2794)
							(mid 0.249642 0.249642)
							(end 0.2794 0.1778)
						)
						(arc
							(start 0.2794 -0.1778)
							(mid 0.249642 -0.249642)
							(end 0.1778 -0.2794)
						)
					)
					(width 0)
					(fill yes)
				)
			)
		)
	)
	(footprint ""
		(layer "F.Cu")
		(at 33.01365 -102.35565)
		(property "Reference" "R9866"
			(at 0 0 0)
			(layer "F.SilkS")
			(hide yes)
			(effects
				(font
					(size 1.27 1.27)
				)
			)
		)
		(property "Value" "47KR2J-2-GP"
			(at 0.064008 -3.993896 0)
			(unlocked yes)
			(layer "F.Fab")
			(hide yes)
			(effects
				(font
					(size 1.016 1.016)
					(thickness 0.1524)
				)
			)
		)
		(property "Device Type" "R402H16"
			(at 0.064008 -5.517896 0)
			(unlocked yes)
			(layer "F.Fab")
			(hide yes)
			(effects
				(font
					(size 1.016 1.016)
					(thickness 0.1524)
				)
			)
		)
		(duplicate_pad_numbers_are_jumpers no)
		(fp_line
			(start -0.508 -0.9398)
			(end -0.508 0.9398)
			(stroke
				(width 0.1524)
				(type default)
			)
			(layer "F.SilkS")
		)
		(fp_line
			(start 0.508 -0.9398)
			(end -0.508 -0.9398)
			(stroke
				(width 0.1524)
				(type default)
			)
			(layer "F.SilkS")
		)
		(fp_rect
			(start -0.508 0.9398)
			(end 0.508 -0.9398)
			(stroke
				(width 0)
				(type default)
			)
			(fill no)
			(layer "F.CrtYd")
		)
		(fp_rect
			(start -0.508 0.9398)
			(end 0.508 -0.9398)
			(stroke
				(width 0)
				(type default)
			)
			(fill no)
			(layer "F.Fab")
		)
		(pad "1" smd custom
			(at 0 -0.4445)
			(size 0.1397 0.1397)
			(layers "F.Cu" "F.Mask" "F.Paste")
			(net "P12V")
			(options
				(clearance outline)
				(anchor circle)
			)
			(primitives
				(gr_poly
					(pts
						(arc
							(start -0.1778 -0.2794)
							(mid -0.249642 -0.249642)
							(end -0.2794 -0.1778)
						)
						(arc
							(start -0.2794 0.1778)
							(mid -0.249642 0.249642)
							(end -0.1778 0.2794)
						)
						(arc
							(start 0.1778 0.2794)
							(mid 0.249642 0.249642)
							(end 0.2794 0.1778)
						)
						(arc
							(start 0.2794 -0.1778)
							(mid 0.249642 -0.249642)
							(end 0.1778 -0.2794)
						)
					)
					(width 0)
					(fill yes)
				)
			)
		)
		(pad "2" smd custom
			(at 0 0.4445)
			(size 0.1397 0.1397)
			(layers "F.Cu" "F.Mask" "F.Paste")
			(net "P12V_MOST13_GATE")
			(options
				(clearance outline)
				(anchor circle)
			)
			(primitives
				(gr_poly
					(pts
						(arc
							(start -0.1778 -0.2794)
							(mid -0.249642 -0.249642)
							(end -0.2794 -0.1778)
						)
						(arc
							(start -0.2794 0.1778)
							(mid -0.249642 0.249642)
							(end -0.1778 0.2794)
						)
						(arc
							(start 0.1778 0.2794)
							(mid 0.249642 0.249642)
							(end 0.2794 0.1778)
						)
						(arc
							(start 0.2794 -0.1778)
							(mid 0.249642 -0.249642)
							(end 0.1778 -0.2794)
						)
					)
					(width 0)
					(fill yes)
				)
			)
		)
	)
	(footprint ""
		(layer "F.Cu")
		(at 31.6992 -491.2614 -90)
		(property "Reference" "R397"
			(at 0 0 270)
			(layer "F.SilkS")
			(hide yes)
			(effects
				(font
					(size 1.27 1.27)
				)
			)
		)
		(property "Value" "0R2J-2-GP"
			(at 0.064008 -3.993896 270)
			(unlocked yes)
			(layer "F.Fab")
			(hide yes)
			(effects
				(font
					(size 1.016 1.016)
					(thickness 0.1524)
				)
			)
		)
		(property "Device Type" "R402H16"
			(at 0.064008 -5.517896 270)
			(unlocked yes)
			(layer "F.Fab")
			(hide yes)
			(effects
				(font
					(size 1.016 1.016)
					(thickness 0.1524)
				)
			)
		)
		(duplicate_pad_numbers_are_jumpers no)
		(fp_line
			(start -0.508 -0.9398)
			(end -0.508 0.9398)
			(stroke
				(width 0.1524)
				(type default)
			)
			(layer "F.SilkS")
		)
		(fp_line
			(start 0.508 -0.9398)
			(end -0.508 -0.9398)
			(stroke
				(width 0.1524)
				(type default)
			)
			(layer "F.SilkS")
		)
		(fp_rect
			(start -0.508 0.9398)
			(end 0.508 -0.9398)
			(stroke
				(width 0)
				(type default)
			)
			(fill no)
			(layer "F.CrtYd")
		)
		(fp_rect
			(start -0.508 0.9398)
			(end 0.508 -0.9398)
			(stroke
				(width 0)
				(type default)
			)
			(fill no)
			(layer "F.Fab")
		)
		(pad "1" smd custom
			(at 0 -0.4445 270)
			(size 0.1397 0.1397)
			(layers "F.Cu" "F.Mask" "F.Paste")
			(net "SCL_DR5_R")
			(options
				(clearance outline)
				(anchor circle)
			)
			(primitives
				(gr_poly
					(pts
						(arc
							(start -0.1778 -0.2794)
							(mid -0.249642 -0.249642)
							(end -0.2794 -0.1778)
						)
						(arc
							(start -0.2794 0.1778)
							(mid -0.249642 0.249642)
							(end -0.1778 0.2794)
						)
						(arc
							(start 0.1778 0.2794)
							(mid 0.249642 0.249642)
							(end 0.2794 0.1778)
						)
						(arc
							(start 0.2794 -0.1778)
							(mid 0.249642 -0.249642)
							(end 0.1778 -0.2794)
						)
					)
					(width 0)
					(fill yes)
				)
			)
		)
		(pad "2" smd custom
			(at 0 0.4445 270)
			(size 0.1397 0.1397)
			(layers "F.Cu" "F.Mask" "F.Paste")
			(net "SCL_DR5")
			(options
				(clearance outline)
				(anchor circle)
			)
			(primitives
				(gr_poly
					(pts
						(arc
							(start -0.1778 -0.2794)
							(mid -0.249642 -0.249642)
							(end -0.2794 -0.1778)
						)
						(arc
							(start -0.2794 0.1778)
							(mid -0.249642 0.249642)
							(end -0.1778 0.2794)
						)
						(arc
							(start 0.1778 0.2794)
							(mid 0.249642 0.249642)
							(end 0.2794 0.1778)
						)
						(arc
							(start 0.2794 -0.1778)
							(mid 0.249642 -0.249642)
							(end 0.1778 -0.2794)
						)
					)
					(width 0)
					(fill yes)
				)
			)
		)
	)
	(footprint ""
		(layer "F.Cu")
		(at 75.8063 -143.256 180)
		(property "Reference" "SR965"
			(at 0 0 180)
			(layer "F.SilkS")
			(hide yes)
			(effects
				(font
					(size 1.27 1.27)
				)
			)
		)
		(property "Value" "2KR2F-3-GP"
			(at 0.064008 -3.993896 180)
			(unlocked yes)
			(layer "F.Fab")
			(hide yes)
			(effects
				(font
					(size 1.016 1.016)
					(thickness 0.1524)
				)
			)
		)
		(property "Device Type" "R402H16"
			(at 0.064008 -5.517896 180)
			(unlocked yes)
			(layer "F.Fab")
			(hide yes)
			(effects
				(font
					(size 1.016 1.016)
					(thickness 0.1524)
				)
			)
		)
		(duplicate_pad_numbers_are_jumpers no)
		(fp_line
			(start 0.508 -0.9398)
			(end -0.508 -0.9398)
			(stroke
				(width 0.1524)
				(type default)
			)
			(layer "F.SilkS")
		)
		(fp_line
			(start -0.508 -0.9398)
			(end -0.508 0.9398)
			(stroke
				(width 0.1524)
				(type default)
			)
			(layer "F.SilkS")
		)
		(fp_rect
			(start -0.508 0.9398)
			(end 0.508 -0.9398)
			(stroke
				(width 0)
				(type default)
			)
			(fill no)
			(layer "F.CrtYd")
		)
		(fp_rect
			(start -0.508 0.9398)
			(end 0.508 -0.9398)
			(stroke
				(width 0)
				(type default)
			)
			(fill no)
			(layer "F.Fab")
		)
		(pad "1" smd custom
			(at 0 -0.4445 180)
			(size 0.1397 0.1397)
			(layers "F.Cu" "F.Mask" "F.Paste")
			(net "P3V3")
			(options
				(clearance outline)
				(anchor circle)
			)
			(primitives
				(gr_poly
					(pts
						(arc
							(start -0.1778 -0.2794)
							(mid -0.249642 -0.249642)
							(end -0.2794 -0.1778)
						)
						(arc
							(start -0.2794 0.1778)
							(mid -0.249642 0.249642)
							(end -0.1778 0.2794)
						)
						(arc
							(start 0.1778 0.2794)
							(mid 0.249642 0.249642)
							(end 0.2794 0.1778)
						)
						(arc
							(start 0.2794 -0.1778)
							(mid 0.249642 -0.249642)
							(end 0.1778 -0.2794)
						)
					)
					(width 0)
					(fill yes)
				)
			)
		)
		(pad "2" smd custom
			(at 0 0.4445 180)
			(size 0.1397 0.1397)
			(layers "F.Cu" "F.Mask" "F.Paste")
			(net "SCL_DR14")
			(options
				(clearance outline)
				(anchor circle)
			)
			(primitives
				(gr_poly
					(pts
						(arc
							(start -0.1778 -0.2794)
							(mid -0.249642 -0.249642)
							(end -0.2794 -0.1778)
						)
						(arc
							(start -0.2794 0.1778)
							(mid -0.249642 0.249642)
							(end -0.1778 0.2794)
						)
						(arc
							(start 0.1778 0.2794)
							(mid 0.249642 0.249642)
							(end 0.2794 0.1778)
						)
						(arc
							(start 0.2794 -0.1778)
							(mid 0.249642 -0.249642)
							(end 0.1778 -0.2794)
						)
					)
					(width 0)
					(fill yes)
				)
			)
		)
	)
	(footprint ""
		(layer "F.Cu")
		(at 76.0984 -366.522)
		(property "Reference" "SR984"
			(at 0 0 0)
			(layer "F.SilkS")
			(hide yes)
			(effects
				(font
					(size 1.27 1.27)
				)
			)
		)
		(property "Value" "2KR2F-3-GP"
			(at 0.064008 -3.993896 0)
			(unlocked yes)
			(layer "F.Fab")
			(hide yes)
			(effects
				(font
					(size 1.016 1.016)
					(thickness 0.1524)
				)
			)
		)
		(property "Device Type" "R402H16"
			(at 0.064008 -5.517896 0)
			(unlocked yes)
			(layer "F.Fab")
			(hide yes)
			(effects
				(font
					(size 1.016 1.016)
					(thickness 0.1524)
				)
			)
		)
		(duplicate_pad_numbers_are_jumpers no)
		(fp_line
			(start -0.508 -0.9398)
			(end -0.508 0.9398)
			(stroke
				(width 0.1524)
				(type default)
			)
			(layer "F.SilkS")
		)
		(fp_line
			(start 0.508 -0.9398)
			(end -0.508 -0.9398)
			(stroke
				(width 0.1524)
				(type default)
			)
			(layer "F.SilkS")
		)
		(fp_rect
			(start -0.508 0.9398)
			(end 0.508 -0.9398)
			(stroke
				(width 0)
				(type default)
			)
			(fill no)
			(layer "F.CrtYd")
		)
		(fp_rect
			(start -0.508 0.9398)
			(end 0.508 -0.9398)
			(stroke
				(width 0)
				(type default)
			)
			(fill no)
			(layer "F.Fab")
		)
		(pad "1" smd custom
			(at 0 -0.4445)
			(size 0.1397 0.1397)
			(layers "F.Cu" "F.Mask" "F.Paste")
			(net "P3V3")
			(options
				(clearance outline)
				(anchor circle)
			)
			(primitives
				(gr_poly
					(pts
						(arc
							(start -0.1778 -0.2794)
							(mid -0.249642 -0.249642)
							(end -0.2794 -0.1778)
						)
						(arc
							(start -0.2794 0.1778)
							(mid -0.249642 0.249642)
							(end -0.1778 0.2794)
						)
						(arc
							(start 0.1778 0.2794)
							(mid 0.249642 0.249642)
							(end 0.2794 0.1778)
						)
						(arc
							(start 0.2794 -0.1778)
							(mid 0.249642 -0.249642)
							(end 0.1778 -0.2794)
						)
					)
					(width 0)
					(fill yes)
				)
			)
		)
		(pad "2" smd custom
			(at 0 0.4445)
			(size 0.1397 0.1397)
			(layers "F.Cu" "F.Mask" "F.Paste")
			(net "SDA_DR10")
			(options
				(clearance outline)
				(anchor circle)
			)
			(primitives
				(gr_poly
					(pts
						(arc
							(start -0.1778 -0.2794)
							(mid -0.249642 -0.249642)
							(end -0.2794 -0.1778)
						)
						(arc
							(start -0.2794 0.1778)
							(mid -0.249642 0.249642)
							(end -0.1778 0.2794)
						)
						(arc
							(start 0.1778 0.2794)
							(mid 0.249642 0.249642)
							(end 0.2794 0.1778)
						)
						(arc
							(start 0.2794 -0.1778)
							(mid 0.249642 -0.249642)
							(end 0.1778 -0.2794)
						)
					)
					(width 0)
					(fill yes)
				)
			)
		)
	)
	(footprint ""
		(layer "F.Cu")
		(at 253.499874 -274.997418)
		(property "Reference" "H5"
			(at 0 0 0)
			(layer "F.SilkS")
			(hide yes)
			(effects
				(font
					(size 1.27 1.27)
				)
			)
		)
		(property "Value" "GEN276X162R197X296-6-F-A-GP"
			(at -6.7183 4.1402 0)
			(unlocked yes)
			(layer "F.Fab")
			(hide yes)
			(effects
				(font
					(size 1.016 1.016)
					(thickness 0.1524)
				)
			)
		)
		(property "Device Type" "GEN276X162R197X296-6-F-A"
			(at -6.7183 2.6162 0)
			(unlocked yes)
			(layer "F.Fab")
			(hide yes)
			(effects
				(font
					(size 1.016 1.016)
					(thickness 0.1524)
				)
			)
		)
		(duplicate_pad_numbers_are_jumpers no)
		(fp_poly
			(pts
				(arc
					(start 2.723642 4.777232)
					(mid -0.000169 6.508462)
					(end -2.723896 4.776978)
				)
				(arc
					(start -2.723896 4.776978)
					(mid 0.000173 -5.499012)
					(end 2.723642 4.777232)
				)
			)
			(stroke
				(width 0)
				(type default)
			)
			(fill no)
			(layer "B.CrtYd")
		)
		(fp_poly
			(pts
				(arc
					(start 2.723642 4.777232)
					(mid -0.000169 6.508462)
					(end -2.723896 4.776978)
				)
				(arc
					(start -2.723896 4.776978)
					(mid 0.000173 -5.499012)
					(end 2.723642 4.777232)
				)
			)
			(stroke
				(width 0)
				(type default)
			)
			(fill no)
			(layer "F.CrtYd")
		)
		(fp_poly
			(pts
				(arc
					(start 2.723642 4.777232)
					(mid -0.000169 6.508462)
					(end -2.723896 4.776978)
				)
				(arc
					(start -2.723896 4.776978)
					(mid 0.000173 -5.499012)
					(end 2.723642 4.777232)
				)
			)
			(stroke
				(width 0)
				(type default)
			)
			(fill no)
			(layer "B.Fab")
		)
		(fp_poly
			(pts
				(arc
					(start 2.723642 4.777232)
					(mid -0.000169 6.508462)
					(end -2.723896 4.776978)
				)
				(arc
					(start -2.723896 4.776978)
					(mid 0.000173 -5.499012)
					(end 2.723642 4.777232)
				)
			)
			(stroke
				(width 0)
				(type default)
			)
			(fill no)
			(layer "F.Fab")
		)
		(pad "" np_thru_hole circle
			(at 0 0)
			(size 0.254 0.254)
			(drill 0.0254)
			(layers "*.Cu" "*.Mask")
			(clearance 3.135376)
			(thermal_gap 3.135376)
		)
		(pad "1" thru_hole circle
			(at 2.549906 0)
			(size 0.8636 0.8636)
			(drill 0.508)
			(layers "*.Cu" "*.Mask")
			(remove_unused_layers no)
			(net "GND")
			(clearance 0.8255)
			(thermal_gap 0.8255)
		)
		(pad "2" thru_hole circle
			(at 2.210054 -1.27)
			(size 0.8636 0.8636)
			(drill 0.508)
			(layers "*.Cu" "*.Mask")
			(remove_unused_layers no)
			(net "GND")
			(clearance 0.8255)
			(thermal_gap 0.8255)
		)
		(pad "3" thru_hole circle
			(at 1.27 -2.210054)
			(size 0.8636 0.8636)
			(drill 0.508)
			(layers "*.Cu" "*.Mask")
			(remove_unused_layers no)
			(net "GND")
			(clearance 0.8255)
			(thermal_gap 0.8255)
		)
		(pad "4" thru_hole circle
			(at -1.279906 -2.210054)
			(size 0.8636 0.8636)
			(drill 0.508)
			(layers "*.Cu" "*.Mask")
			(remove_unused_layers no)
			(net "GND")
			(clearance 0.8255)
			(thermal_gap 0.8255)
		)
		(pad "5" thru_hole circle
			(at -2.210054 -1.27)
			(size 0.8636 0.8636)
			(drill 0.508)
			(layers "*.Cu" "*.Mask")
			(remove_unused_layers no)
			(net "GND")
			(clearance 0.8255)
			(thermal_gap 0.8255)
		)
		(pad "6" thru_hole circle
			(at -2.549906 0)
			(size 0.8636 0.8636)
			(drill 0.508)
			(layers "*.Cu" "*.Mask")
			(remove_unused_layers no)
			(net "GND")
			(clearance 0.8255)
			(thermal_gap 0.8255)
		)
		(zone
			(layers "F.Cu" "B.Cu" "In1.Cu" "In2.Cu" "In3.Cu" "In4.Cu" "In5.Cu" "In6.Cu")
			(hatch none 0.5)
			(connect_pads
				(clearance 0)
			)
			(min_thickness 0.25)
			(keepout
				(tracks allowed)
				(vias not_allowed)
				(pads allowed)
				(copperpour not_allowed)
				(footprints allowed)
			)
			(placement
				(enabled no)
				(sheetname "")
			)
			(fill
				(thermal_gap 0.5)
				(thermal_bridge_width 0.5)
				(island_removal_mode 0)
			)
			(polygon
				(pts
					(arc
						(start 257.817874 -275.000466)
						(mid 249.181874 -275.000466)
						(end 257.817874 -275.000466)
					)
				)
			)
		)
		(zone
			(layers "F.Cu" "B.Cu" "In1.Cu" "In2.Cu" "In3.Cu" "In4.Cu" "In5.Cu" "In6.Cu")
			(hatch none 0.5)
			(connect_pads
				(clearance 0)
			)
			(min_thickness 0.25)
			(keepout
				(tracks not_allowed)
				(vias allowed)
				(pads allowed)
				(copperpour not_allowed)
				(footprints allowed)
			)
			(placement
				(enabled no)
				(sheetname "")
			)
			(fill
				(thermal_gap 0.5)
				(thermal_bridge_width 0.5)
				(island_removal_mode 0)
			)
			(polygon
				(pts
					(arc
						(start 255.839214 -273.388074)
						(mid 253.499954 -268.488971)
						(end 251.16028 -273.388074)
					)
					(arc
						(start 251.16028 -273.388074)
						(mid 251.406247 -273.82844)
						(end 251.491496 -274.325588)
					)
					(arc
						(start 251.491496 -274.997418)
						(mid 253.499874 -277.005796)
						(end 255.507998 -274.997418)
					)
					(arc
						(start 255.507998 -274.325588)
						(mid 255.593233 -273.828434)
						(end 255.839214 -273.388074)
					)
				)
			)
		)
	)
	(footprint ""
		(layer "F.Cu")
		(at 8.8138 -470.6366 90)
		(property "Reference" "PC1166"
			(at 0 0 90)
			(layer "F.SilkS")
			(hide yes)
			(effects
				(font
					(size 1.27 1.27)
				)
			)
		)
		(property "Value" "SC22U25V6KX-GP-U"
			(at -2.860802 -5.279644 90)
			(unlocked yes)
			(layer "F.Fab")
			(hide yes)
			(effects
				(font
					(size 1.016 1.016)
					(thickness 0.1524)
				)
			)
		)
		(property "Device Type" "C1206-TO0D3H75"
			(at -2.860802 -6.803644 90)
			(unlocked yes)
			(layer "F.Fab")
			(hide yes)
			(effects
				(font
					(size 1.016 1.016)
					(thickness 0.1524)
				)
			)
		)
		(duplicate_pad_numbers_are_jumpers no)
		(fp_line
			(start 1.3081 -2.3749)
			(end 1.3081 2.3749)
			(stroke
				(width 0.1524)
				(type default)
			)
			(layer "F.SilkS")
		)
		(fp_line
			(start -1.3081 -2.3749)
			(end 1.3081 -2.3749)
			(stroke
				(width 0.1524)
				(type default)
			)
			(layer "F.SilkS")
		)
		(fp_line
			(start 1.3081 2.3749)
			(end -1.3081 2.3749)
			(stroke
				(width 0.1524)
				(type default)
			)
			(layer "F.SilkS")
		)
		(fp_line
			(start -1.3081 2.3749)
			(end -1.3081 -2.3749)
			(stroke
				(width 0.1524)
				(type default)
			)
			(layer "F.SilkS")
		)
		(fp_rect
			(start -0.8001 1.6002)
			(end 0.8001 -1.6002)
			(stroke
				(width 0)
				(type default)
			)
			(fill no)
			(layer "F.CrtYd")
		)
		(fp_poly
			(pts
				(xy -1.5621 2.4511) (xy -1.5621 1.6002) (xy 0.8001 1.6002) (xy 0.8001 -1.6002) (xy -0.8001 -1.6002)
				(xy -0.8001 1.5875) (xy -1.5621 1.5875) (xy -1.5621 -2.4511) (xy 1.5621 -2.4511) (xy 1.5621 2.4511)
			)
			(stroke
				(width 0)
				(type default)
			)
			(fill no)
			(layer "F.CrtYd")
		)
		(fp_rect
			(start -1.5621 2.4511)
			(end 1.5621 -2.4511)
			(stroke
				(width 0)
				(type default)
			)
			(fill no)
			(layer "F.Fab")
		)
		(pad "1" smd rect
			(at 0 -1.392936 90)
			(size 2.1082 1.4478)
			(layers "F.Cu" "F.Mask" "F.Paste")
			(net "P12V")
		)
		(pad "2" smd rect
			(at 0 1.392936 90)
			(size 2.1082 1.4478)
			(layers "F.Cu" "F.Mask" "F.Paste")
			(net "GND")
		)
	)
	(footprint ""
		(layer "F.Cu")
		(at 7.9248 -450.9389 -90)
		(property "Reference" "C9540"
			(at 0 0 270)
			(layer "F.SilkS")
			(hide yes)
			(effects
				(font
					(size 1.27 1.27)
				)
			)
		)
		(property "Value" "SCD01U50V2KX-1GP"
			(at 1.1811 -2.7051 270)
			(unlocked yes)
			(layer "F.Fab")
			(hide yes)
			(effects
				(font
					(size 1.016 1.016)
					(thickness 0.1524)
				)
			)
		)
		(property "Device Type" "C402H22"
			(at 1.1811 -4.2291 270)
			(unlocked yes)
			(layer "F.Fab")
			(hide yes)
			(effects
				(font
					(size 1.016 1.016)
					(thickness 0.1524)
				)
			)
		)
		(duplicate_pad_numbers_are_jumpers no)
		(fp_rect
			(start -0.4318 0.9525)
			(end 0.4318 -0.9525)
			(stroke
				(width 0)
				(type default)
			)
			(fill no)
			(layer "F.CrtYd")
		)
		(fp_rect
			(start -0.4318 0.9525)
			(end 0.4318 -0.9525)
			(stroke
				(width 0)
				(type default)
			)
			(fill no)
			(layer "F.Fab")
		)
		(pad "1" smd custom
			(at 0 -0.4445 270)
			(size 0.1524 0.1524)
			(layers "F.Cu" "F.Mask" "F.Paste")
			(net "PE_100M_CLK4_P")
			(options
				(clearance outline)
				(anchor circle)
			)
			(primitives
				(gr_poly
					(pts
						(arc
							(start 0.3048 -0.2032)
							(mid 0.275042 -0.275042)
							(end 0.2032 -0.3048)
						)
						(arc
							(start -0.2032 -0.3048)
							(mid -0.275042 -0.275042)
							(end -0.3048 -0.2032)
						)
						(arc
							(start -0.3048 0.2032)
							(mid -0.275042 0.275042)
							(end -0.2032 0.3048)
						)
						(arc
							(start 0.2032 0.3048)
							(mid 0.275042 0.275042)
							(end 0.3048 0.2032)
						)
					)
					(width 0)
					(fill yes)
				)
			)
		)
		(pad "2" smd custom
			(at 0 0.4445 270)
			(size 0.1524 0.1524)
			(layers "F.Cu" "F.Mask" "F.Paste")
			(net "PE_100M_CLK4_C_P")
			(options
				(clearance outline)
				(anchor circle)
			)
			(primitives
				(gr_poly
					(pts
						(arc
							(start 0.3048 -0.2032)
							(mid 0.275042 -0.275042)
							(end 0.2032 -0.3048)
						)
						(arc
							(start -0.2032 -0.3048)
							(mid -0.275042 -0.275042)
							(end -0.3048 -0.2032)
						)
						(arc
							(start -0.3048 0.2032)
							(mid -0.275042 0.275042)
							(end -0.2032 0.3048)
						)
						(arc
							(start 0.2032 0.3048)
							(mid 0.275042 0.275042)
							(end 0.3048 0.2032)
						)
					)
					(width 0)
					(fill yes)
				)
			)
		)
	)
	(footprint ""
		(layer "F.Cu")
		(at 25.146 -393.827)
		(property "Reference" "C388"
			(at 0 0 0)
			(layer "F.SilkS")
			(hide yes)
			(effects
				(font
					(size 1.27 1.27)
				)
			)
		)
		(property "Value" "SCD1U25V2KX-2-GP"
			(at 1.1811 -2.7051 0)
			(unlocked yes)
			(layer "F.Fab")
			(hide yes)
			(effects
				(font
					(size 1.016 1.016)
					(thickness 0.1524)
				)
			)
		)
		(property "Device Type" "C402H22"
			(at 1.1811 -4.2291 0)
			(unlocked yes)
			(layer "F.Fab")
			(hide yes)
			(effects
				(font
					(size 1.016 1.016)
					(thickness 0.1524)
				)
			)
		)
		(duplicate_pad_numbers_are_jumpers no)
		(fp_rect
			(start -0.4318 0.9525)
			(end 0.4318 -0.9525)
			(stroke
				(width 0)
				(type default)
			)
			(fill no)
			(layer "F.CrtYd")
		)
		(fp_rect
			(start -0.4318 0.9525)
			(end 0.4318 -0.9525)
			(stroke
				(width 0)
				(type default)
			)
			(fill no)
			(layer "F.Fab")
		)
		(pad "1" smd custom
			(at 0 -0.4445)
			(size 0.1524 0.1524)
			(layers "F.Cu" "F.Mask" "F.Paste")
			(net "P12V")
			(options
				(clearance outline)
				(anchor circle)
			)
			(primitives
				(gr_poly
					(pts
						(arc
							(start 0.3048 -0.2032)
							(mid 0.275042 -0.275042)
							(end 0.2032 -0.3048)
						)
						(arc
							(start -0.2032 -0.3048)
							(mid -0.275042 -0.275042)
							(end -0.3048 -0.2032)
						)
						(arc
							(start -0.3048 0.2032)
							(mid -0.275042 0.275042)
							(end -0.2032 0.3048)
						)
						(arc
							(start 0.2032 0.3048)
							(mid 0.275042 0.275042)
							(end 0.3048 0.2032)
						)
					)
					(width 0)
					(fill yes)
				)
			)
		)
		(pad "2" smd custom
			(at 0 0.4445)
			(size 0.1524 0.1524)
			(layers "F.Cu" "F.Mask" "F.Paste")
			(net "SW_SSD6_N")
			(options
				(clearance outline)
				(anchor circle)
			)
			(primitives
				(gr_poly
					(pts
						(arc
							(start 0.3048 -0.2032)
							(mid 0.275042 -0.275042)
							(end 0.2032 -0.3048)
						)
						(arc
							(start -0.2032 -0.3048)
							(mid -0.275042 -0.275042)
							(end -0.3048 -0.2032)
						)
						(arc
							(start -0.3048 0.2032)
							(mid -0.275042 0.275042)
							(end -0.2032 0.3048)
						)
						(arc
							(start 0.2032 0.3048)
							(mid 0.275042 0.275042)
							(end 0.3048 0.2032)
						)
					)
					(width 0)
					(fill yes)
				)
			)
		)
	)
	(footprint ""
		(layer "F.Cu")
		(at 203.454 -49.022 90)
		(property "Reference" "R334"
			(at 0 0 90)
			(layer "F.SilkS")
			(hide yes)
			(effects
				(font
					(size 1.27 1.27)
				)
			)
		)
		(property "Value" "0R2J-2-GP"
			(at 0.064008 -3.993896 90)
			(unlocked yes)
			(layer "F.Fab")
			(hide yes)
			(effects
				(font
					(size 1.016 1.016)
					(thickness 0.1524)
				)
			)
		)
		(property "Device Type" "R402H16"
			(at 0.064008 -5.517896 90)
			(unlocked yes)
			(layer "F.Fab")
			(hide yes)
			(effects
				(font
					(size 1.016 1.016)
					(thickness 0.1524)
				)
			)
		)
		(duplicate_pad_numbers_are_jumpers no)
		(fp_line
			(start 0.508 -0.9398)
			(end -0.508 -0.9398)
			(stroke
				(width 0.1524)
				(type default)
			)
			(layer "F.SilkS")
		)
		(fp_line
			(start -0.508 -0.9398)
			(end -0.508 0.9398)
			(stroke
				(width 0.1524)
				(type default)
			)
			(layer "F.SilkS")
		)
		(fp_rect
			(start -0.508 0.9398)
			(end 0.508 -0.9398)
			(stroke
				(width 0)
				(type default)
			)
			(fill no)
			(layer "F.CrtYd")
		)
		(fp_rect
			(start -0.508 0.9398)
			(end 0.508 -0.9398)
			(stroke
				(width 0)
				(type default)
			)
			(fill no)
			(layer "F.Fab")
		)
		(pad "1" smd custom
			(at 0 -0.4445 90)
			(size 0.1397 0.1397)
			(layers "F.Cu" "F.Mask" "F.Paste")
			(net "I2C_B_SCL")
			(options
				(clearance outline)
				(anchor circle)
			)
			(primitives
				(gr_poly
					(pts
						(arc
							(start -0.1778 -0.2794)
							(mid -0.249642 -0.249642)
							(end -0.2794 -0.1778)
						)
						(arc
							(start -0.2794 0.1778)
							(mid -0.249642 0.249642)
							(end -0.1778 0.2794)
						)
						(arc
							(start 0.1778 0.2794)
							(mid 0.249642 0.249642)
							(end 0.2794 0.1778)
						)
						(arc
							(start 0.2794 -0.1778)
							(mid 0.249642 -0.249642)
							(end 0.1778 -0.2794)
						)
					)
					(width 0)
					(fill yes)
				)
			)
		)
		(pad "2" smd custom
			(at 0 0.4445 90)
			(size 0.1397 0.1397)
			(layers "F.Cu" "F.Mask" "F.Paste")
			(net "TMP3_SCL")
			(options
				(clearance outline)
				(anchor circle)
			)
			(primitives
				(gr_poly
					(pts
						(arc
							(start -0.1778 -0.2794)
							(mid -0.249642 -0.249642)
							(end -0.2794 -0.1778)
						)
						(arc
							(start -0.2794 0.1778)
							(mid -0.249642 0.249642)
							(end -0.1778 0.2794)
						)
						(arc
							(start 0.1778 0.2794)
							(mid 0.249642 0.249642)
							(end 0.2794 0.1778)
						)
						(arc
							(start 0.2794 -0.1778)
							(mid 0.249642 -0.249642)
							(end 0.1778 -0.2794)
						)
					)
					(width 0)
					(fill yes)
				)
			)
		)
	)
	(footprint ""
		(layer "F.Cu")
		(at 99.06 -293.116 90)
		(property "Reference" "C940"
			(at 0 0 90)
			(layer "F.SilkS")
			(hide yes)
			(effects
				(font
					(size 1.27 1.27)
				)
			)
		)
		(property "Value" "SC1KP50V2KX-1GP"
			(at 1.1811 -2.7051 90)
			(unlocked yes)
			(layer "F.Fab")
			(hide yes)
			(effects
				(font
					(size 1.016 1.016)
					(thickness 0.1524)
				)
			)
		)
		(property "Device Type" "C402H22"
			(at 1.1811 -4.2291 90)
			(unlocked yes)
			(layer "F.Fab")
			(hide yes)
			(effects
				(font
					(size 1.016 1.016)
					(thickness 0.1524)
				)
			)
		)
		(duplicate_pad_numbers_are_jumpers no)
		(fp_rect
			(start -0.4318 0.9525)
			(end 0.4318 -0.9525)
			(stroke
				(width 0)
				(type default)
			)
			(fill no)
			(layer "F.CrtYd")
		)
		(fp_rect
			(start -0.4318 0.9525)
			(end 0.4318 -0.9525)
			(stroke
				(width 0)
				(type default)
			)
			(fill no)
			(layer "F.Fab")
		)
		(pad "1" smd custom
			(at 0 -0.4445 90)
			(size 0.1524 0.1524)
			(layers "F.Cu" "F.Mask" "F.Paste")
			(net "SSD2_CLK0_OE_R_N")
			(options
				(clearance outline)
				(anchor circle)
			)
			(primitives
				(gr_poly
					(pts
						(arc
							(start 0.3048 -0.2032)
							(mid 0.275042 -0.275042)
							(end 0.2032 -0.3048)
						)
						(arc
							(start -0.2032 -0.3048)
							(mid -0.275042 -0.275042)
							(end -0.3048 -0.2032)
						)
						(arc
							(start -0.3048 0.2032)
							(mid -0.275042 0.275042)
							(end -0.2032 0.3048)
						)
						(arc
							(start 0.2032 0.3048)
							(mid 0.275042 0.275042)
							(end 0.3048 0.2032)
						)
					)
					(width 0)
					(fill yes)
				)
			)
		)
		(pad "2" smd custom
			(at 0 0.4445 90)
			(size 0.1524 0.1524)
			(layers "F.Cu" "F.Mask" "F.Paste")
			(net "GND")
			(options
				(clearance outline)
				(anchor circle)
			)
			(primitives
				(gr_poly
					(pts
						(arc
							(start 0.3048 -0.2032)
							(mid 0.275042 -0.275042)
							(end 0.2032 -0.3048)
						)
						(arc
							(start -0.2032 -0.3048)
							(mid -0.275042 -0.275042)
							(end -0.3048 -0.2032)
						)
						(arc
							(start -0.3048 0.2032)
							(mid -0.275042 0.275042)
							(end -0.2032 0.3048)
						)
						(arc
							(start 0.2032 0.3048)
							(mid 0.275042 0.275042)
							(end 0.3048 0.2032)
						)
					)
					(width 0)
					(fill yes)
				)
			)
		)
	)
	(footprint ""
		(layer "F.Cu")
		(at 25.3238 -190.119)
		(property "Reference" "C390"
			(at 0 0 0)
			(layer "F.SilkS")
			(hide yes)
			(effects
				(font
					(size 1.27 1.27)
				)
			)
		)
		(property "Value" "SCD1U25V2KX-2-GP"
			(at 1.1811 -2.7051 0)
			(unlocked yes)
			(layer "F.Fab")
			(hide yes)
			(effects
				(font
					(size 1.016 1.016)
					(thickness 0.1524)
				)
			)
		)
		(property "Device Type" "C402H22"
			(at 1.1811 -4.2291 0)
			(unlocked yes)
			(layer "F.Fab")
			(hide yes)
			(effects
				(font
					(size 1.016 1.016)
					(thickness 0.1524)
				)
			)
		)
		(duplicate_pad_numbers_are_jumpers no)
		(fp_rect
			(start -0.4318 0.9525)
			(end 0.4318 -0.9525)
			(stroke
				(width 0)
				(type default)
			)
			(fill no)
			(layer "F.CrtYd")
		)
		(fp_rect
			(start -0.4318 0.9525)
			(end 0.4318 -0.9525)
			(stroke
				(width 0)
				(type default)
			)
			(fill no)
			(layer "F.Fab")
		)
		(pad "1" smd custom
			(at 0 -0.4445)
			(size 0.1524 0.1524)
			(layers "F.Cu" "F.Mask" "F.Paste")
			(net "P12V")
			(options
				(clearance outline)
				(anchor circle)
			)
			(primitives
				(gr_poly
					(pts
						(arc
							(start 0.3048 -0.2032)
							(mid 0.275042 -0.275042)
							(end 0.2032 -0.3048)
						)
						(arc
							(start -0.2032 -0.3048)
							(mid -0.275042 -0.275042)
							(end -0.3048 -0.2032)
						)
						(arc
							(start -0.3048 0.2032)
							(mid -0.275042 0.275042)
							(end -0.2032 0.3048)
						)
						(arc
							(start 0.2032 0.3048)
							(mid 0.275042 0.275042)
							(end 0.3048 0.2032)
						)
					)
					(width 0)
					(fill yes)
				)
			)
		)
		(pad "2" smd custom
			(at 0 0.4445)
			(size 0.1524 0.1524)
			(layers "F.Cu" "F.Mask" "F.Paste")
			(net "SW_SSD8_N")
			(options
				(clearance outline)
				(anchor circle)
			)
			(primitives
				(gr_poly
					(pts
						(arc
							(start 0.3048 -0.2032)
							(mid 0.275042 -0.275042)
							(end 0.2032 -0.3048)
						)
						(arc
							(start -0.2032 -0.3048)
							(mid -0.275042 -0.275042)
							(end -0.3048 -0.2032)
						)
						(arc
							(start -0.3048 0.2032)
							(mid -0.275042 0.275042)
							(end -0.2032 0.3048)
						)
						(arc
							(start 0.2032 0.3048)
							(mid 0.275042 0.275042)
							(end 0.3048 0.2032)
						)
					)
					(width 0)
					(fill yes)
				)
			)
		)
	)
	(footprint ""
		(layer "F.Cu")
		(at 219.075 -496.1382)
		(property "Reference" "PC1188"
			(at 0 0 0)
			(layer "F.SilkS")
			(hide yes)
			(effects
				(font
					(size 1.27 1.27)
				)
			)
		)
		(property "Value" "SCD01U50V2KX-1GP"
			(at 1.1811 -2.7051 0)
			(unlocked yes)
			(layer "F.Fab")
			(hide yes)
			(effects
				(font
					(size 1.016 1.016)
					(thickness 0.1524)
				)
			)
		)
		(property "Device Type" "C402H22"
			(at 1.1811 -4.2291 0)
			(unlocked yes)
			(layer "F.Fab")
			(hide yes)
			(effects
				(font
					(size 1.016 1.016)
					(thickness 0.1524)
				)
			)
		)
		(duplicate_pad_numbers_are_jumpers no)
		(fp_rect
			(start -0.4318 0.9525)
			(end 0.4318 -0.9525)
			(stroke
				(width 0)
				(type default)
			)
			(fill no)
			(layer "F.CrtYd")
		)
		(fp_rect
			(start -0.4318 0.9525)
			(end 0.4318 -0.9525)
			(stroke
				(width 0)
				(type default)
			)
			(fill no)
			(layer "F.Fab")
		)
		(pad "1" smd custom
			(at 0 -0.4445)
			(size 0.1524 0.1524)
			(layers "F.Cu" "F.Mask" "F.Paste")
			(net "P12V_SSD0")
			(options
				(clearance outline)
				(anchor circle)
			)
			(primitives
				(gr_poly
					(pts
						(arc
							(start 0.3048 -0.2032)
							(mid 0.275042 -0.275042)
							(end 0.2032 -0.3048)
						)
						(arc
							(start -0.2032 -0.3048)
							(mid -0.275042 -0.275042)
							(end -0.3048 -0.2032)
						)
						(arc
							(start -0.3048 0.2032)
							(mid -0.275042 0.275042)
							(end -0.2032 0.3048)
						)
						(arc
							(start 0.2032 0.3048)
							(mid 0.275042 0.275042)
							(end 0.3048 0.2032)
						)
					)
					(width 0)
					(fill yes)
				)
			)
		)
		(pad "2" smd custom
			(at 0 0.4445)
			(size 0.1524 0.1524)
			(layers "F.Cu" "F.Mask" "F.Paste")
			(net "GND")
			(options
				(clearance outline)
				(anchor circle)
			)
			(primitives
				(gr_poly
					(pts
						(arc
							(start 0.3048 -0.2032)
							(mid 0.275042 -0.275042)
							(end 0.2032 -0.3048)
						)
						(arc
							(start -0.2032 -0.3048)
							(mid -0.275042 -0.275042)
							(end -0.3048 -0.2032)
						)
						(arc
							(start -0.3048 0.2032)
							(mid -0.275042 0.275042)
							(end -0.2032 0.3048)
						)
						(arc
							(start 0.2032 0.3048)
							(mid 0.275042 0.275042)
							(end 0.3048 0.2032)
						)
					)
					(width 0)
					(fill yes)
				)
			)
		)
	)
	(footprint ""
		(layer "F.Cu")
		(at 49.53 -13.335 90)
		(property "Reference" "R152"
			(at 0 0 90)
			(layer "F.SilkS")
			(hide yes)
			(effects
				(font
					(size 1.27 1.27)
				)
			)
		)
		(property "Value" "4K7R2J-2-GP"
			(at 0.064008 -3.993896 90)
			(unlocked yes)
			(layer "F.Fab")
			(hide yes)
			(effects
				(font
					(size 1.016 1.016)
					(thickness 0.1524)
				)
			)
		)
		(property "Device Type" "R402H16"
			(at 0.064008 -5.517896 90)
			(unlocked yes)
			(layer "F.Fab")
			(hide yes)
			(effects
				(font
					(size 1.016 1.016)
					(thickness 0.1524)
				)
			)
		)
		(duplicate_pad_numbers_are_jumpers no)
		(fp_line
			(start 0.508 -0.9398)
			(end -0.508 -0.9398)
			(stroke
				(width 0.1524)
				(type default)
			)
			(layer "F.SilkS")
		)
		(fp_line
			(start -0.508 -0.9398)
			(end -0.508 0.9398)
			(stroke
				(width 0.1524)
				(type default)
			)
			(layer "F.SilkS")
		)
		(fp_rect
			(start -0.508 0.9398)
			(end 0.508 -0.9398)
			(stroke
				(width 0)
				(type default)
			)
			(fill no)
			(layer "F.CrtYd")
		)
		(fp_rect
			(start -0.508 0.9398)
			(end 0.508 -0.9398)
			(stroke
				(width 0)
				(type default)
			)
			(fill no)
			(layer "F.Fab")
		)
		(pad "1" smd custom
			(at 0 -0.4445 90)
			(size 0.1397 0.1397)
			(layers "F.Cu" "F.Mask" "F.Paste")
			(net "P12V")
			(options
				(clearance outline)
				(anchor circle)
			)
			(primitives
				(gr_poly
					(pts
						(arc
							(start -0.1778 -0.2794)
							(mid -0.249642 -0.249642)
							(end -0.2794 -0.1778)
						)
						(arc
							(start -0.2794 0.1778)
							(mid -0.249642 0.249642)
							(end -0.1778 0.2794)
						)
						(arc
							(start 0.1778 0.2794)
							(mid 0.249642 0.249642)
							(end 0.2794 0.1778)
						)
						(arc
							(start 0.2794 -0.1778)
							(mid 0.249642 -0.249642)
							(end 0.1778 -0.2794)
						)
					)
					(width 0)
					(fill yes)
				)
			)
		)
		(pad "2" smd custom
			(at 0 0.4445 90)
			(size 0.1397 0.1397)
			(layers "F.Cu" "F.Mask" "F.Paste")
			(net "SW_SSD14_R")
			(options
				(clearance outline)
				(anchor circle)
			)
			(primitives
				(gr_poly
					(pts
						(arc
							(start -0.1778 -0.2794)
							(mid -0.249642 -0.249642)
							(end -0.2794 -0.1778)
						)
						(arc
							(start -0.2794 0.1778)
							(mid -0.249642 0.249642)
							(end -0.1778 0.2794)
						)
						(arc
							(start 0.1778 0.2794)
							(mid 0.249642 0.249642)
							(end 0.2794 0.1778)
						)
						(arc
							(start 0.2794 -0.1778)
							(mid 0.249642 -0.249642)
							(end 0.1778 -0.2794)
						)
					)
					(width 0)
					(fill yes)
				)
			)
		)
	)
	(footprint ""
		(layer "F.Cu")
		(at 89.789 -113.665 -90)
		(property "Reference" "C9345"
			(at 0 0 270)
			(layer "F.SilkS")
			(hide yes)
			(effects
				(font
					(size 1.27 1.27)
				)
			)
		)
		(property "Value" "SC1KP50V2KX-1GP"
			(at 1.1811 -2.7051 270)
			(unlocked yes)
			(layer "F.Fab")
			(hide yes)
			(effects
				(font
					(size 1.016 1.016)
					(thickness 0.1524)
				)
			)
		)
		(property "Device Type" "C402H22"
			(at 1.1811 -4.2291 270)
			(unlocked yes)
			(layer "F.Fab")
			(hide yes)
			(effects
				(font
					(size 1.016 1.016)
					(thickness 0.1524)
				)
			)
		)
		(duplicate_pad_numbers_are_jumpers no)
		(fp_rect
			(start -0.4318 0.9525)
			(end 0.4318 -0.9525)
			(stroke
				(width 0)
				(type default)
			)
			(fill no)
			(layer "F.CrtYd")
		)
		(fp_rect
			(start -0.4318 0.9525)
			(end 0.4318 -0.9525)
			(stroke
				(width 0)
				(type default)
			)
			(fill no)
			(layer "F.Fab")
		)
		(pad "1" smd custom
			(at 0 -0.4445 270)
			(size 0.1524 0.1524)
			(layers "F.Cu" "F.Mask" "F.Paste")
			(net "SSD_PRSNT13")
			(options
				(clearance outline)
				(anchor circle)
			)
			(primitives
				(gr_poly
					(pts
						(arc
							(start 0.3048 -0.2032)
							(mid 0.275042 -0.275042)
							(end 0.2032 -0.3048)
						)
						(arc
							(start -0.2032 -0.3048)
							(mid -0.275042 -0.275042)
							(end -0.3048 -0.2032)
						)
						(arc
							(start -0.3048 0.2032)
							(mid -0.275042 0.275042)
							(end -0.2032 0.3048)
						)
						(arc
							(start 0.2032 0.3048)
							(mid 0.275042 0.275042)
							(end 0.3048 0.2032)
						)
					)
					(width 0)
					(fill yes)
				)
			)
		)
		(pad "2" smd custom
			(at 0 0.4445 270)
			(size 0.1524 0.1524)
			(layers "F.Cu" "F.Mask" "F.Paste")
			(net "GND")
			(options
				(clearance outline)
				(anchor circle)
			)
			(primitives
				(gr_poly
					(pts
						(arc
							(start 0.3048 -0.2032)
							(mid 0.275042 -0.275042)
							(end 0.2032 -0.3048)
						)
						(arc
							(start -0.2032 -0.3048)
							(mid -0.275042 -0.275042)
							(end -0.3048 -0.2032)
						)
						(arc
							(start -0.3048 0.2032)
							(mid -0.275042 0.275042)
							(end -0.2032 0.3048)
						)
						(arc
							(start 0.2032 0.3048)
							(mid 0.275042 0.275042)
							(end 0.3048 0.2032)
						)
					)
					(width 0)
					(fill yes)
				)
			)
		)
	)
	(footprint ""
		(layer "F.Cu")
		(at 32.131 -82.804 -90)
		(property "Reference" "R407"
			(at 0 0 270)
			(layer "F.SilkS")
			(hide yes)
			(effects
				(font
					(size 1.27 1.27)
				)
			)
		)
		(property "Value" "0R2J-2-GP"
			(at 0.064008 -3.993896 270)
			(unlocked yes)
			(layer "F.Fab")
			(hide yes)
			(effects
				(font
					(size 1.016 1.016)
					(thickness 0.1524)
				)
			)
		)
		(property "Device Type" "R402H16"
			(at 0.064008 -5.517896 270)
			(unlocked yes)
			(layer "F.Fab")
			(hide yes)
			(effects
				(font
					(size 1.016 1.016)
					(thickness 0.1524)
				)
			)
		)
		(duplicate_pad_numbers_are_jumpers no)
		(fp_line
			(start -0.508 -0.9398)
			(end -0.508 0.9398)
			(stroke
				(width 0.1524)
				(type default)
			)
			(layer "F.SilkS")
		)
		(fp_line
			(start 0.508 -0.9398)
			(end -0.508 -0.9398)
			(stroke
				(width 0.1524)
				(type default)
			)
			(layer "F.SilkS")
		)
		(fp_rect
			(start -0.508 0.9398)
			(end 0.508 -0.9398)
			(stroke
				(width 0)
				(type default)
			)
			(fill no)
			(layer "F.CrtYd")
		)
		(fp_rect
			(start -0.508 0.9398)
			(end 0.508 -0.9398)
			(stroke
				(width 0)
				(type default)
			)
			(fill no)
			(layer "F.Fab")
		)
		(pad "1" smd custom
			(at 0 -0.4445 270)
			(size 0.1397 0.1397)
			(layers "F.Cu" "F.Mask" "F.Paste")
			(net "SDA_DR9_R")
			(options
				(clearance outline)
				(anchor circle)
			)
			(primitives
				(gr_poly
					(pts
						(arc
							(start -0.1778 -0.2794)
							(mid -0.249642 -0.249642)
							(end -0.2794 -0.1778)
						)
						(arc
							(start -0.2794 0.1778)
							(mid -0.249642 0.249642)
							(end -0.1778 0.2794)
						)
						(arc
							(start 0.1778 0.2794)
							(mid 0.249642 0.249642)
							(end 0.2794 0.1778)
						)
						(arc
							(start 0.2794 -0.1778)
							(mid 0.249642 -0.249642)
							(end 0.1778 -0.2794)
						)
					)
					(width 0)
					(fill yes)
				)
			)
		)
		(pad "2" smd custom
			(at 0 0.4445 270)
			(size 0.1397 0.1397)
			(layers "F.Cu" "F.Mask" "F.Paste")
			(net "SDA_DR9")
			(options
				(clearance outline)
				(anchor circle)
			)
			(primitives
				(gr_poly
					(pts
						(arc
							(start -0.1778 -0.2794)
							(mid -0.249642 -0.249642)
							(end -0.2794 -0.1778)
						)
						(arc
							(start -0.2794 0.1778)
							(mid -0.249642 0.249642)
							(end -0.1778 0.2794)
						)
						(arc
							(start 0.1778 0.2794)
							(mid 0.249642 0.249642)
							(end 0.2794 0.1778)
						)
						(arc
							(start 0.2794 -0.1778)
							(mid 0.249642 -0.249642)
							(end 0.1778 -0.2794)
						)
					)
					(width 0)
					(fill yes)
				)
			)
		)
	)
	(footprint ""
		(layer "F.Cu")
		(at 217.043 -288.798 -90)
		(property "Reference" "R392"
			(at 0 0 270)
			(layer "F.SilkS")
			(hide yes)
			(effects
				(font
					(size 1.27 1.27)
				)
			)
		)
		(property "Value" "0R2J-2-GP"
			(at 0.064008 -3.993896 270)
			(unlocked yes)
			(layer "F.Fab")
			(hide yes)
			(effects
				(font
					(size 1.016 1.016)
					(thickness 0.1524)
				)
			)
		)
		(property "Device Type" "R402H16"
			(at 0.064008 -5.517896 270)
			(unlocked yes)
			(layer "F.Fab")
			(hide yes)
			(effects
				(font
					(size 1.016 1.016)
					(thickness 0.1524)
				)
			)
		)
		(duplicate_pad_numbers_are_jumpers no)
		(fp_line
			(start -0.508 -0.9398)
			(end -0.508 0.9398)
			(stroke
				(width 0.1524)
				(type default)
			)
			(layer "F.SilkS")
		)
		(fp_line
			(start 0.508 -0.9398)
			(end -0.508 -0.9398)
			(stroke
				(width 0.1524)
				(type default)
			)
			(layer "F.SilkS")
		)
		(fp_rect
			(start -0.508 0.9398)
			(end 0.508 -0.9398)
			(stroke
				(width 0)
				(type default)
			)
			(fill no)
			(layer "F.CrtYd")
		)
		(fp_rect
			(start -0.508 0.9398)
			(end 0.508 -0.9398)
			(stroke
				(width 0)
				(type default)
			)
			(fill no)
			(layer "F.Fab")
		)
		(pad "1" smd custom
			(at 0 -0.4445 270)
			(size 0.1397 0.1397)
			(layers "F.Cu" "F.Mask" "F.Paste")
			(net "SDA_DR2_R")
			(options
				(clearance outline)
				(anchor circle)
			)
			(primitives
				(gr_poly
					(pts
						(arc
							(start -0.1778 -0.2794)
							(mid -0.249642 -0.249642)
							(end -0.2794 -0.1778)
						)
						(arc
							(start -0.2794 0.1778)
							(mid -0.249642 0.249642)
							(end -0.1778 0.2794)
						)
						(arc
							(start 0.1778 0.2794)
							(mid 0.249642 0.249642)
							(end 0.2794 0.1778)
						)
						(arc
							(start 0.2794 -0.1778)
							(mid 0.249642 -0.249642)
							(end 0.1778 -0.2794)
						)
					)
					(width 0)
					(fill yes)
				)
			)
		)
		(pad "2" smd custom
			(at 0 0.4445 270)
			(size 0.1397 0.1397)
			(layers "F.Cu" "F.Mask" "F.Paste")
			(net "SDA_DR2")
			(options
				(clearance outline)
				(anchor circle)
			)
			(primitives
				(gr_poly
					(pts
						(arc
							(start -0.1778 -0.2794)
							(mid -0.249642 -0.249642)
							(end -0.2794 -0.1778)
						)
						(arc
							(start -0.2794 0.1778)
							(mid -0.249642 0.249642)
							(end -0.1778 0.2794)
						)
						(arc
							(start 0.1778 0.2794)
							(mid 0.249642 0.249642)
							(end 0.2794 0.1778)
						)
						(arc
							(start 0.2794 -0.1778)
							(mid 0.249642 -0.249642)
							(end 0.1778 -0.2794)
						)
					)
					(width 0)
					(fill yes)
				)
			)
		)
	)
	(footprint ""
		(layer "F.Cu")
		(at 22.86 -94.234 180)
		(property "Reference" "R9750"
			(at 0 0 180)
			(layer "F.SilkS")
			(hide yes)
			(effects
				(font
					(size 1.27 1.27)
				)
			)
		)
		(property "Value" "4K7R2J-2-GP"
			(at 0.064008 -3.993896 180)
			(unlocked yes)
			(layer "F.Fab")
			(hide yes)
			(effects
				(font
					(size 1.016 1.016)
					(thickness 0.1524)
				)
			)
		)
		(property "Device Type" "R402H16"
			(at 0.064008 -5.517896 180)
			(unlocked yes)
			(layer "F.Fab")
			(hide yes)
			(effects
				(font
					(size 1.016 1.016)
					(thickness 0.1524)
				)
			)
		)
		(duplicate_pad_numbers_are_jumpers no)
		(fp_line
			(start 0.508 -0.9398)
			(end -0.508 -0.9398)
			(stroke
				(width 0.1524)
				(type default)
			)
			(layer "F.SilkS")
		)
		(fp_line
			(start -0.508 -0.9398)
			(end -0.508 0.9398)
			(stroke
				(width 0.1524)
				(type default)
			)
			(layer "F.SilkS")
		)
		(fp_rect
			(start -0.508 0.9398)
			(end 0.508 -0.9398)
			(stroke
				(width 0)
				(type default)
			)
			(fill no)
			(layer "F.CrtYd")
		)
		(fp_rect
			(start -0.508 0.9398)
			(end 0.508 -0.9398)
			(stroke
				(width 0)
				(type default)
			)
			(fill no)
			(layer "F.Fab")
		)
		(pad "1" smd custom
			(at 0 -0.4445 180)
			(size 0.1397 0.1397)
			(layers "F.Cu" "F.Mask" "F.Paste")
			(net "P3V3")
			(options
				(clearance outline)
				(anchor circle)
			)
			(primitives
				(gr_poly
					(pts
						(arc
							(start -0.1778 -0.2794)
							(mid -0.249642 -0.249642)
							(end -0.2794 -0.1778)
						)
						(arc
							(start -0.2794 0.1778)
							(mid -0.249642 0.249642)
							(end -0.1778 0.2794)
						)
						(arc
							(start 0.1778 0.2794)
							(mid 0.249642 0.249642)
							(end 0.2794 0.1778)
						)
						(arc
							(start 0.2794 -0.1778)
							(mid 0.249642 -0.249642)
							(end 0.1778 -0.2794)
						)
					)
					(width 0)
					(fill yes)
				)
			)
		)
		(pad "2" smd custom
			(at 0 0.4445 180)
			(size 0.1397 0.1397)
			(layers "F.Cu" "F.Mask" "F.Paste")
			(net "SSD9_PWREN")
			(options
				(clearance outline)
				(anchor circle)
			)
			(primitives
				(gr_poly
					(pts
						(arc
							(start -0.1778 -0.2794)
							(mid -0.249642 -0.249642)
							(end -0.2794 -0.1778)
						)
						(arc
							(start -0.2794 0.1778)
							(mid -0.249642 0.249642)
							(end -0.1778 0.2794)
						)
						(arc
							(start 0.1778 0.2794)
							(mid 0.249642 0.249642)
							(end 0.2794 0.1778)
						)
						(arc
							(start 0.2794 -0.1778)
							(mid 0.249642 -0.249642)
							(end 0.1778 -0.2794)
						)
					)
					(width 0)
					(fill yes)
				)
			)
		)
	)
	(footprint ""
		(layer "F.Cu")
		(at 87.503 -423.164)
		(property "Reference" "R9072"
			(at 0 0 0)
			(layer "F.SilkS")
			(hide yes)
			(effects
				(font
					(size 1.27 1.27)
				)
			)
		)
		(property "Value" "27R2F-GP"
			(at 0.064008 -3.993896 0)
			(unlocked yes)
			(layer "F.Fab")
			(hide yes)
			(effects
				(font
					(size 1.016 1.016)
					(thickness 0.1524)
				)
			)
		)
		(property "Device Type" "R402H16"
			(at 0.064008 -5.517896 0)
			(unlocked yes)
			(layer "F.Fab")
			(hide yes)
			(effects
				(font
					(size 1.016 1.016)
					(thickness 0.1524)
				)
			)
		)
		(duplicate_pad_numbers_are_jumpers no)
		(fp_line
			(start -0.508 -0.9398)
			(end -0.508 0.9398)
			(stroke
				(width 0.1524)
				(type default)
			)
			(layer "F.SilkS")
		)
		(fp_line
			(start 0.508 -0.9398)
			(end -0.508 -0.9398)
			(stroke
				(width 0.1524)
				(type default)
			)
			(layer "F.SilkS")
		)
		(fp_rect
			(start -0.508 0.9398)
			(end 0.508 -0.9398)
			(stroke
				(width 0)
				(type default)
			)
			(fill no)
			(layer "F.CrtYd")
		)
		(fp_rect
			(start -0.508 0.9398)
			(end 0.508 -0.9398)
			(stroke
				(width 0)
				(type default)
			)
			(fill no)
			(layer "F.Fab")
		)
		(pad "1" smd custom
			(at 0 -0.4445)
			(size 0.1397 0.1397)
			(layers "F.Cu" "F.Mask" "F.Paste")
			(net "PE_CLK_100M_DR10_2_R_N")
			(options
				(clearance outline)
				(anchor circle)
			)
			(primitives
				(gr_poly
					(pts
						(arc
							(start -0.1778 -0.2794)
							(mid -0.249642 -0.249642)
							(end -0.2794 -0.1778)
						)
						(arc
							(start -0.2794 0.1778)
							(mid -0.249642 0.249642)
							(end -0.1778 0.2794)
						)
						(arc
							(start 0.1778 0.2794)
							(mid 0.249642 0.249642)
							(end 0.2794 0.1778)
						)
						(arc
							(start 0.2794 -0.1778)
							(mid 0.249642 -0.249642)
							(end 0.1778 -0.2794)
						)
					)
					(width 0)
					(fill yes)
				)
			)
		)
		(pad "2" smd custom
			(at 0 0.4445)
			(size 0.1397 0.1397)
			(layers "F.Cu" "F.Mask" "F.Paste")
			(net "PE_CLK100M_DR10_2_N")
			(options
				(clearance outline)
				(anchor circle)
			)
			(primitives
				(gr_poly
					(pts
						(arc
							(start -0.1778 -0.2794)
							(mid -0.249642 -0.249642)
							(end -0.2794 -0.1778)
						)
						(arc
							(start -0.2794 0.1778)
							(mid -0.249642 0.249642)
							(end -0.1778 0.2794)
						)
						(arc
							(start 0.1778 0.2794)
							(mid 0.249642 0.249642)
							(end 0.2794 0.1778)
						)
						(arc
							(start 0.2794 -0.1778)
							(mid 0.249642 -0.249642)
							(end 0.1778 -0.2794)
						)
					)
					(width 0)
					(fill yes)
				)
			)
		)
	)
	(footprint ""
		(layer "F.Cu")
		(at 227.457 -34.913062 90)
		(property "Reference" "U201"
			(at 0 0 90)
			(layer "F.SilkS")
			(hide yes)
			(effects
				(font
					(size 1.27 1.27)
				)
			)
		)
		(property "Value" "SN74LVC1G08DCKR-GP"
			(at -2.3368 -8.6868 90)
			(unlocked yes)
			(layer "F.Fab")
			(hide yes)
			(effects
				(font
					(size 1.016 1.016)
					(thickness 0.1524)
				)
			)
		)
		(property "Device Type" "SC70-5H44"
			(at -2.3114 -10.414 90)
			(unlocked yes)
			(layer "F.Fab")
			(hide yes)
			(effects
				(font
					(size 1.016 1.016)
					(thickness 0.1524)
				)
			)
		)
		(duplicate_pad_numbers_are_jumpers no)
		(fp_line
			(start 1.3843 -1.8034)
			(end 1.3843 -1.1176)
			(stroke
				(width 0.3302)
				(type default)
			)
			(layer "F.SilkS")
		)
		(fp_line
			(start 0.6604 -1.8034)
			(end 1.3843 -1.8034)
			(stroke
				(width 0.3302)
				(type default)
			)
			(layer "F.SilkS")
		)
		(fp_line
			(start 1.27 -1.7018)
			(end 1.27 1.7018)
			(stroke
				(width 0.1524)
				(type default)
			)
			(layer "F.SilkS")
		)
		(fp_line
			(start -1.27 -1.7018)
			(end 1.27 -1.7018)
			(stroke
				(width 0.1524)
				(type default)
			)
			(layer "F.SilkS")
		)
		(fp_line
			(start 1.27 1.7018)
			(end -1.27 1.7018)
			(stroke
				(width 0.1524)
				(type default)
			)
			(layer "F.SilkS")
		)
		(fp_line
			(start -1.27 1.7018)
			(end -1.27 -1.7018)
			(stroke
				(width 0.1524)
				(type default)
			)
			(layer "F.SilkS")
		)
		(fp_rect
			(start -1.524 1.9558)
			(end 1.524 -1.9558)
			(stroke
				(width 0)
				(type default)
			)
			(fill no)
			(layer "F.CrtYd")
		)
		(fp_poly
			(pts
				(xy -1.524 -1.9558) (xy 1.524 -1.9558) (xy 1.524 1.9558) (xy -1.524 1.9558)
			)
			(stroke
				(width 0)
				(type default)
			)
			(fill no)
			(layer "F.Fab")
		)
		(pad "1" smd rect
			(at 0.65024 -0.8255 90)
			(size 0.4064 1.2192)
			(layers "F.Cu" "F.Mask" "F.Paste")
			(net "SSD4_CLK0_OE_MOS_N")
		)
		(pad "2" smd rect
			(at 0 -0.8255 90)
			(size 0.4064 1.2192)
			(layers "F.Cu" "F.Mask" "F.Paste")
			(net "ATTN_LED_DR4_N")
		)
		(pad "3" smd rect
			(at -0.65024 -0.8255 90)
			(size 0.4064 1.2192)
			(layers "F.Cu" "F.Mask" "F.Paste")
			(net "GND")
		)
		(pad "4" smd rect
			(at -0.65024 0.8255 90)
			(size 0.4064 1.2192)
			(layers "F.Cu" "F.Mask" "F.Paste")
			(net "ATTN_LED_DR4_AND")
		)
		(pad "5" smd rect
			(at 0.65024 0.8255 90)
			(size 0.4064 1.2192)
			(layers "F.Cu" "F.Mask" "F.Paste")
			(net "P3V3")
		)
	)
	(footprint ""
		(layer "F.Cu")
		(at 96.647 -88.138 180)
		(property "Reference" "R9616"
			(at 0 0 180)
			(layer "F.SilkS")
			(hide yes)
			(effects
				(font
					(size 1.27 1.27)
				)
			)
		)
		(property "Value" "10R2F-L-GP"
			(at 0.064008 -3.993896 180)
			(unlocked yes)
			(layer "F.Fab")
			(hide yes)
			(effects
				(font
					(size 1.016 1.016)
					(thickness 0.1524)
				)
			)
		)
		(property "Device Type" "R402H14"
			(at 0.064008 -5.517896 180)
			(unlocked yes)
			(layer "F.Fab")
			(hide yes)
			(effects
				(font
					(size 1.016 1.016)
					(thickness 0.1524)
				)
			)
		)
		(duplicate_pad_numbers_are_jumpers no)
		(fp_line
			(start 0.508 -0.9398)
			(end -0.508 -0.9398)
			(stroke
				(width 0.1524)
				(type default)
			)
			(layer "F.SilkS")
		)
		(fp_line
			(start -0.508 -0.9398)
			(end -0.508 0.9398)
			(stroke
				(width 0.1524)
				(type default)
			)
			(layer "F.SilkS")
		)
		(fp_rect
			(start -0.508 0.9398)
			(end 0.508 -0.9398)
			(stroke
				(width 0)
				(type default)
			)
			(fill no)
			(layer "F.CrtYd")
		)
		(fp_rect
			(start -0.508 0.9398)
			(end 0.508 -0.9398)
			(stroke
				(width 0)
				(type default)
			)
			(fill no)
			(layer "F.Fab")
		)
		(pad "1" smd custom
			(at 0 -0.4445 180)
			(size 0.1397 0.1397)
			(layers "F.Cu" "F.Mask" "F.Paste")
			(net "SSD_PRSNT_NET14")
			(options
				(clearance outline)
				(anchor circle)
			)
			(primitives
				(gr_poly
					(pts
						(arc
							(start -0.1778 -0.2794)
							(mid -0.249642 -0.249642)
							(end -0.2794 -0.1778)
						)
						(arc
							(start -0.2794 0.1778)
							(mid -0.249642 0.249642)
							(end -0.1778 0.2794)
						)
						(arc
							(start 0.1778 0.2794)
							(mid 0.249642 0.249642)
							(end 0.2794 0.1778)
						)
						(arc
							(start 0.2794 -0.1778)
							(mid 0.249642 -0.249642)
							(end 0.1778 -0.2794)
						)
					)
					(width 0)
					(fill yes)
				)
			)
		)
		(pad "2" smd custom
			(at 0 0.4445 180)
			(size 0.1397 0.1397)
			(layers "F.Cu" "F.Mask" "F.Paste")
			(net "SSD_PRSNT14")
			(options
				(clearance outline)
				(anchor circle)
			)
			(primitives
				(gr_poly
					(pts
						(arc
							(start -0.1778 -0.2794)
							(mid -0.249642 -0.249642)
							(end -0.2794 -0.1778)
						)
						(arc
							(start -0.2794 0.1778)
							(mid -0.249642 0.249642)
							(end -0.1778 0.2794)
						)
						(arc
							(start 0.1778 0.2794)
							(mid 0.249642 0.249642)
							(end 0.2794 0.1778)
						)
						(arc
							(start 0.2794 -0.1778)
							(mid 0.249642 -0.249642)
							(end 0.1778 -0.2794)
						)
					)
					(width 0)
					(fill yes)
				)
			)
		)
	)
	(footprint ""
		(layer "F.Cu")
		(at 29.845 -321.437 90)
		(property "Reference" "R410"
			(at 0 0 90)
			(layer "F.SilkS")
			(hide yes)
			(effects
				(font
					(size 1.27 1.27)
				)
			)
		)
		(property "Value" "0R2J-2-GP"
			(at 0.064008 -3.993896 90)
			(unlocked yes)
			(layer "F.Fab")
			(hide yes)
			(effects
				(font
					(size 1.016 1.016)
					(thickness 0.1524)
				)
			)
		)
		(property "Device Type" "R402H16"
			(at 0.064008 -5.517896 90)
			(unlocked yes)
			(layer "F.Fab")
			(hide yes)
			(effects
				(font
					(size 1.016 1.016)
					(thickness 0.1524)
				)
			)
		)
		(duplicate_pad_numbers_are_jumpers no)
		(fp_line
			(start 0.508 -0.9398)
			(end -0.508 -0.9398)
			(stroke
				(width 0.1524)
				(type default)
			)
			(layer "F.SilkS")
		)
		(fp_line
			(start -0.508 -0.9398)
			(end -0.508 0.9398)
			(stroke
				(width 0.1524)
				(type default)
			)
			(layer "F.SilkS")
		)
		(fp_rect
			(start -0.508 0.9398)
			(end 0.508 -0.9398)
			(stroke
				(width 0)
				(type default)
			)
			(fill no)
			(layer "F.CrtYd")
		)
		(fp_rect
			(start -0.508 0.9398)
			(end 0.508 -0.9398)
			(stroke
				(width 0)
				(type default)
			)
			(fill no)
			(layer "F.Fab")
		)
		(pad "1" smd custom
			(at 0 -0.4445 90)
			(size 0.1397 0.1397)
			(layers "F.Cu" "F.Mask" "F.Paste")
			(net "SCL_DR11_R")
			(options
				(clearance outline)
				(anchor circle)
			)
			(primitives
				(gr_poly
					(pts
						(arc
							(start -0.1778 -0.2794)
							(mid -0.249642 -0.249642)
							(end -0.2794 -0.1778)
						)
						(arc
							(start -0.2794 0.1778)
							(mid -0.249642 0.249642)
							(end -0.1778 0.2794)
						)
						(arc
							(start 0.1778 0.2794)
							(mid 0.249642 0.249642)
							(end 0.2794 0.1778)
						)
						(arc
							(start 0.2794 -0.1778)
							(mid 0.249642 -0.249642)
							(end 0.1778 -0.2794)
						)
					)
					(width 0)
					(fill yes)
				)
			)
		)
		(pad "2" smd custom
			(at 0 0.4445 90)
			(size 0.1397 0.1397)
			(layers "F.Cu" "F.Mask" "F.Paste")
			(net "SCL_DR11")
			(options
				(clearance outline)
				(anchor circle)
			)
			(primitives
				(gr_poly
					(pts
						(arc
							(start -0.1778 -0.2794)
							(mid -0.249642 -0.249642)
							(end -0.2794 -0.1778)
						)
						(arc
							(start -0.2794 0.1778)
							(mid -0.249642 0.249642)
							(end -0.1778 0.2794)
						)
						(arc
							(start 0.1778 0.2794)
							(mid 0.249642 0.249642)
							(end 0.2794 0.1778)
						)
						(arc
							(start 0.2794 -0.1778)
							(mid 0.249642 -0.249642)
							(end 0.1778 -0.2794)
						)
					)
					(width 0)
					(fill yes)
				)
			)
		)
	)
	(footprint ""
		(layer "F.Cu")
		(at 70.739 -143.51 90)
		(property "Reference" "SR967"
			(at 0 0 90)
			(layer "F.SilkS")
			(hide yes)
			(effects
				(font
					(size 1.27 1.27)
				)
			)
		)
		(property "Value" "2KR2F-3-GP"
			(at 0.064008 -3.993896 90)
			(unlocked yes)
			(layer "F.Fab")
			(hide yes)
			(effects
				(font
					(size 1.016 1.016)
					(thickness 0.1524)
				)
			)
		)
		(property "Device Type" "R402H16"
			(at 0.064008 -5.517896 90)
			(unlocked yes)
			(layer "F.Fab")
			(hide yes)
			(effects
				(font
					(size 1.016 1.016)
					(thickness 0.1524)
				)
			)
		)
		(duplicate_pad_numbers_are_jumpers no)
		(fp_line
			(start 0.508 -0.9398)
			(end -0.508 -0.9398)
			(stroke
				(width 0.1524)
				(type default)
			)
			(layer "F.SilkS")
		)
		(fp_line
			(start -0.508 -0.9398)
			(end -0.508 0.9398)
			(stroke
				(width 0.1524)
				(type default)
			)
			(layer "F.SilkS")
		)
		(fp_rect
			(start -0.508 0.9398)
			(end 0.508 -0.9398)
			(stroke
				(width 0)
				(type default)
			)
			(fill no)
			(layer "F.CrtYd")
		)
		(fp_rect
			(start -0.508 0.9398)
			(end 0.508 -0.9398)
			(stroke
				(width 0)
				(type default)
			)
			(fill no)
			(layer "F.Fab")
		)
		(pad "1" smd custom
			(at 0 -0.4445 90)
			(size 0.1397 0.1397)
			(layers "F.Cu" "F.Mask" "F.Paste")
			(net "P3V3")
			(options
				(clearance outline)
				(anchor circle)
			)
			(primitives
				(gr_poly
					(pts
						(arc
							(start -0.1778 -0.2794)
							(mid -0.249642 -0.249642)
							(end -0.2794 -0.1778)
						)
						(arc
							(start -0.2794 0.1778)
							(mid -0.249642 0.249642)
							(end -0.1778 0.2794)
						)
						(arc
							(start 0.1778 0.2794)
							(mid 0.249642 0.249642)
							(end 0.2794 0.1778)
						)
						(arc
							(start 0.2794 -0.1778)
							(mid 0.249642 -0.249642)
							(end 0.1778 -0.2794)
						)
					)
					(width 0)
					(fill yes)
				)
			)
		)
		(pad "2" smd custom
			(at 0 0.4445 90)
			(size 0.1397 0.1397)
			(layers "F.Cu" "F.Mask" "F.Paste")
			(net "SCL_DR9")
			(options
				(clearance outline)
				(anchor circle)
			)
			(primitives
				(gr_poly
					(pts
						(arc
							(start -0.1778 -0.2794)
							(mid -0.249642 -0.249642)
							(end -0.2794 -0.1778)
						)
						(arc
							(start -0.2794 0.1778)
							(mid -0.249642 0.249642)
							(end -0.1778 0.2794)
						)
						(arc
							(start 0.1778 0.2794)
							(mid 0.249642 0.249642)
							(end 0.2794 0.1778)
						)
						(arc
							(start 0.2794 -0.1778)
							(mid 0.249642 -0.249642)
							(end 0.1778 -0.2794)
						)
					)
					(width 0)
					(fill yes)
				)
			)
		)
	)
	(footprint ""
		(layer "F.Cu")
		(at 207.391 -197.231 180)
		(property "Reference" "R9503"
			(at 0 0 180)
			(layer "F.SilkS")
			(hide yes)
			(effects
				(font
					(size 1.27 1.27)
				)
			)
		)
		(property "Value" "4K7R2J-2-GP"
			(at 0.064008 -3.993896 180)
			(unlocked yes)
			(layer "F.Fab")
			(hide yes)
			(effects
				(font
					(size 1.016 1.016)
					(thickness 0.1524)
				)
			)
		)
		(property "Device Type" "R402H16"
			(at 0.064008 -5.517896 180)
			(unlocked yes)
			(layer "F.Fab")
			(hide yes)
			(effects
				(font
					(size 1.016 1.016)
					(thickness 0.1524)
				)
			)
		)
		(duplicate_pad_numbers_are_jumpers no)
		(fp_line
			(start 0.508 -0.9398)
			(end -0.508 -0.9398)
			(stroke
				(width 0.1524)
				(type default)
			)
			(layer "F.SilkS")
		)
		(fp_line
			(start -0.508 -0.9398)
			(end -0.508 0.9398)
			(stroke
				(width 0.1524)
				(type default)
			)
			(layer "F.SilkS")
		)
		(fp_rect
			(start -0.508 0.9398)
			(end 0.508 -0.9398)
			(stroke
				(width 0)
				(type default)
			)
			(fill no)
			(layer "F.CrtYd")
		)
		(fp_rect
			(start -0.508 0.9398)
			(end 0.508 -0.9398)
			(stroke
				(width 0)
				(type default)
			)
			(fill no)
			(layer "F.Fab")
		)
		(pad "1" smd custom
			(at 0 -0.4445 180)
			(size 0.1397 0.1397)
			(layers "F.Cu" "F.Mask" "F.Paste")
			(net "P3V3")
			(options
				(clearance outline)
				(anchor circle)
			)
			(primitives
				(gr_poly
					(pts
						(arc
							(start -0.1778 -0.2794)
							(mid -0.249642 -0.249642)
							(end -0.2794 -0.1778)
						)
						(arc
							(start -0.2794 0.1778)
							(mid -0.249642 0.249642)
							(end -0.1778 0.2794)
						)
						(arc
							(start 0.1778 0.2794)
							(mid 0.249642 0.249642)
							(end 0.2794 0.1778)
						)
						(arc
							(start 0.2794 -0.1778)
							(mid 0.249642 -0.249642)
							(end 0.1778 -0.2794)
						)
					)
					(width 0)
					(fill yes)
				)
			)
		)
		(pad "2" smd custom
			(at 0 0.4445 180)
			(size 0.1397 0.1397)
			(layers "F.Cu" "F.Mask" "F.Paste")
			(net "SSD3_PWREN")
			(options
				(clearance outline)
				(anchor circle)
			)
			(primitives
				(gr_poly
					(pts
						(arc
							(start -0.1778 -0.2794)
							(mid -0.249642 -0.249642)
							(end -0.2794 -0.1778)
						)
						(arc
							(start -0.2794 0.1778)
							(mid -0.249642 0.249642)
							(end -0.1778 0.2794)
						)
						(arc
							(start 0.1778 0.2794)
							(mid 0.249642 0.249642)
							(end 0.2794 0.1778)
						)
						(arc
							(start 0.2794 -0.1778)
							(mid 0.249642 -0.249642)
							(end 0.1778 -0.2794)
						)
					)
					(width 0)
					(fill yes)
				)
			)
		)
	)
	(footprint ""
		(layer "F.Cu")
		(at 88.011 -86.614 -90)
		(property "Reference" "R9395"
			(at 0 0 270)
			(layer "F.SilkS")
			(hide yes)
			(effects
				(font
					(size 1.27 1.27)
				)
			)
		)
		(property "Value" "4K7R2J-2-GP"
			(at 0.064008 -3.993896 270)
			(unlocked yes)
			(layer "F.Fab")
			(hide yes)
			(effects
				(font
					(size 1.016 1.016)
					(thickness 0.1524)
				)
			)
		)
		(property "Device Type" "R402H16"
			(at 0.064008 -5.517896 270)
			(unlocked yes)
			(layer "F.Fab")
			(hide yes)
			(effects
				(font
					(size 1.016 1.016)
					(thickness 0.1524)
				)
			)
		)
		(duplicate_pad_numbers_are_jumpers no)
		(fp_line
			(start -0.508 -0.9398)
			(end -0.508 0.9398)
			(stroke
				(width 0.1524)
				(type default)
			)
			(layer "F.SilkS")
		)
		(fp_line
			(start 0.508 -0.9398)
			(end -0.508 -0.9398)
			(stroke
				(width 0.1524)
				(type default)
			)
			(layer "F.SilkS")
		)
		(fp_rect
			(start -0.508 0.9398)
			(end 0.508 -0.9398)
			(stroke
				(width 0)
				(type default)
			)
			(fill no)
			(layer "F.CrtYd")
		)
		(fp_rect
			(start -0.508 0.9398)
			(end 0.508 -0.9398)
			(stroke
				(width 0)
				(type default)
			)
			(fill no)
			(layer "F.Fab")
		)
		(pad "1" smd custom
			(at 0 -0.4445 270)
			(size 0.1397 0.1397)
			(layers "F.Cu" "F.Mask" "F.Paste")
			(net "P3V3")
			(options
				(clearance outline)
				(anchor circle)
			)
			(primitives
				(gr_poly
					(pts
						(arc
							(start -0.1778 -0.2794)
							(mid -0.249642 -0.249642)
							(end -0.2794 -0.1778)
						)
						(arc
							(start -0.2794 0.1778)
							(mid -0.249642 0.249642)
							(end -0.1778 0.2794)
						)
						(arc
							(start 0.1778 0.2794)
							(mid 0.249642 0.249642)
							(end 0.2794 0.1778)
						)
						(arc
							(start 0.2794 -0.1778)
							(mid 0.249642 -0.249642)
							(end 0.1778 -0.2794)
						)
					)
					(width 0)
					(fill yes)
				)
			)
		)
		(pad "2" smd custom
			(at 0 0.4445 270)
			(size 0.1397 0.1397)
			(layers "F.Cu" "F.Mask" "F.Paste")
			(net "SSD_PRSNT_NET9")
			(options
				(clearance outline)
				(anchor circle)
			)
			(primitives
				(gr_poly
					(pts
						(arc
							(start -0.1778 -0.2794)
							(mid -0.249642 -0.249642)
							(end -0.2794 -0.1778)
						)
						(arc
							(start -0.2794 0.1778)
							(mid -0.249642 0.249642)
							(end -0.1778 0.2794)
						)
						(arc
							(start 0.1778 0.2794)
							(mid 0.249642 0.249642)
							(end 0.2794 0.1778)
						)
						(arc
							(start 0.2794 -0.1778)
							(mid 0.249642 -0.249642)
							(end 0.1778 -0.2794)
						)
					)
					(width 0)
					(fill yes)
				)
			)
		)
	)
	(footprint ""
		(layer "F.Cu")
		(at 94.869 -26.162)
		(property "Reference" "C358"
			(at 0 0 0)
			(layer "F.SilkS")
			(hide yes)
			(effects
				(font
					(size 1.27 1.27)
				)
			)
		)
		(property "Value" "SCD1U16V2KX-3GP"
			(at 1.1811 -2.7051 0)
			(unlocked yes)
			(layer "F.Fab")
			(hide yes)
			(effects
				(font
					(size 1.016 1.016)
					(thickness 0.1524)
				)
			)
		)
		(property "Device Type" "C402H22"
			(at 1.1811 -4.2291 0)
			(unlocked yes)
			(layer "F.Fab")
			(hide yes)
			(effects
				(font
					(size 1.016 1.016)
					(thickness 0.1524)
				)
			)
		)
		(duplicate_pad_numbers_are_jumpers no)
		(fp_rect
			(start -0.4318 0.9525)
			(end 0.4318 -0.9525)
			(stroke
				(width 0)
				(type default)
			)
			(fill no)
			(layer "F.CrtYd")
		)
		(fp_rect
			(start -0.4318 0.9525)
			(end 0.4318 -0.9525)
			(stroke
				(width 0)
				(type default)
			)
			(fill no)
			(layer "F.Fab")
		)
		(pad "1" smd custom
			(at 0 -0.4445)
			(size 0.1524 0.1524)
			(layers "F.Cu" "F.Mask" "F.Paste")
			(net "P3V3_SENSE")
			(options
				(clearance outline)
				(anchor circle)
			)
			(primitives
				(gr_poly
					(pts
						(arc
							(start 0.3048 -0.2032)
							(mid 0.275042 -0.275042)
							(end 0.2032 -0.3048)
						)
						(arc
							(start -0.2032 -0.3048)
							(mid -0.275042 -0.275042)
							(end -0.3048 -0.2032)
						)
						(arc
							(start -0.3048 0.2032)
							(mid -0.275042 0.275042)
							(end -0.2032 0.3048)
						)
						(arc
							(start 0.2032 0.3048)
							(mid 0.275042 0.275042)
							(end 0.3048 0.2032)
						)
					)
					(width 0)
					(fill yes)
				)
			)
		)
		(pad "2" smd custom
			(at 0 0.4445)
			(size 0.1524 0.1524)
			(layers "F.Cu" "F.Mask" "F.Paste")
			(net "GND")
			(options
				(clearance outline)
				(anchor circle)
			)
			(primitives
				(gr_poly
					(pts
						(arc
							(start 0.3048 -0.2032)
							(mid 0.275042 -0.275042)
							(end 0.2032 -0.3048)
						)
						(arc
							(start -0.2032 -0.3048)
							(mid -0.275042 -0.275042)
							(end -0.3048 -0.2032)
						)
						(arc
							(start -0.3048 0.2032)
							(mid -0.275042 0.275042)
							(end -0.2032 0.3048)
						)
						(arc
							(start 0.2032 0.3048)
							(mid 0.275042 0.275042)
							(end 0.3048 0.2032)
						)
					)
					(width 0)
					(fill yes)
				)
			)
		)
	)
	(footprint ""
		(layer "F.Cu")
		(at 78.3844 -211.2772)
		(property "Reference" "R9968"
			(at 0 0 0)
			(layer "F.SilkS")
			(hide yes)
			(effects
				(font
					(size 1.27 1.27)
				)
			)
		)
		(property "Value" "470R2F-GP"
			(at 0.064008 -3.993896 0)
			(unlocked yes)
			(layer "F.Fab")
			(hide yes)
			(effects
				(font
					(size 1.016 1.016)
					(thickness 0.1524)
				)
			)
		)
		(property "Device Type" "R402H16"
			(at 0.064008 -5.517896 0)
			(unlocked yes)
			(layer "F.Fab")
			(hide yes)
			(effects
				(font
					(size 1.016 1.016)
					(thickness 0.1524)
				)
			)
		)
		(duplicate_pad_numbers_are_jumpers no)
		(fp_line
			(start -0.508 -0.9398)
			(end -0.508 0.9398)
			(stroke
				(width 0.1524)
				(type default)
			)
			(layer "F.SilkS")
		)
		(fp_line
			(start 0.508 -0.9398)
			(end -0.508 -0.9398)
			(stroke
				(width 0.1524)
				(type default)
			)
			(layer "F.SilkS")
		)
		(fp_rect
			(start -0.508 0.9398)
			(end 0.508 -0.9398)
			(stroke
				(width 0)
				(type default)
			)
			(fill no)
			(layer "F.CrtYd")
		)
		(fp_rect
			(start -0.508 0.9398)
			(end 0.508 -0.9398)
			(stroke
				(width 0)
				(type default)
			)
			(fill no)
			(layer "F.Fab")
		)
		(pad "1" smd custom
			(at 0 -0.4445)
			(size 0.1397 0.1397)
			(layers "F.Cu" "F.Mask" "F.Paste")
			(net "VDD_DIFF_3")
			(options
				(clearance outline)
				(anchor circle)
			)
			(primitives
				(gr_poly
					(pts
						(arc
							(start -0.1778 -0.2794)
							(mid -0.249642 -0.249642)
							(end -0.2794 -0.1778)
						)
						(arc
							(start -0.2794 0.1778)
							(mid -0.249642 0.249642)
							(end -0.1778 0.2794)
						)
						(arc
							(start 0.1778 0.2794)
							(mid 0.249642 0.249642)
							(end 0.2794 0.1778)
						)
						(arc
							(start 0.2794 -0.1778)
							(mid 0.249642 -0.249642)
							(end 0.1778 -0.2794)
						)
					)
					(width 0)
					(fill yes)
				)
			)
		)
		(pad "2" smd custom
			(at 0 0.4445)
			(size 0.1397 0.1397)
			(layers "F.Cu" "F.Mask" "F.Paste")
			(net "PE_100M_CLK2_P")
			(options
				(clearance outline)
				(anchor circle)
			)
			(primitives
				(gr_poly
					(pts
						(arc
							(start -0.1778 -0.2794)
							(mid -0.249642 -0.249642)
							(end -0.2794 -0.1778)
						)
						(arc
							(start -0.2794 0.1778)
							(mid -0.249642 0.249642)
							(end -0.1778 0.2794)
						)
						(arc
							(start 0.1778 0.2794)
							(mid 0.249642 0.249642)
							(end 0.2794 0.1778)
						)
						(arc
							(start 0.2794 -0.1778)
							(mid 0.249642 -0.249642)
							(end 0.1778 -0.2794)
						)
					)
					(width 0)
					(fill yes)
				)
			)
		)
	)
	(footprint ""
		(layer "F.Cu")
		(at 29.0322 -17.145 180)
		(property "Reference" "R417"
			(at 0 0 180)
			(layer "F.SilkS")
			(hide yes)
			(effects
				(font
					(size 1.27 1.27)
				)
			)
		)
		(property "Value" "0R2J-2-GP"
			(at 0.064008 -3.993896 180)
			(unlocked yes)
			(layer "F.Fab")
			(hide yes)
			(effects
				(font
					(size 1.016 1.016)
					(thickness 0.1524)
				)
			)
		)
		(property "Device Type" "R402H16"
			(at 0.064008 -5.517896 180)
			(unlocked yes)
			(layer "F.Fab")
			(hide yes)
			(effects
				(font
					(size 1.016 1.016)
					(thickness 0.1524)
				)
			)
		)
		(duplicate_pad_numbers_are_jumpers no)
		(fp_line
			(start 0.508 -0.9398)
			(end -0.508 -0.9398)
			(stroke
				(width 0.1524)
				(type default)
			)
			(layer "F.SilkS")
		)
		(fp_line
			(start -0.508 -0.9398)
			(end -0.508 0.9398)
			(stroke
				(width 0.1524)
				(type default)
			)
			(layer "F.SilkS")
		)
		(fp_rect
			(start -0.508 0.9398)
			(end 0.508 -0.9398)
			(stroke
				(width 0)
				(type default)
			)
			(fill no)
			(layer "F.CrtYd")
		)
		(fp_rect
			(start -0.508 0.9398)
			(end 0.508 -0.9398)
			(stroke
				(width 0)
				(type default)
			)
			(fill no)
			(layer "F.Fab")
		)
		(pad "1" smd custom
			(at 0 -0.4445 180)
			(size 0.1397 0.1397)
			(layers "F.Cu" "F.Mask" "F.Paste")
			(net "SCL_DR14_R")
			(options
				(clearance outline)
				(anchor circle)
			)
			(primitives
				(gr_poly
					(pts
						(arc
							(start -0.1778 -0.2794)
							(mid -0.249642 -0.249642)
							(end -0.2794 -0.1778)
						)
						(arc
							(start -0.2794 0.1778)
							(mid -0.249642 0.249642)
							(end -0.1778 0.2794)
						)
						(arc
							(start 0.1778 0.2794)
							(mid 0.249642 0.249642)
							(end 0.2794 0.1778)
						)
						(arc
							(start 0.2794 -0.1778)
							(mid 0.249642 -0.249642)
							(end 0.1778 -0.2794)
						)
					)
					(width 0)
					(fill yes)
				)
			)
		)
		(pad "2" smd custom
			(at 0 0.4445 180)
			(size 0.1397 0.1397)
			(layers "F.Cu" "F.Mask" "F.Paste")
			(net "SCL_DR14")
			(options
				(clearance outline)
				(anchor circle)
			)
			(primitives
				(gr_poly
					(pts
						(arc
							(start -0.1778 -0.2794)
							(mid -0.249642 -0.249642)
							(end -0.2794 -0.1778)
						)
						(arc
							(start -0.2794 0.1778)
							(mid -0.249642 0.249642)
							(end -0.1778 0.2794)
						)
						(arc
							(start 0.1778 0.2794)
							(mid 0.249642 0.249642)
							(end 0.2794 0.1778)
						)
						(arc
							(start 0.2794 -0.1778)
							(mid 0.249642 -0.249642)
							(end 0.1778 -0.2794)
						)
					)
					(width 0)
					(fill yes)
				)
			)
		)
	)
	(footprint ""
		(layer "F.Cu")
		(at 32.11703 -84.662518 180)
		(property "Reference" "SR1110"
			(at 0 0 180)
			(layer "F.SilkS")
			(hide yes)
			(effects
				(font
					(size 1.27 1.27)
				)
			)
		)
		(property "Value" "4K7R2F-GP"
			(at 0.064008 -3.993896 180)
			(unlocked yes)
			(layer "F.Fab")
			(hide yes)
			(effects
				(font
					(size 1.016 1.016)
					(thickness 0.1524)
				)
			)
		)
		(property "Device Type" "R402H16"
			(at 0.064008 -5.517896 180)
			(unlocked yes)
			(layer "F.Fab")
			(hide yes)
			(effects
				(font
					(size 1.016 1.016)
					(thickness 0.1524)
				)
			)
		)
		(duplicate_pad_numbers_are_jumpers no)
		(fp_line
			(start 0.508 -0.9398)
			(end -0.508 -0.9398)
			(stroke
				(width 0.1524)
				(type default)
			)
			(layer "F.SilkS")
		)
		(fp_line
			(start -0.508 -0.9398)
			(end -0.508 0.9398)
			(stroke
				(width 0.1524)
				(type default)
			)
			(layer "F.SilkS")
		)
		(fp_rect
			(start -0.508 0.9398)
			(end 0.508 -0.9398)
			(stroke
				(width 0)
				(type default)
			)
			(fill no)
			(layer "F.CrtYd")
		)
		(fp_rect
			(start -0.508 0.9398)
			(end 0.508 -0.9398)
			(stroke
				(width 0)
				(type default)
			)
			(fill no)
			(layer "F.Fab")
		)
		(pad "1" smd custom
			(at 0 -0.4445 180)
			(size 0.1397 0.1397)
			(layers "F.Cu" "F.Mask" "F.Paste")
			(net "DUALPORTEN#9")
			(options
				(clearance outline)
				(anchor circle)
			)
			(primitives
				(gr_poly
					(pts
						(arc
							(start -0.1778 -0.2794)
							(mid -0.249642 -0.249642)
							(end -0.2794 -0.1778)
						)
						(arc
							(start -0.2794 0.1778)
							(mid -0.249642 0.249642)
							(end -0.1778 0.2794)
						)
						(arc
							(start 0.1778 0.2794)
							(mid 0.249642 0.249642)
							(end 0.2794 0.1778)
						)
						(arc
							(start 0.2794 -0.1778)
							(mid 0.249642 -0.249642)
							(end 0.1778 -0.2794)
						)
					)
					(width 0)
					(fill yes)
				)
			)
		)
		(pad "2" smd custom
			(at 0 0.4445 180)
			(size 0.1397 0.1397)
			(layers "F.Cu" "F.Mask" "F.Paste")
			(net "GND")
			(options
				(clearance outline)
				(anchor circle)
			)
			(primitives
				(gr_poly
					(pts
						(arc
							(start -0.1778 -0.2794)
							(mid -0.249642 -0.249642)
							(end -0.2794 -0.1778)
						)
						(arc
							(start -0.2794 0.1778)
							(mid -0.249642 0.249642)
							(end -0.1778 0.2794)
						)
						(arc
							(start 0.1778 0.2794)
							(mid 0.249642 0.249642)
							(end 0.2794 0.1778)
						)
						(arc
							(start 0.2794 -0.1778)
							(mid 0.249642 -0.249642)
							(end 0.1778 -0.2794)
						)
					)
					(width 0)
					(fill yes)
				)
			)
		)
	)
	(footprint ""
		(layer "F.Cu")
		(at 82.931 -217.17 90)
		(property "Reference" "R9356"
			(at 0 0 90)
			(layer "F.SilkS")
			(hide yes)
			(effects
				(font
					(size 1.27 1.27)
				)
			)
		)
		(property "Value" "2D2R2F-GP"
			(at 0.064008 -3.993896 90)
			(unlocked yes)
			(layer "F.Fab")
			(hide yes)
			(effects
				(font
					(size 1.016 1.016)
					(thickness 0.1524)
				)
			)
		)
		(property "Device Type" "R402H16"
			(at 0.064008 -5.517896 90)
			(unlocked yes)
			(layer "F.Fab")
			(hide yes)
			(effects
				(font
					(size 1.016 1.016)
					(thickness 0.1524)
				)
			)
		)
		(duplicate_pad_numbers_are_jumpers no)
		(fp_line
			(start 0.508 -0.9398)
			(end -0.508 -0.9398)
			(stroke
				(width 0.1524)
				(type default)
			)
			(layer "F.SilkS")
		)
		(fp_line
			(start -0.508 -0.9398)
			(end -0.508 0.9398)
			(stroke
				(width 0.1524)
				(type default)
			)
			(layer "F.SilkS")
		)
		(fp_rect
			(start -0.508 0.9398)
			(end 0.508 -0.9398)
			(stroke
				(width 0)
				(type default)
			)
			(fill no)
			(layer "F.CrtYd")
		)
		(fp_rect
			(start -0.508 0.9398)
			(end 0.508 -0.9398)
			(stroke
				(width 0)
				(type default)
			)
			(fill no)
			(layer "F.Fab")
		)
		(pad "1" smd custom
			(at 0 -0.4445 90)
			(size 0.1397 0.1397)
			(layers "F.Cu" "F.Mask" "F.Paste")
			(net "VDD_DIFF_3")
			(options
				(clearance outline)
				(anchor circle)
			)
			(primitives
				(gr_poly
					(pts
						(arc
							(start -0.1778 -0.2794)
							(mid -0.249642 -0.249642)
							(end -0.2794 -0.1778)
						)
						(arc
							(start -0.2794 0.1778)
							(mid -0.249642 0.249642)
							(end -0.1778 0.2794)
						)
						(arc
							(start 0.1778 0.2794)
							(mid 0.249642 0.249642)
							(end 0.2794 0.1778)
						)
						(arc
							(start 0.2794 -0.1778)
							(mid 0.249642 -0.249642)
							(end 0.1778 -0.2794)
						)
					)
					(width 0)
					(fill yes)
				)
			)
		)
		(pad "2" smd custom
			(at 0 0.4445 90)
			(size 0.1397 0.1397)
			(layers "F.Cu" "F.Mask" "F.Paste")
			(net "VDDA_3")
			(options
				(clearance outline)
				(anchor circle)
			)
			(primitives
				(gr_poly
					(pts
						(arc
							(start -0.1778 -0.2794)
							(mid -0.249642 -0.249642)
							(end -0.2794 -0.1778)
						)
						(arc
							(start -0.2794 0.1778)
							(mid -0.249642 0.249642)
							(end -0.1778 0.2794)
						)
						(arc
							(start 0.1778 0.2794)
							(mid 0.249642 0.249642)
							(end 0.2794 0.1778)
						)
						(arc
							(start 0.2794 -0.1778)
							(mid 0.249642 -0.249642)
							(end 0.1778 -0.2794)
						)
					)
					(width 0)
					(fill yes)
				)
			)
		)
	)
	(footprint ""
		(layer "F.Cu")
		(at 25.4 -236.982 180)
		(property "Reference" "PC1254"
			(at 0 0 180)
			(layer "F.SilkS")
			(hide yes)
			(effects
				(font
					(size 1.27 1.27)
				)
			)
		)
		(property "Value" "SCD1U25V3KX-GP"
			(at 0 -2.8194 180)
			(unlocked yes)
			(layer "F.Fab")
			(hide yes)
			(effects
				(font
					(size 1.016 1.016)
					(thickness 0.1524)
				)
			)
		)
		(property "Device Type" "C603H36"
			(at 0 -4.3434 180)
			(unlocked yes)
			(layer "F.Fab")
			(hide yes)
			(effects
				(font
					(size 1.016 1.016)
					(thickness 0.1524)
				)
			)
		)
		(duplicate_pad_numbers_are_jumpers no)
		(fp_line
			(start 0.508 0)
			(end -0.508 0)
			(stroke
				(width 0.2032)
				(type default)
			)
			(layer "F.SilkS")
		)
		(fp_rect
			(start -0.5842 1.3335)
			(end 0.5842 -1.3335)
			(stroke
				(width 0)
				(type default)
			)
			(fill no)
			(layer "F.CrtYd")
		)
		(fp_rect
			(start -0.5842 1.3335)
			(end 0.5842 -1.3335)
			(stroke
				(width 0)
				(type default)
			)
			(fill no)
			(layer "F.Fab")
		)
		(pad "1" smd custom
			(at 0 -0.762 180)
			(size 0.2159 0.2159)
			(layers "F.Cu" "F.Mask" "F.Paste")
			(net "P3V3")
			(options
				(clearance outline)
				(anchor circle)
			)
			(primitives
				(gr_poly
					(pts
						(arc
							(start -0.3302 -0.4318)
							(mid -0.402042 -0.402042)
							(end -0.4318 -0.3302)
						)
						(arc
							(start -0.4318 0.3302)
							(mid -0.402042 0.402042)
							(end -0.3302 0.4318)
						)
						(arc
							(start 0.3302 0.4318)
							(mid 0.402042 0.402042)
							(end 0.4318 0.3302)
						)
						(arc
							(start 0.4318 -0.3302)
							(mid 0.402042 -0.402042)
							(end 0.3302 -0.4318)
						)
					)
					(width 0)
					(fill yes)
				)
			)
		)
		(pad "2" smd custom
			(at 0 0.762 180)
			(size 0.2159 0.2159)
			(layers "F.Cu" "F.Mask" "F.Paste")
			(net "GND")
			(options
				(clearance outline)
				(anchor circle)
			)
			(primitives
				(gr_poly
					(pts
						(arc
							(start -0.3302 -0.4318)
							(mid -0.402042 -0.402042)
							(end -0.4318 -0.3302)
						)
						(arc
							(start -0.4318 0.3302)
							(mid -0.402042 0.402042)
							(end -0.3302 0.4318)
						)
						(arc
							(start 0.3302 0.4318)
							(mid 0.402042 0.402042)
							(end 0.4318 0.3302)
						)
						(arc
							(start 0.4318 -0.3302)
							(mid 0.402042 -0.402042)
							(end 0.3302 -0.4318)
						)
					)
					(width 0)
					(fill yes)
				)
			)
		)
	)
	(footprint ""
		(layer "F.Cu")
		(at 232.791 -436.626 90)
		(property "Reference" "PC1279"
			(at 0 0 90)
			(layer "F.SilkS")
			(hide yes)
			(effects
				(font
					(size 1.27 1.27)
				)
			)
		)
		(property "Value" "SC3300P50V2KX-1GP"
			(at 1.1811 -2.7051 90)
			(unlocked yes)
			(layer "F.Fab")
			(hide yes)
			(effects
				(font
					(size 1.016 1.016)
					(thickness 0.1524)
				)
			)
		)
		(property "Device Type" "C402H22"
			(at 1.1811 -4.2291 90)
			(unlocked yes)
			(layer "F.Fab")
			(hide yes)
			(effects
				(font
					(size 1.016 1.016)
					(thickness 0.1524)
				)
			)
		)
		(duplicate_pad_numbers_are_jumpers no)
		(fp_rect
			(start -0.4318 0.9525)
			(end 0.4318 -0.9525)
			(stroke
				(width 0)
				(type default)
			)
			(fill no)
			(layer "F.CrtYd")
		)
		(fp_rect
			(start -0.4318 0.9525)
			(end 0.4318 -0.9525)
			(stroke
				(width 0)
				(type default)
			)
			(fill no)
			(layer "F.Fab")
		)
		(pad "1" smd custom
			(at 0 -0.4445 90)
			(size 0.1524 0.1524)
			(layers "F.Cu" "F.Mask" "F.Paste")
			(net "P3V3_SS")
			(options
				(clearance outline)
				(anchor circle)
			)
			(primitives
				(gr_poly
					(pts
						(arc
							(start 0.3048 -0.2032)
							(mid 0.275042 -0.275042)
							(end 0.2032 -0.3048)
						)
						(arc
							(start -0.2032 -0.3048)
							(mid -0.275042 -0.275042)
							(end -0.3048 -0.2032)
						)
						(arc
							(start -0.3048 0.2032)
							(mid -0.275042 0.275042)
							(end -0.2032 0.3048)
						)
						(arc
							(start 0.2032 0.3048)
							(mid 0.275042 0.275042)
							(end 0.3048 0.2032)
						)
					)
					(width 0)
					(fill yes)
				)
			)
		)
		(pad "2" smd custom
			(at 0 0.4445 90)
			(size 0.1524 0.1524)
			(layers "F.Cu" "F.Mask" "F.Paste")
			(net "AGND_P3V3")
			(options
				(clearance outline)
				(anchor circle)
			)
			(primitives
				(gr_poly
					(pts
						(arc
							(start 0.3048 -0.2032)
							(mid 0.275042 -0.275042)
							(end 0.2032 -0.3048)
						)
						(arc
							(start -0.2032 -0.3048)
							(mid -0.275042 -0.275042)
							(end -0.3048 -0.2032)
						)
						(arc
							(start -0.3048 0.2032)
							(mid -0.275042 0.275042)
							(end -0.2032 0.3048)
						)
						(arc
							(start 0.2032 0.3048)
							(mid 0.275042 0.275042)
							(end 0.3048 0.2032)
						)
					)
					(width 0)
					(fill yes)
				)
			)
		)
	)
	(footprint ""
		(layer "F.Cu")
		(at 106.045 -434.848 180)
		(property "Reference" "C110"
			(at 0 0 180)
			(layer "F.SilkS")
			(hide yes)
			(effects
				(font
					(size 1.27 1.27)
				)
			)
		)
		(property "Value" "SC1KP50V2KX-1GP"
			(at 1.1811 -2.7051 180)
			(unlocked yes)
			(layer "F.Fab")
			(hide yes)
			(effects
				(font
					(size 1.016 1.016)
					(thickness 0.1524)
				)
			)
		)
		(property "Device Type" "C402H22"
			(at 1.1811 -4.2291 180)
			(unlocked yes)
			(layer "F.Fab")
			(hide yes)
			(effects
				(font
					(size 1.016 1.016)
					(thickness 0.1524)
				)
			)
		)
		(duplicate_pad_numbers_are_jumpers no)
		(fp_rect
			(start -0.4318 0.9525)
			(end 0.4318 -0.9525)
			(stroke
				(width 0)
				(type default)
			)
			(fill no)
			(layer "F.CrtYd")
		)
		(fp_rect
			(start -0.4318 0.9525)
			(end 0.4318 -0.9525)
			(stroke
				(width 0)
				(type default)
			)
			(fill no)
			(layer "F.Fab")
		)
		(pad "1" smd custom
			(at 0 -0.4445 180)
			(size 0.1524 0.1524)
			(layers "F.Cu" "F.Mask" "F.Paste")
			(net "SSD_PRSNT0")
			(options
				(clearance outline)
				(anchor circle)
			)
			(primitives
				(gr_poly
					(pts
						(arc
							(start 0.3048 -0.2032)
							(mid 0.275042 -0.275042)
							(end 0.2032 -0.3048)
						)
						(arc
							(start -0.2032 -0.3048)
							(mid -0.275042 -0.275042)
							(end -0.3048 -0.2032)
						)
						(arc
							(start -0.3048 0.2032)
							(mid -0.275042 0.275042)
							(end -0.2032 0.3048)
						)
						(arc
							(start 0.2032 0.3048)
							(mid 0.275042 0.275042)
							(end 0.3048 0.2032)
						)
					)
					(width 0)
					(fill yes)
				)
			)
		)
		(pad "2" smd custom
			(at 0 0.4445 180)
			(size 0.1524 0.1524)
			(layers "F.Cu" "F.Mask" "F.Paste")
			(net "GND")
			(options
				(clearance outline)
				(anchor circle)
			)
			(primitives
				(gr_poly
					(pts
						(arc
							(start 0.3048 -0.2032)
							(mid 0.275042 -0.275042)
							(end 0.2032 -0.3048)
						)
						(arc
							(start -0.2032 -0.3048)
							(mid -0.275042 -0.275042)
							(end -0.3048 -0.2032)
						)
						(arc
							(start -0.3048 0.2032)
							(mid -0.275042 0.275042)
							(end -0.2032 0.3048)
						)
						(arc
							(start 0.2032 0.3048)
							(mid 0.275042 0.275042)
							(end 0.3048 0.2032)
						)
					)
					(width 0)
					(fill yes)
				)
			)
		)
	)
	(footprint ""
		(layer "F.Cu")
		(at 52.2224 -244.088158 -90)
		(property "Reference" "R9830"
			(at 0 0 270)
			(layer "F.SilkS")
			(hide yes)
			(effects
				(font
					(size 1.27 1.27)
				)
			)
		)
		(property "Value" "0R2J-2-GP"
			(at 0.064008 -3.993896 270)
			(unlocked yes)
			(layer "F.Fab")
			(hide yes)
			(effects
				(font
					(size 1.016 1.016)
					(thickness 0.1524)
				)
			)
		)
		(property "Device Type" "R402H16"
			(at 0.064008 -5.517896 270)
			(unlocked yes)
			(layer "F.Fab")
			(hide yes)
			(effects
				(font
					(size 1.016 1.016)
					(thickness 0.1524)
				)
			)
		)
		(duplicate_pad_numbers_are_jumpers no)
		(fp_line
			(start -0.508 -0.9398)
			(end -0.508 0.9398)
			(stroke
				(width 0.1524)
				(type default)
			)
			(layer "F.SilkS")
		)
		(fp_line
			(start 0.508 -0.9398)
			(end -0.508 -0.9398)
			(stroke
				(width 0.1524)
				(type default)
			)
			(layer "F.SilkS")
		)
		(fp_rect
			(start -0.508 0.9398)
			(end 0.508 -0.9398)
			(stroke
				(width 0)
				(type default)
			)
			(fill no)
			(layer "F.CrtYd")
		)
		(fp_rect
			(start -0.508 0.9398)
			(end 0.508 -0.9398)
			(stroke
				(width 0)
				(type default)
			)
			(fill no)
			(layer "F.Fab")
		)
		(pad "1" smd custom
			(at 0 -0.4445 270)
			(size 0.1397 0.1397)
			(layers "F.Cu" "F.Mask" "F.Paste")
			(net "ATTN_LED_DR7_R")
			(options
				(clearance outline)
				(anchor circle)
			)
			(primitives
				(gr_poly
					(pts
						(arc
							(start -0.1778 -0.2794)
							(mid -0.249642 -0.249642)
							(end -0.2794 -0.1778)
						)
						(arc
							(start -0.2794 0.1778)
							(mid -0.249642 0.249642)
							(end -0.1778 0.2794)
						)
						(arc
							(start 0.1778 0.2794)
							(mid 0.249642 0.249642)
							(end 0.2794 0.1778)
						)
						(arc
							(start 0.2794 -0.1778)
							(mid 0.249642 -0.249642)
							(end 0.1778 -0.2794)
						)
					)
					(width 0)
					(fill yes)
				)
			)
		)
		(pad "2" smd custom
			(at 0 0.4445 270)
			(size 0.1397 0.1397)
			(layers "F.Cu" "F.Mask" "F.Paste")
			(net "ATTN_LED_DR7_N")
			(options
				(clearance outline)
				(anchor circle)
			)
			(primitives
				(gr_poly
					(pts
						(arc
							(start -0.1778 -0.2794)
							(mid -0.249642 -0.249642)
							(end -0.2794 -0.1778)
						)
						(arc
							(start -0.2794 0.1778)
							(mid -0.249642 0.249642)
							(end -0.1778 0.2794)
						)
						(arc
							(start 0.1778 0.2794)
							(mid 0.249642 0.249642)
							(end 0.2794 0.1778)
						)
						(arc
							(start 0.2794 -0.1778)
							(mid 0.249642 -0.249642)
							(end 0.1778 -0.2794)
						)
					)
					(width 0)
					(fill yes)
				)
			)
		)
	)
	(footprint ""
		(layer "F.Cu")
		(at 78.232 -154.178)
		(property "Reference" "SR977"
			(at 0 0 0)
			(layer "F.SilkS")
			(hide yes)
			(effects
				(font
					(size 1.27 1.27)
				)
			)
		)
		(property "Value" "2KR2F-3-GP"
			(at 0.064008 -3.993896 0)
			(unlocked yes)
			(layer "F.Fab")
			(hide yes)
			(effects
				(font
					(size 1.016 1.016)
					(thickness 0.1524)
				)
			)
		)
		(property "Device Type" "R402H16"
			(at 0.064008 -5.517896 0)
			(unlocked yes)
			(layer "F.Fab")
			(hide yes)
			(effects
				(font
					(size 1.016 1.016)
					(thickness 0.1524)
				)
			)
		)
		(duplicate_pad_numbers_are_jumpers no)
		(fp_line
			(start -0.508 -0.9398)
			(end -0.508 0.9398)
			(stroke
				(width 0.1524)
				(type default)
			)
			(layer "F.SilkS")
		)
		(fp_line
			(start 0.508 -0.9398)
			(end -0.508 -0.9398)
			(stroke
				(width 0.1524)
				(type default)
			)
			(layer "F.SilkS")
		)
		(fp_rect
			(start -0.508 0.9398)
			(end 0.508 -0.9398)
			(stroke
				(width 0)
				(type default)
			)
			(fill no)
			(layer "F.CrtYd")
		)
		(fp_rect
			(start -0.508 0.9398)
			(end 0.508 -0.9398)
			(stroke
				(width 0)
				(type default)
			)
			(fill no)
			(layer "F.Fab")
		)
		(pad "1" smd custom
			(at 0 -0.4445)
			(size 0.1397 0.1397)
			(layers "F.Cu" "F.Mask" "F.Paste")
			(net "P3V3")
			(options
				(clearance outline)
				(anchor circle)
			)
			(primitives
				(gr_poly
					(pts
						(arc
							(start -0.1778 -0.2794)
							(mid -0.249642 -0.249642)
							(end -0.2794 -0.1778)
						)
						(arc
							(start -0.2794 0.1778)
							(mid -0.249642 0.249642)
							(end -0.1778 0.2794)
						)
						(arc
							(start 0.1778 0.2794)
							(mid 0.249642 0.249642)
							(end 0.2794 0.1778)
						)
						(arc
							(start 0.2794 -0.1778)
							(mid 0.249642 -0.249642)
							(end 0.1778 -0.2794)
						)
					)
					(width 0)
					(fill yes)
				)
			)
		)
		(pad "2" smd custom
			(at 0 0.4445)
			(size 0.1397 0.1397)
			(layers "F.Cu" "F.Mask" "F.Paste")
			(net "SCL_DR3")
			(options
				(clearance outline)
				(anchor circle)
			)
			(primitives
				(gr_poly
					(pts
						(arc
							(start -0.1778 -0.2794)
							(mid -0.249642 -0.249642)
							(end -0.2794 -0.1778)
						)
						(arc
							(start -0.2794 0.1778)
							(mid -0.249642 0.249642)
							(end -0.1778 0.2794)
						)
						(arc
							(start 0.1778 0.2794)
							(mid 0.249642 0.249642)
							(end 0.2794 0.1778)
						)
						(arc
							(start 0.2794 -0.1778)
							(mid 0.249642 -0.249642)
							(end 0.1778 -0.2794)
						)
					)
					(width 0)
					(fill yes)
				)
			)
		)
	)
	(footprint ""
		(layer "F.Cu")
		(at 259.899912 -409.949904 90)
		(property "Reference" "CN7"
			(at 0 0 90)
			(layer "F.SilkS")
			(hide yes)
			(effects
				(font
					(size 1.27 1.27)
				)
			)
		)
		(property "Value" "AMP-CONN60-5-GP"
			(at -32.935418 -14.620748 90)
			(unlocked yes)
			(layer "F.Fab")
			(hide yes)
			(effects
				(font
					(size 1.016 1.016)
					(thickness 0.1524)
				)
			)
		)
		(property "Device Type" "GPCE54362413HR"
			(at -32.935418 -16.144748 90)
			(unlocked yes)
			(layer "F.Fab")
			(hide yes)
			(effects
				(font
					(size 1.016 1.016)
					(thickness 0.1524)
				)
			)
		)
		(duplicate_pad_numbers_are_jumpers no)
		(fp_line
			(start -0.5334 -10.7696)
			(end -46.0502 -10.7696)
			(stroke
				(width 0.1524)
				(type default)
			)
			(layer "F.SilkS")
		)
		(fp_line
			(start -46.0502 -10.7696)
			(end -46.0502 -4.0132)
			(stroke
				(width 0.1524)
				(type default)
			)
			(layer "F.SilkS")
		)
		(fp_line
			(start 0.7874 -8.3058)
			(end -0.5334 -8.3058)
			(stroke
				(width 0.1524)
				(type default)
			)
			(layer "F.SilkS")
		)
		(fp_line
			(start -0.5334 -8.3058)
			(end -0.5334 -10.7696)
			(stroke
				(width 0.1524)
				(type default)
			)
			(layer "F.SilkS")
		)
		(fp_line
			(start 0.534924 -7.504938)
			(end 0.534924 -0.249936)
			(stroke
				(width 0.1524)
				(type default)
			)
			(layer "F.SilkS")
		)
		(fp_line
			(start 2.0066 -7.3533)
			(end 1.6256 -7.3533)
			(stroke
				(width 0.3302)
				(type default)
			)
			(layer "F.SilkS")
		)
		(fp_line
			(start 16.4465 -7.2644)
			(end 0.7874 -7.2644)
			(stroke
				(width 0.1524)
				(type default)
			)
			(layer "F.SilkS")
		)
		(fp_line
			(start 0.7874 -7.2644)
			(end 0.7874 -8.3058)
			(stroke
				(width 0.1524)
				(type default)
			)
			(layer "F.SilkS")
		)
		(fp_line
			(start 24.384 -4.0132)
			(end 16.4465 -4.0132)
			(stroke
				(width 0.1524)
				(type default)
			)
			(layer "F.SilkS")
		)
		(fp_line
			(start 16.4465 -4.0132)
			(end 16.4465 -7.2644)
			(stroke
				(width 0.1524)
				(type default)
			)
			(layer "F.SilkS")
		)
		(fp_line
			(start -46.0502 -4.0132)
			(end -54.2798 -4.0132)
			(stroke
				(width 0.1524)
				(type default)
			)
			(layer "F.SilkS")
		)
		(fp_line
			(start -54.2798 -4.0132)
			(end -54.2798 3.599942)
			(stroke
				(width 0.1524)
				(type default)
			)
			(layer "F.SilkS")
		)
		(fp_line
			(start 0.534924 -0.249936)
			(end 0.78486 0)
			(stroke
				(width 0.1524)
				(type default)
			)
			(layer "F.SilkS")
		)
		(fp_line
			(start -0.534924 -0.249936)
			(end -0.534924 -7.504938)
			(stroke
				(width 0.1524)
				(type default)
			)
			(layer "F.SilkS")
		)
		(fp_line
			(start 0.78486 0)
			(end 15.88008 0)
			(stroke
				(width 0.1524)
				(type default)
			)
			(layer "F.SilkS")
		)
		(fp_line
			(start -0.78486 0)
			(end -0.534924 -0.249936)
			(stroke
				(width 0.1524)
				(type default)
			)
			(layer "F.SilkS")
		)
		(fp_line
			(start -45.779944 0)
			(end -0.78486 0)
			(stroke
				(width 0.1524)
				(type default)
			)
			(layer "F.SilkS")
		)
		(fp_line
			(start 17.130014 1.249934)
			(end 17.130014 2.599944)
			(stroke
				(width 0.1524)
				(type default)
			)
			(layer "F.SilkS")
		)
		(fp_line
			(start 17.130014 2.599944)
			(end 18.130012 3.599942)
			(stroke
				(width 0.1524)
				(type default)
			)
			(layer "F.SilkS")
		)
		(fp_line
			(start -47.029878 2.599944)
			(end -47.029878 1.249934)
			(stroke
				(width 0.1524)
				(type default)
			)
			(layer "F.SilkS")
		)
		(fp_line
			(start 24.384 3.599942)
			(end 24.384 -4.0132)
			(stroke
				(width 0.1524)
				(type default)
			)
			(layer "F.SilkS")
		)
		(fp_line
			(start 18.130012 3.599942)
			(end 24.384 3.599942)
			(stroke
				(width 0.1524)
				(type default)
			)
			(layer "F.SilkS")
		)
		(fp_line
			(start -48.029876 3.599942)
			(end -47.029878 2.599944)
			(stroke
				(width 0.1524)
				(type default)
			)
			(layer "F.SilkS")
		)
		(fp_line
			(start -54.2798 3.599942)
			(end -48.029876 3.599942)
			(stroke
				(width 0.1524)
				(type default)
			)
			(layer "F.SilkS")
		)
		(fp_arc
			(start -0.534924 -7.504938)
			(mid 0 -8.039862)
			(end 0.534924 -7.504938)
			(stroke
				(width 0.1524)
				(type default)
			)
			(layer "F.SilkS")
		)
		(fp_arc
			(start 15.88008 0)
			(mid 16.763917 0.366097)
			(end 17.130014 1.249934)
			(stroke
				(width 0.1524)
				(type default)
			)
			(layer "F.SilkS")
		)
		(fp_arc
			(start -47.029878 1.249934)
			(mid -46.663781 0.366097)
			(end -45.779944 0)
			(stroke
				(width 0.1524)
				(type default)
			)
			(layer "F.SilkS")
		)
		(fp_poly
			(pts
				(xy 1.8288 -7.3406) (xy 1.3208 -7.8486) (xy 2.3368 -7.8486)
			)
			(stroke
				(width 0)
				(type default)
			)
			(fill yes)
			(layer "F.SilkS")
		)
		(fp_poly
			(pts
				(xy -5.144516 -7.006082) (xy -5.144516 -0.503936) (xy -0.775716 -0.503936) (xy -0.775716 -7.006082)
			)
			(stroke
				(width 0)
				(type default)
			)
			(fill yes)
			(layer "F.Paste")
		)
		(fp_poly
			(pts
				(xy -10.345166 -0.503682) (xy -5.855716 -0.503682) (xy -5.855716 -7.006082) (xy -10.345166 -7.006082)
			)
			(stroke
				(width 0)
				(type default)
			)
			(fill yes)
			(layer "F.Paste")
		)
		(fp_poly
			(pts
				(xy -15.304516 -0.503682) (xy -10.815066 -0.503682) (xy -10.815066 -7.006082) (xy -15.304516 -7.006082)
			)
			(stroke
				(width 0)
				(type default)
			)
			(fill yes)
			(layer "F.Paste")
		)
		(fp_poly
			(pts
				(xy -20.505166 -0.503682) (xy -16.015716 -0.503682) (xy -16.015716 -7.006082) (xy -20.505166 -7.006082)
			)
			(stroke
				(width 0)
				(type default)
			)
			(fill yes)
			(layer "F.Paste")
		)
		(fp_poly
			(pts
				(xy -25.464516 -0.503682) (xy -20.975066 -0.503682) (xy -20.975066 -7.006082) (xy -25.464516 -7.006082)
			)
			(stroke
				(width 0)
				(type default)
			)
			(fill yes)
			(layer "F.Paste")
		)
		(fp_poly
			(pts
				(xy -30.665166 -0.503682) (xy -26.175716 -0.503682) (xy -26.175716 -7.006082) (xy -30.665166 -7.006082)
			)
			(stroke
				(width 0)
				(type default)
			)
			(fill yes)
			(layer "F.Paste")
		)
		(fp_poly
			(pts
				(xy -35.624516 -0.503682) (xy -31.135066 -0.503682) (xy -31.135066 -7.006082) (xy -35.624516 -7.006082)
			)
			(stroke
				(width 0)
				(type default)
			)
			(fill yes)
			(layer "F.Paste")
		)
		(fp_poly
			(pts
				(xy -40.825166 -0.503682) (xy -36.335716 -0.503682) (xy -36.335716 -7.006082) (xy -40.825166 -7.006082)
			)
			(stroke
				(width 0)
				(type default)
			)
			(fill yes)
			(layer "F.Paste")
		)
		(fp_poly
			(pts
				(xy -45.784516 -0.503682) (xy -41.295066 -0.503682) (xy -41.295066 -7.006082) (xy -45.784516 -7.006082)
			)
			(stroke
				(width 0)
				(type default)
			)
			(fill yes)
			(layer "F.Paste")
		)
		(fp_poly
			(pts
				(xy -5.144516 -0.503936) (xy -0.775716 -0.503936) (xy -0.775716 -7.006082) (xy -5.144516 -7.006082)
			)
			(stroke
				(width 0)
				(type default)
			)
			(fill yes)
			(layer "B.Paste")
		)
		(fp_poly
			(pts
				(xy -10.345166 -0.503682) (xy -5.855716 -0.503682) (xy -5.855716 -7.006082) (xy -10.345166 -7.006082)
			)
			(stroke
				(width 0)
				(type default)
			)
			(fill yes)
			(layer "B.Paste")
		)
		(fp_poly
			(pts
				(xy -15.304516 -0.503682) (xy -10.815066 -0.503682) (xy -10.815066 -7.006082) (xy -15.304516 -7.006082)
			)
			(stroke
				(width 0)
				(type default)
			)
			(fill yes)
			(layer "B.Paste")
		)
		(fp_poly
			(pts
				(xy -20.505166 -0.503682) (xy -16.015716 -0.503682) (xy -16.015716 -7.006082) (xy -20.505166 -7.006082)
			)
			(stroke
				(width 0)
				(type default)
			)
			(fill yes)
			(layer "B.Paste")
		)
		(fp_poly
			(pts
				(xy -25.464516 -0.503682) (xy -20.975066 -0.503682) (xy -20.975066 -7.006082) (xy -25.464516 -7.006082)
			)
			(stroke
				(width 0)
				(type default)
			)
			(fill yes)
			(layer "B.Paste")
		)
		(fp_poly
			(pts
				(xy -30.665166 -0.503682) (xy -26.175716 -0.503682) (xy -26.175716 -7.006082) (xy -30.665166 -7.006082)
			)
			(stroke
				(width 0)
				(type default)
			)
			(fill yes)
			(layer "B.Paste")
		)
		(fp_poly
			(pts
				(xy -35.624516 -0.503682) (xy -31.135066 -0.503682) (xy -31.135066 -7.006082) (xy -35.624516 -7.006082)
			)
			(stroke
				(width 0)
				(type default)
			)
			(fill yes)
			(layer "B.Paste")
		)
		(fp_poly
			(pts
				(xy -40.825166 -0.503682) (xy -36.335716 -0.503682) (xy -36.335716 -7.006082) (xy -40.825166 -7.006082)
			)
			(stroke
				(width 0)
				(type default)
			)
			(fill yes)
			(layer "B.Paste")
		)
		(fp_poly
			(pts
				(xy -45.784516 -0.503682) (xy -41.295066 -0.503682) (xy -41.295066 -7.006082) (xy -45.784516 -7.006082)
			)
			(stroke
				(width 0)
				(type default)
			)
			(fill yes)
			(layer "B.Paste")
		)
		(fp_poly
			(pts
				(xy -48.9204 15.24) (xy -48.9204 3.7338) (xy -54.0258 3.7338) (xy -54.0258 -3.7592) (xy -45.4025 -3.7592)
				(xy -45.4025 -7.0104) (xy 15.9893 -7.0104) (xy 15.9893 -3.7592) (xy 24.13 -3.7592) (xy 24.13 3.7338)
				(xy 20.1676 3.7338) (xy 20.1676 15.24)
			)
			(stroke
				(width 0)
				(type default)
			)
			(fill no)
			(layer "B.CrtYd")
		)
		(fp_poly
			(pts
				(xy -49.4284 15.748) (xy -49.4284 4.2418) (xy -54.5338 4.2418) (xy -54.5338 -4.2672) (xy -46.3042 -4.2672)
				(xy -46.3042 -11.0236) (xy -0.2794 -11.0236) (xy -0.2794 -8.5598) (xy 1.0414 -8.5598) (xy 1.0414 -7.5184)
				(xy 16.7005 -7.5184) (xy 16.7005 -4.2672) (xy 24.638 -4.2672) (xy 24.638 4.2418) (xy 20.6756 4.2418)
				(xy 20.6756 15.748) (xy -14.94282 15.748) (xy -14.94282 15.24) (xy 20.1676 15.24) (xy 20.1676 3.7338)
				(xy 24.13 3.7338) (xy 24.13 -3.7592) (xy 15.9893 -3.7592) (xy 15.9893 -7.0104) (xy -45.4025 -7.0104)
				(xy -45.4025 -3.7592) (xy -54.0258 -3.7592) (xy -54.0258 3.7338) (xy -48.9204 3.7338) (xy -48.9204 15.24)
				(xy -14.9479 15.24) (xy -14.9479 15.748)
			)
			(stroke
				(width 0)
				(type default)
			)
			(fill no)
			(layer "B.CrtYd")
		)
		(fp_poly
			(pts
				(xy -48.9204 15.24) (xy -48.9204 3.7338) (xy -54.0258 3.7338) (xy -54.0258 -3.7592) (xy -45.4025 -3.7592)
				(xy -45.4025 -7.0104) (xy 15.9893 -7.0104) (xy 15.9893 -3.7592) (xy 24.13 -3.7592) (xy 24.13 3.7338)
				(xy 20.1676 3.7338) (xy 20.1676 15.24)
			)
			(stroke
				(width 0)
				(type default)
			)
			(fill no)
			(layer "F.CrtYd")
		)
		(fp_poly
			(pts
				(xy -49.4284 15.748) (xy -49.4284 4.2418) (xy -54.5338 4.2418) (xy -54.5338 -4.2672) (xy -46.3042 -4.2672)
				(xy -46.3042 -11.0236) (xy -0.2794 -11.0236) (xy -0.2794 -8.5598) (xy 1.0414 -8.5598) (xy 1.0414 -7.5184)
				(xy 16.7005 -7.5184) (xy 16.7005 -4.2672) (xy 24.638 -4.2672) (xy 24.638 4.2418) (xy 20.6756 4.2418)
				(xy 20.6756 15.748) (xy -14.94282 15.748) (xy -14.94282 15.24) (xy 20.1676 15.24) (xy 20.1676 3.7338)
				(xy 24.13 3.7338) (xy 24.13 -3.7592) (xy 15.9893 -3.7592) (xy 15.9893 -7.0104) (xy -45.4025 -7.0104)
				(xy -45.4025 -3.7592) (xy -54.0258 -3.7592) (xy -54.0258 3.7338) (xy -48.9204 3.7338) (xy -48.9204 15.24)
				(xy -14.9479 15.24) (xy -14.9479 15.748)
			)
			(stroke
				(width 0)
				(type default)
			)
			(fill no)
			(layer "F.CrtYd")
		)
		(fp_poly
			(pts
				(xy -49.4284 15.748) (xy -49.4284 4.2418) (xy -54.5338 4.2418) (xy -54.5338 -4.2672) (xy -46.3042 -4.2672)
				(xy -46.3042 -11.0236) (xy -0.2794 -11.0236) (xy -0.2794 -8.5598) (xy 1.0414 -8.5598) (xy 1.0414 -7.5184)
				(xy 16.7005 -7.5184) (xy 16.7005 -4.2672) (xy 24.638 -4.2672) (xy 24.638 4.2418) (xy 20.6756 4.2418)
				(xy 20.6756 15.748)
			)
			(stroke
				(width 0)
				(type default)
			)
			(fill no)
			(layer "B.Fab")
		)
		(fp_poly
			(pts
				(xy -49.4284 15.748) (xy -49.4284 4.2418) (xy -54.5338 4.2418) (xy -54.5338 -4.2672) (xy -46.3042 -4.2672)
				(xy -46.3042 -11.0236) (xy -0.2794 -11.0236) (xy -0.2794 -8.5598) (xy 1.0414 -8.5598) (xy 1.0414 -7.5184)
				(xy 16.7005 -7.5184) (xy 16.7005 -4.2672) (xy 24.638 -4.2672) (xy 24.638 4.2418) (xy 20.6756 4.2418)
				(xy 20.6756 15.748)
			)
			(stroke
				(width 0)
				(type default)
			)
			(fill no)
			(layer "F.Fab")
		)
		(fp_text user "Slit"
			(at -17.4117 4.739386 90)
			(unlocked yes)
			(layer "F.SilkS")
			(effects
				(font
					(size 0.635 0.635)
					(thickness 0.1524)
				)
				(justify left)
			)
		)
		(fp_text user "02 Do not mirror"
			(at -25.019 6.993636 90)
			(unlocked yes)
			(layer "F.Fab")
			(effects
				(font
					(size 1.016 1.016)
					(thickness 0.1524)
				)
				(justify left)
			)
		)
		(pad "" np_thru_hole circle
			(at -50.279808 0 90)
			(size 0.254 0.254)
			(drill 3.7084)
			(layers "*.Cu" "*.Mask")
			(clearance 2.0828)
			(thermal_gap 2.0828)
		)
		(pad "" np_thru_hole circle
			(at 20.379944 0 90)
			(size 0.254 0.254)
			(drill 3.7084)
			(layers "*.Cu" "*.Mask")
			(clearance 2.0828)
			(thermal_gap 2.0828)
		)
		(pad "P1" smd rect
			(at -42.164 -8.377682 90)
			(size 0.0254 0.0254)
			(layers "F.Cu" "F.Mask" "F.Paste")
			(net "P12V")
		)
		(pad "P2" smd custom
			(at -41.060116 -8.377682 90)
			(size 2.3622 2.3622)
			(layers "F.Cu" "F.Mask" "F.Paste")
			(net "P12V")
			(options
				(clearance outline)
				(anchor circle)
			)
			(primitives
				(gr_poly
					(pts
						(xy -4.7244 5.0038) (xy -4.7244 -5.0038) (xy 4.7244 -5.0038) (xy 4.7244 5.0038) (xy 0.23495 5.0038)
						(xy 0.23495 -1.4986) (xy -0.23495 -1.4986) (xy -0.23495 5.0038)
					)
					(width 0)
					(fill yes)
				)
			)
		)
		(pad "P3" smd rect
			(at -39.878 -8.377682 90)
			(size 0.0254 0.0254)
			(layers "F.Cu" "F.Mask" "F.Paste")
			(net "P12V")
		)
		(pad "P4" smd rect
			(at -38.862 -8.377682 90)
			(size 0.0254 0.0254)
			(layers "F.Cu" "F.Mask" "F.Paste")
			(net "P12V")
		)
		(pad "P5" smd rect
			(at -32.004 -8.377682 90)
			(size 0.0254 0.0254)
			(layers "F.Cu" "F.Mask" "F.Paste")
			(net "P12V")
		)
		(pad "P6" smd custom
			(at -30.900116 -8.377682 90)
			(size 2.3622 2.3622)
			(layers "F.Cu" "F.Mask" "F.Paste")
			(net "P12V")
			(options
				(clearance outline)
				(anchor circle)
			)
			(primitives
				(gr_poly
					(pts
						(xy -4.7244 5.0038) (xy -4.7244 -5.0038) (xy 4.7244 -5.0038) (xy 4.7244 5.0038) (xy 0.23495 5.0038)
						(xy 0.23495 -1.4986) (xy -0.23495 -1.4986) (xy -0.23495 5.0038)
					)
					(width 0)
					(fill yes)
				)
			)
		)
		(pad "P7" smd rect
			(at -29.718 -8.377682 90)
			(size 0.0254 0.0254)
			(layers "F.Cu" "F.Mask" "F.Paste")
			(net "P12V")
		)
		(pad "P8" smd rect
			(at -28.702 -8.377682 90)
			(size 0.0254 0.0254)
			(layers "F.Cu" "F.Mask" "F.Paste")
			(net "P12V")
		)
		(pad "P9" smd rect
			(at -22.098 -8.377682 90)
			(size 0.0254 0.0254)
			(layers "F.Cu" "F.Mask" "F.Paste")
			(net "GND")
		)
		(pad "P10" smd custom
			(at -20.740116 -8.377682 90)
			(size 2.3622 2.3622)
			(layers "F.Cu" "F.Mask" "F.Paste")
			(net "GND")
			(options
				(clearance outline)
				(anchor circle)
			)
			(primitives
				(gr_poly
					(pts
						(xy -4.7244 5.0038) (xy -4.7244 -5.0038) (xy 4.7244 -5.0038) (xy 4.7244 5.0038) (xy 0.23495 5.0038)
						(xy 0.23495 -1.4986) (xy -0.23495 -1.4986) (xy -0.23495 5.0038)
					)
					(width 0)
					(fill yes)
				)
			)
		)
		(pad "P11" smd rect
			(at -19.558 -8.377682 90)
			(size 0.0254 0.0254)
			(layers "F.Cu" "F.Mask" "F.Paste")
			(net "GND")
		)
		(pad "P12" smd rect
			(at -18.542 -8.377682 90)
			(size 0.0254 0.0254)
			(layers "F.Cu" "F.Mask" "F.Paste")
			(net "GND")
		)
		(pad "P13" smd rect
			(at -11.938 -8.377682 90)
			(size 0.0254 0.0254)
			(layers "F.Cu" "F.Mask" "F.Paste")
			(net "GND")
		)
		(pad "P14" smd custom
			(at -10.580116 -8.377682 90)
			(size 2.3622 2.3622)
			(layers "F.Cu" "F.Mask" "F.Paste")
			(net "GND")
			(options
				(clearance outline)
				(anchor circle)
			)
			(primitives
				(gr_poly
					(pts
						(xy -4.7244 5.0038) (xy -4.7244 -5.0038) (xy 4.7244 -5.0038) (xy 4.7244 5.0038) (xy 0.23495 5.0038)
						(xy 0.23495 -1.4986) (xy -0.23495 -1.4986) (xy -0.23495 5.0038)
					)
					(width 0)
					(fill yes)
				)
			)
		)
		(pad "P15" smd rect
			(at -9.144 -8.377682 90)
			(size 0.0254 0.0254)
			(layers "F.Cu" "F.Mask" "F.Paste")
			(net "GND")
		)
		(pad "P16" smd rect
			(at -7.874 -8.377682 90)
			(size 0.0254 0.0254)
			(layers "F.Cu" "F.Mask" "F.Paste")
			(net "GND")
		)
		(pad "P17" smd rect
			(at -2.960116 -5.126736 90)
			(size 4.3688 10.0076)
			(drill
				(offset 0 -0.381)
			)
			(layers "F.Cu" "F.Mask" "F.Paste")
			(net "GND")
		)
		(pad "P18" smd rect
			(at -2.032 -5.126736 90)
			(size 0.0254 0.0254)
			(layers "F.Cu" "F.Mask" "F.Paste")
			(net "GND")
		)
		(pad "P19" smd rect
			(at -2.032 -5.507736 90)
			(size 0.0254 0.0254)
			(layers "F.Cu" "F.Mask" "F.Paste")
			(net "GND")
		)
		(pad "P20" smd rect
			(at -2.960116 -5.507736 90)
			(size 4.3688 10.0076)
			(layers "F.Cu" "F.Mask" "F.Paste")
			(net "GND")
		)
		(pad "P21" smd rect
			(at -7.874 -8.758682 90)
			(size 0.0254 0.0254)
			(layers "F.Cu" "F.Mask" "F.Paste")
			(net "GND")
		)
		(pad "P22" smd rect
			(at -9.144 -8.758682 90)
			(size 0.0254 0.0254)
			(layers "F.Cu" "F.Mask" "F.Paste")
			(net "GND")
		)
		(pad "P23" smd custom
			(at -10.580116 -8.758682 90)
			(size 2.3622 2.3622)
			(layers "F.Cu" "F.Mask" "F.Paste")
			(net "GND")
			(options
				(clearance outline)
				(anchor circle)
			)
			(primitives
				(gr_poly
					(pts
						(xy -4.7244 5.0038) (xy -4.7244 -5.0038) (xy 4.7244 -5.0038) (xy 4.7244 5.0038) (xy 0.23495 5.0038)
						(xy 0.23495 -1.4986) (xy -0.23495 -1.4986) (xy -0.23495 5.0038)
					)
					(width 0)
					(fill yes)
				)
			)
		)
		(pad "P24" smd rect
			(at -11.938 -8.758682 90)
			(size 0.0254 0.0254)
			(layers "F.Cu" "F.Mask" "F.Paste")
			(net "GND")
		)
		(pad "P25" smd rect
			(at -18.542 -8.758682 90)
			(size 0.0254 0.0254)
			(layers "F.Cu" "F.Mask" "F.Paste")
			(net "GND")
		)
		(pad "P26" smd rect
			(at -19.558 -8.758682 90)
			(size 0.0254 0.0254)
			(layers "F.Cu" "F.Mask" "F.Paste")
			(net "GND")
		)
		(pad "P27" smd custom
			(at -20.740116 -8.758682 90)
			(size 2.3622 2.3622)
			(layers "F.Cu" "F.Mask" "F.Paste")
			(net "GND")
			(options
				(clearance outline)
				(anchor circle)
			)
			(primitives
				(gr_poly
					(pts
						(xy -4.7244 5.0038) (xy -4.7244 -5.0038) (xy 4.7244 -5.0038) (xy 4.7244 5.0038) (xy 0.23495 5.0038)
						(xy 0.23495 -1.4986) (xy -0.23495 -1.4986) (xy -0.23495 5.0038)
					)
					(width 0)
					(fill yes)
				)
			)
		)
		(pad "P28" smd rect
			(at -22.098 -8.758682 90)
			(size 0.0254 0.0254)
			(layers "F.Cu" "F.Mask" "F.Paste")
			(net "GND")
		)
		(pad "P29" smd rect
			(at -28.702 -8.758682 90)
			(size 0.0254 0.0254)
			(layers "F.Cu" "F.Mask" "F.Paste")
			(net "P12V")
		)
		(pad "P30" smd rect
			(at -29.718 -8.758682 90)
			(size 0.0254 0.0254)
			(layers "F.Cu" "F.Mask" "F.Paste")
			(net "P12V")
		)
		(pad "P31" smd custom
			(at -30.900116 -8.758682 90)
			(size 2.3622 2.3622)
			(layers "F.Cu" "F.Mask" "F.Paste")
			(net "P12V")
			(options
				(clearance outline)
				(anchor circle)
			)
			(primitives
				(gr_poly
					(pts
						(xy -4.7244 5.0038) (xy -4.7244 -5.0038) (xy 4.7244 -5.0038) (xy 4.7244 5.0038) (xy 0.23495 5.0038)
						(xy 0.23495 -1.4986) (xy -0.23495 -1.4986) (xy -0.23495 5.0038)
					)
					(width 0)
					(fill yes)
				)
			)
		)
		(pad "P32" smd rect
			(at -32.004 -8.758682 90)
			(size 0.0254 0.0254)
			(layers "F.Cu" "F.Mask" "F.Paste")
			(net "P12V")
		)
		(pad "P33" smd rect
			(at -38.862 -8.758682 90)
			(size 0.0254 0.0254)
			(layers "F.Cu" "F.Mask" "F.Paste")
			(net "P12V")
		)
		(pad "P34" smd rect
			(at -39.878 -8.758682 90)
			(size 0.0254 0.0254)
			(layers "F.Cu" "F.Mask" "F.Paste")
			(net "P12V")
		)
		(pad "P35" smd custom
			(at -41.060116 -8.758682 90)
			(size 2.3622 2.3622)
			(layers "F.Cu" "F.Mask" "F.Paste")
			(net "P12V")
			(options
				(clearance outline)
				(anchor circle)
			)
			(primitives
				(gr_poly
					(pts
						(xy -4.7244 5.0038) (xy -4.7244 -5.0038) (xy 4.7244 -5.0038) (xy 4.7244 5.0038) (xy 0.23495 5.0038)
						(xy 0.23495 -1.4986) (xy -0.23495 -1.4986) (xy -0.23495 5.0038)
					)
					(width 0)
					(fill yes)
				)
			)
		)
		(pad "P36" smd rect
			(at -42.164 -8.758682 90)
			(size 0.0254 0.0254)
			(layers "F.Cu" "F.Mask" "F.Paste")
			(net "P12V")
		)
		(pad "S1" smd rect
			(at 1.810004 -3.805936 90)
			(size 0.8128 5.842)
			(drill
				(offset 0 0.381)
			)
			(layers "F.Cu" "F.Mask" "F.Paste")
			(net "GND")
		)
		(pad "S2" smd rect
			(at 3.080004 -3.805936 90)
			(size 0.8128 5.842)
			(drill
				(offset 0 0.381)
			)
			(layers "F.Cu" "F.Mask" "F.Paste")
			(net "P3V3")
		)
		(pad "S3" smd rect
			(at 4.350004 -3.805936 90)
			(size 0.8128 5.842)
			(drill
				(offset 0 0.381)
			)
			(layers "F.Cu" "F.Mask" "F.Paste")
			(net "P3V3")
		)
		(pad "S4" smd rect
			(at 5.620004 -3.805936 90)
			(size 0.8128 5.842)
			(drill
				(offset 0 0.381)
			)
			(layers "F.Cu" "F.Mask" "F.Paste")
			(net "PEER_TRAY_PRESENT")
		)
		(pad "S5" smd rect
			(at 6.890004 -3.805936 90)
			(size 0.8128 5.842)
			(drill
				(offset 0 0.381)
			)
			(layers "F.Cu" "F.Mask" "F.Paste")
			(net "N70914768")
		)
		(pad "S6" smd rect
			(at 8.160004 -3.805936 90)
			(size 0.8128 5.842)
			(drill
				(offset 0 0.381)
			)
			(layers "F.Cu" "F.Mask" "F.Paste")
			(net "SELF_TRAY_PRESENT")
		)
		(pad "S7" smd rect
			(at 9.430004 -3.805936 90)
			(size 0.8128 5.842)
			(drill
				(offset 0 0.381)
			)
			(layers "F.Cu" "F.Mask" "F.Paste")
			(net "PWM_EXP_A")
		)
		(pad "S8" smd rect
			(at 10.700004 -3.805936 90)
			(size 0.8128 5.842)
			(drill
				(offset 0 0.381)
			)
			(layers "F.Cu" "F.Mask" "F.Paste")
			(net "GND")
		)
		(pad "S9" smd rect
			(at 11.970004 -3.805936 90)
			(size 0.8128 5.842)
			(drill
				(offset 0 0.381)
			)
			(layers "F.Cu" "F.Mask" "F.Paste")
			(net "I2C_C_SDA")
		)
		(pad "S10" smd rect
			(at 13.240004 -3.805936 90)
			(size 0.8128 5.842)
			(drill
				(offset 0 0.381)
			)
			(layers "F.Cu" "F.Mask" "F.Paste")
			(net "GND")
		)
		(pad "S11" smd rect
			(at 14.510004 -3.805936 90)
			(size 0.8128 5.842)
			(drill
				(offset 0 0.381)
			)
			(layers "F.Cu" "F.Mask" "F.Paste")
			(net "I2C_C_SCL")
		)
		(pad "S12" smd rect
			(at 15.780004 -3.805936 90)
			(size 0.8128 5.842)
			(drill
				(offset 0 0.381)
			)
			(layers "F.Cu" "F.Mask" "F.Paste")
			(net "GND")
		)
		(pad "S13" smd rect
			(at 15.780004 -3.424936 90)
			(size 0.8128 5.842)
			(layers "F.Cu" "F.Mask" "F.Paste")
			(net "GND")
		)
		(pad "S14" smd rect
			(at 14.510004 -3.424936 90)
			(size 0.8128 5.842)
			(layers "F.Cu" "F.Mask" "F.Paste")
			(net "SELF_1A&2A_HB")
		)
		(pad "S15" smd rect
			(at 13.240004 -3.424936 90)
			(size 0.8128 5.842)
			(layers "F.Cu" "F.Mask" "F.Paste")
			(net "N70930468")
		)
		(pad "S16" smd rect
			(at 11.970004 -3.424936 90)
			(size 0.8128 5.842)
			(layers "F.Cu" "F.Mask" "F.Paste")
			(net "TRAY_ID")
		)
		(pad "S17" smd rect
			(at 10.700004 -3.424936 90)
			(size 0.8128 5.842)
			(layers "F.Cu" "F.Mask" "F.Paste")
			(net "FCB_HW_REVISION")
		)
		(pad "S18" smd rect
			(at 9.430004 -3.424936 90)
			(size 0.8128 5.842)
			(layers "F.Cu" "F.Mask" "F.Paste")
			(net "SD_LATCH_RELEASE")
		)
		(pad "S19" smd rect
			(at 8.160004 -3.424936 90)
			(size 0.8128 5.842)
			(layers "F.Cu" "F.Mask" "F.Paste")
			(net "GND")
		)
		(pad "S20" smd rect
			(at 6.890004 -3.424936 90)
			(size 0.8128 5.842)
			(layers "F.Cu" "F.Mask" "F.Paste")
			(net "PEER_1A&2A_HB")
		)
		(pad "S21" smd rect
			(at 5.620004 -3.424936 90)
			(size 0.8128 5.842)
			(layers "F.Cu" "F.Mask" "F.Paste")
			(net "N70929042")
		)
		(pad "S22" smd rect
			(at 4.350004 -3.424936 90)
			(size 0.8128 5.842)
			(layers "F.Cu" "F.Mask" "F.Paste")
			(net "GND")
		)
		(pad "S23" smd rect
			(at 3.080004 -3.424936 90)
			(size 0.8128 5.842)
			(layers "F.Cu" "F.Mask" "F.Paste")
			(net "GND")
		)
		(pad "S24" smd rect
			(at 1.810004 -3.424936 90)
			(size 0.8128 5.842)
			(layers "F.Cu" "F.Mask" "F.Paste")
			(net "Net_110")
		)
		(zone
			(layers "F.Cu" "B.Cu" "In1.Cu" "In2.Cu" "In3.Cu" "In4.Cu" "In5.Cu" "In6.Cu")
			(hatch none 0.5)
			(connect_pads
				(clearance 0)
			)
			(min_thickness 0.25)
			(keepout
				(tracks not_allowed)
				(vias allowed)
				(pads allowed)
				(copperpour not_allowed)
				(footprints allowed)
			)
			(placement
				(enabled no)
				(sheetname "")
			)
			(fill
				(thermal_gap 0.5)
				(thermal_bridge_width 0.5)
				(island_removal_mode 0)
			)
			(polygon
				(pts
					(arc
						(start 262.058912 -430.329848)
						(mid 257.740912 -430.329848)
						(end 262.058912 -430.329848)
					)
				)
			)
		)
		(zone
			(layers "F.Cu" "B.Cu" "In1.Cu" "In2.Cu" "In3.Cu" "In4.Cu" "In5.Cu" "In6.Cu")
			(hatch none 0.5)
			(connect_pads
				(clearance 0)
			)
			(min_thickness 0.25)
			(keepout
				(tracks not_allowed)
				(vias allowed)
				(pads allowed)
				(copperpour not_allowed)
				(footprints allowed)
			)
			(placement
				(enabled no)
				(sheetname "")
			)
			(fill
				(thermal_gap 0.5)
				(thermal_bridge_width 0.5)
				(island_removal_mode 0)
			)
			(polygon
				(pts
					(arc
						(start 262.058912 -359.670096)
						(mid 257.740912 -359.670096)
						(end 262.058912 -359.670096)
					)
				)
			)
		)
	)
	(footprint ""
		(layer "F.Cu")
		(at 71.247 -440.182)
		(property "Reference" "R351"
			(at 0 0 0)
			(layer "F.SilkS")
			(hide yes)
			(effects
				(font
					(size 1.27 1.27)
				)
			)
		)
		(property "Value" "0R2J-2-GP"
			(at 0.064008 -3.993896 0)
			(unlocked yes)
			(layer "F.Fab")
			(hide yes)
			(effects
				(font
					(size 1.016 1.016)
					(thickness 0.1524)
				)
			)
		)
		(property "Device Type" "R402H16"
			(at 0.064008 -5.517896 0)
			(unlocked yes)
			(layer "F.Fab")
			(hide yes)
			(effects
				(font
					(size 1.016 1.016)
					(thickness 0.1524)
				)
			)
		)
		(duplicate_pad_numbers_are_jumpers no)
		(fp_line
			(start -0.508 -0.9398)
			(end -0.508 0.9398)
			(stroke
				(width 0.1524)
				(type default)
			)
			(layer "F.SilkS")
		)
		(fp_line
			(start 0.508 -0.9398)
			(end -0.508 -0.9398)
			(stroke
				(width 0.1524)
				(type default)
			)
			(layer "F.SilkS")
		)
		(fp_rect
			(start -0.508 0.9398)
			(end 0.508 -0.9398)
			(stroke
				(width 0)
				(type default)
			)
			(fill no)
			(layer "F.CrtYd")
		)
		(fp_rect
			(start -0.508 0.9398)
			(end 0.508 -0.9398)
			(stroke
				(width 0)
				(type default)
			)
			(fill no)
			(layer "F.Fab")
		)
		(pad "1" smd custom
			(at 0 -0.4445)
			(size 0.1397 0.1397)
			(layers "F.Cu" "F.Mask" "F.Paste")
			(net "EEPROM_WP")
			(options
				(clearance outline)
				(anchor circle)
			)
			(primitives
				(gr_poly
					(pts
						(arc
							(start -0.1778 -0.2794)
							(mid -0.249642 -0.249642)
							(end -0.2794 -0.1778)
						)
						(arc
							(start -0.2794 0.1778)
							(mid -0.249642 0.249642)
							(end -0.1778 0.2794)
						)
						(arc
							(start 0.1778 0.2794)
							(mid 0.249642 0.249642)
							(end 0.2794 0.1778)
						)
						(arc
							(start 0.2794 -0.1778)
							(mid 0.249642 -0.249642)
							(end 0.1778 -0.2794)
						)
					)
					(width 0)
					(fill yes)
				)
			)
		)
		(pad "2" smd custom
			(at 0 0.4445)
			(size 0.1397 0.1397)
			(layers "F.Cu" "F.Mask" "F.Paste")
			(net "GND")
			(options
				(clearance outline)
				(anchor circle)
			)
			(primitives
				(gr_poly
					(pts
						(arc
							(start -0.1778 -0.2794)
							(mid -0.249642 -0.249642)
							(end -0.2794 -0.1778)
						)
						(arc
							(start -0.2794 0.1778)
							(mid -0.249642 0.249642)
							(end -0.1778 0.2794)
						)
						(arc
							(start 0.1778 0.2794)
							(mid 0.249642 0.249642)
							(end 0.2794 0.1778)
						)
						(arc
							(start 0.2794 -0.1778)
							(mid 0.249642 -0.249642)
							(end 0.1778 -0.2794)
						)
					)
					(width 0)
					(fill yes)
				)
			)
		)
	)
	(footprint ""
		(layer "F.Cu")
		(at 95.504 -313.817 180)
		(property "Reference" "R9099"
			(at 0 0 180)
			(layer "F.SilkS")
			(hide yes)
			(effects
				(font
					(size 1.27 1.27)
				)
			)
		)
		(property "Value" "27R2F-GP"
			(at 0.064008 -3.993896 180)
			(unlocked yes)
			(layer "F.Fab")
			(hide yes)
			(effects
				(font
					(size 1.016 1.016)
					(thickness 0.1524)
				)
			)
		)
		(property "Device Type" "R402H16"
			(at 0.064008 -5.517896 180)
			(unlocked yes)
			(layer "F.Fab")
			(hide yes)
			(effects
				(font
					(size 1.016 1.016)
					(thickness 0.1524)
				)
			)
		)
		(duplicate_pad_numbers_are_jumpers no)
		(fp_line
			(start 0.508 -0.9398)
			(end -0.508 -0.9398)
			(stroke
				(width 0.1524)
				(type default)
			)
			(layer "F.SilkS")
		)
		(fp_line
			(start -0.508 -0.9398)
			(end -0.508 0.9398)
			(stroke
				(width 0.1524)
				(type default)
			)
			(layer "F.SilkS")
		)
		(fp_rect
			(start -0.508 0.9398)
			(end 0.508 -0.9398)
			(stroke
				(width 0)
				(type default)
			)
			(fill no)
			(layer "F.CrtYd")
		)
		(fp_rect
			(start -0.508 0.9398)
			(end 0.508 -0.9398)
			(stroke
				(width 0)
				(type default)
			)
			(fill no)
			(layer "F.Fab")
		)
		(pad "1" smd custom
			(at 0 -0.4445 180)
			(size 0.1397 0.1397)
			(layers "F.Cu" "F.Mask" "F.Paste")
			(net "PE_CLK_100M_DR6_1_R_N")
			(options
				(clearance outline)
				(anchor circle)
			)
			(primitives
				(gr_poly
					(pts
						(arc
							(start -0.1778 -0.2794)
							(mid -0.249642 -0.249642)
							(end -0.2794 -0.1778)
						)
						(arc
							(start -0.2794 0.1778)
							(mid -0.249642 0.249642)
							(end -0.1778 0.2794)
						)
						(arc
							(start 0.1778 0.2794)
							(mid 0.249642 0.249642)
							(end 0.2794 0.1778)
						)
						(arc
							(start 0.2794 -0.1778)
							(mid 0.249642 -0.249642)
							(end 0.1778 -0.2794)
						)
					)
					(width 0)
					(fill yes)
				)
			)
		)
		(pad "2" smd custom
			(at 0 0.4445 180)
			(size 0.1397 0.1397)
			(layers "F.Cu" "F.Mask" "F.Paste")
			(net "PE_CLK100M_DR6_1_N")
			(options
				(clearance outline)
				(anchor circle)
			)
			(primitives
				(gr_poly
					(pts
						(arc
							(start -0.1778 -0.2794)
							(mid -0.249642 -0.249642)
							(end -0.2794 -0.1778)
						)
						(arc
							(start -0.2794 0.1778)
							(mid -0.249642 0.249642)
							(end -0.1778 0.2794)
						)
						(arc
							(start 0.1778 0.2794)
							(mid 0.249642 0.249642)
							(end 0.2794 0.1778)
						)
						(arc
							(start 0.2794 -0.1778)
							(mid 0.249642 -0.249642)
							(end 0.1778 -0.2794)
						)
					)
					(width 0)
					(fill yes)
				)
			)
		)
	)
	(footprint ""
		(layer "F.Cu")
		(at 37.973 -308.737 180)
		(property "Reference" "R9771"
			(at 0 0 180)
			(layer "F.SilkS")
			(hide yes)
			(effects
				(font
					(size 1.27 1.27)
				)
			)
		)
		(property "Value" "4K7R2J-2-GP"
			(at 0.064008 -3.993896 180)
			(unlocked yes)
			(layer "F.Fab")
			(hide yes)
			(effects
				(font
					(size 1.016 1.016)
					(thickness 0.1524)
				)
			)
		)
		(property "Device Type" "R402H16"
			(at 0.064008 -5.517896 180)
			(unlocked yes)
			(layer "F.Fab")
			(hide yes)
			(effects
				(font
					(size 1.016 1.016)
					(thickness 0.1524)
				)
			)
		)
		(duplicate_pad_numbers_are_jumpers no)
		(fp_line
			(start 0.508 -0.9398)
			(end -0.508 -0.9398)
			(stroke
				(width 0.1524)
				(type default)
			)
			(layer "F.SilkS")
		)
		(fp_line
			(start -0.508 -0.9398)
			(end -0.508 0.9398)
			(stroke
				(width 0.1524)
				(type default)
			)
			(layer "F.SilkS")
		)
		(fp_rect
			(start -0.508 0.9398)
			(end 0.508 -0.9398)
			(stroke
				(width 0)
				(type default)
			)
			(fill no)
			(layer "F.CrtYd")
		)
		(fp_rect
			(start -0.508 0.9398)
			(end 0.508 -0.9398)
			(stroke
				(width 0)
				(type default)
			)
			(fill no)
			(layer "F.Fab")
		)
		(pad "1" smd custom
			(at 0 -0.4445 180)
			(size 0.1397 0.1397)
			(layers "F.Cu" "F.Mask" "F.Paste")
			(net "SSD11_PWREN")
			(options
				(clearance outline)
				(anchor circle)
			)
			(primitives
				(gr_poly
					(pts
						(arc
							(start -0.1778 -0.2794)
							(mid -0.249642 -0.249642)
							(end -0.2794 -0.1778)
						)
						(arc
							(start -0.2794 0.1778)
							(mid -0.249642 0.249642)
							(end -0.1778 0.2794)
						)
						(arc
							(start 0.1778 0.2794)
							(mid 0.249642 0.249642)
							(end 0.2794 0.1778)
						)
						(arc
							(start 0.2794 -0.1778)
							(mid 0.249642 -0.249642)
							(end 0.1778 -0.2794)
						)
					)
					(width 0)
					(fill yes)
				)
			)
		)
		(pad "2" smd custom
			(at 0 0.4445 180)
			(size 0.1397 0.1397)
			(layers "F.Cu" "F.Mask" "F.Paste")
			(net "GND")
			(options
				(clearance outline)
				(anchor circle)
			)
			(primitives
				(gr_poly
					(pts
						(arc
							(start -0.1778 -0.2794)
							(mid -0.249642 -0.249642)
							(end -0.2794 -0.1778)
						)
						(arc
							(start -0.2794 0.1778)
							(mid -0.249642 0.249642)
							(end -0.1778 0.2794)
						)
						(arc
							(start 0.1778 0.2794)
							(mid 0.249642 0.249642)
							(end 0.2794 0.1778)
						)
						(arc
							(start 0.2794 -0.1778)
							(mid 0.249642 -0.249642)
							(end 0.1778 -0.2794)
						)
					)
					(width 0)
					(fill yes)
				)
			)
		)
	)
	(footprint ""
		(layer "F.Cu")
		(at 208.153 -293.116)
		(property "Reference" "R553"
			(at 0 0 0)
			(layer "F.SilkS")
			(hide yes)
			(effects
				(font
					(size 1.27 1.27)
				)
			)
		)
		(property "Value" "200KR2F-L-GP"
			(at 0.064008 -3.993896 0)
			(unlocked yes)
			(layer "F.Fab")
			(hide yes)
			(effects
				(font
					(size 1.016 1.016)
					(thickness 0.1524)
				)
			)
		)
		(property "Device Type" "R402H16"
			(at 0.064008 -5.517896 0)
			(unlocked yes)
			(layer "F.Fab")
			(hide yes)
			(effects
				(font
					(size 1.016 1.016)
					(thickness 0.1524)
				)
			)
		)
		(duplicate_pad_numbers_are_jumpers no)
		(fp_line
			(start -0.508 -0.9398)
			(end -0.508 0.9398)
			(stroke
				(width 0.1524)
				(type default)
			)
			(layer "F.SilkS")
		)
		(fp_line
			(start 0.508 -0.9398)
			(end -0.508 -0.9398)
			(stroke
				(width 0.1524)
				(type default)
			)
			(layer "F.SilkS")
		)
		(fp_rect
			(start -0.508 0.9398)
			(end 0.508 -0.9398)
			(stroke
				(width 0)
				(type default)
			)
			(fill no)
			(layer "F.CrtYd")
		)
		(fp_rect
			(start -0.508 0.9398)
			(end 0.508 -0.9398)
			(stroke
				(width 0)
				(type default)
			)
			(fill no)
			(layer "F.Fab")
		)
		(pad "1" smd custom
			(at 0 -0.4445)
			(size 0.1397 0.1397)
			(layers "F.Cu" "F.Mask" "F.Paste")
			(net "SW_SSD2_R")
			(options
				(clearance outline)
				(anchor circle)
			)
			(primitives
				(gr_poly
					(pts
						(arc
							(start -0.1778 -0.2794)
							(mid -0.249642 -0.249642)
							(end -0.2794 -0.1778)
						)
						(arc
							(start -0.2794 0.1778)
							(mid -0.249642 0.249642)
							(end -0.1778 0.2794)
						)
						(arc
							(start 0.1778 0.2794)
							(mid 0.249642 0.249642)
							(end 0.2794 0.1778)
						)
						(arc
							(start 0.2794 -0.1778)
							(mid 0.249642 -0.249642)
							(end 0.1778 -0.2794)
						)
					)
					(width 0)
					(fill yes)
				)
			)
		)
		(pad "2" smd custom
			(at 0 0.4445)
			(size 0.1397 0.1397)
			(layers "F.Cu" "F.Mask" "F.Paste")
			(net "SW_SSD2_N")
			(options
				(clearance outline)
				(anchor circle)
			)
			(primitives
				(gr_poly
					(pts
						(arc
							(start -0.1778 -0.2794)
							(mid -0.249642 -0.249642)
							(end -0.2794 -0.1778)
						)
						(arc
							(start -0.2794 0.1778)
							(mid -0.249642 0.249642)
							(end -0.1778 0.2794)
						)
						(arc
							(start 0.1778 0.2794)
							(mid 0.249642 0.249642)
							(end 0.2794 0.1778)
						)
						(arc
							(start 0.2794 -0.1778)
							(mid 0.249642 -0.249642)
							(end 0.1778 -0.2794)
						)
					)
					(width 0)
					(fill yes)
				)
			)
		)
	)
	(footprint ""
		(layer "F.Cu")
		(at 23.495 -153.67 180)
		(property "Reference" "R9905"
			(at 0 0 180)
			(layer "F.SilkS")
			(hide yes)
			(effects
				(font
					(size 1.27 1.27)
				)
			)
		)
		(property "Value" "1K82R2F-1-GP"
			(at 0.064008 -3.993896 180)
			(unlocked yes)
			(layer "F.Fab")
			(hide yes)
			(effects
				(font
					(size 1.016 1.016)
					(thickness 0.1524)
				)
			)
		)
		(property "Device Type" "R402H16"
			(at 0.064008 -5.517896 180)
			(unlocked yes)
			(layer "F.Fab")
			(hide yes)
			(effects
				(font
					(size 1.016 1.016)
					(thickness 0.1524)
				)
			)
		)
		(duplicate_pad_numbers_are_jumpers no)
		(fp_line
			(start 0.508 -0.9398)
			(end -0.508 -0.9398)
			(stroke
				(width 0.1524)
				(type default)
			)
			(layer "F.SilkS")
		)
		(fp_line
			(start -0.508 -0.9398)
			(end -0.508 0.9398)
			(stroke
				(width 0.1524)
				(type default)
			)
			(layer "F.SilkS")
		)
		(fp_rect
			(start -0.508 0.9398)
			(end 0.508 -0.9398)
			(stroke
				(width 0)
				(type default)
			)
			(fill no)
			(layer "F.CrtYd")
		)
		(fp_rect
			(start -0.508 0.9398)
			(end 0.508 -0.9398)
			(stroke
				(width 0)
				(type default)
			)
			(fill no)
			(layer "F.Fab")
		)
		(pad "1" smd custom
			(at 0 -0.4445 180)
			(size 0.1397 0.1397)
			(layers "F.Cu" "F.Mask" "F.Paste")
			(net "P12V")
			(options
				(clearance outline)
				(anchor circle)
			)
			(primitives
				(gr_poly
					(pts
						(arc
							(start -0.1778 -0.2794)
							(mid -0.249642 -0.249642)
							(end -0.2794 -0.1778)
						)
						(arc
							(start -0.2794 0.1778)
							(mid -0.249642 0.249642)
							(end -0.1778 0.2794)
						)
						(arc
							(start 0.1778 0.2794)
							(mid 0.249642 0.249642)
							(end 0.2794 0.1778)
						)
						(arc
							(start 0.2794 -0.1778)
							(mid 0.249642 -0.249642)
							(end 0.1778 -0.2794)
						)
					)
					(width 0)
					(fill yes)
				)
			)
		)
		(pad "2" smd custom
			(at 0 0.4445 180)
			(size 0.1397 0.1397)
			(layers "F.Cu" "F.Mask" "F.Paste")
			(net "DRV_ACT_13")
			(options
				(clearance outline)
				(anchor circle)
			)
			(primitives
				(gr_poly
					(pts
						(arc
							(start -0.1778 -0.2794)
							(mid -0.249642 -0.249642)
							(end -0.2794 -0.1778)
						)
						(arc
							(start -0.2794 0.1778)
							(mid -0.249642 0.249642)
							(end -0.1778 0.2794)
						)
						(arc
							(start 0.1778 0.2794)
							(mid 0.249642 0.249642)
							(end 0.2794 0.1778)
						)
						(arc
							(start 0.2794 -0.1778)
							(mid 0.249642 -0.249642)
							(end 0.1778 -0.2794)
						)
					)
					(width 0)
					(fill yes)
				)
			)
		)
	)
	(footprint ""
		(layer "F.Cu")
		(at 81.661 -365.1758 -90)
		(property "Reference" "SR989"
			(at 0 0 270)
			(layer "F.SilkS")
			(hide yes)
			(effects
				(font
					(size 1.27 1.27)
				)
			)
		)
		(property "Value" "2KR2F-3-GP"
			(at 0.064008 -3.993896 270)
			(unlocked yes)
			(layer "F.Fab")
			(hide yes)
			(effects
				(font
					(size 1.016 1.016)
					(thickness 0.1524)
				)
			)
		)
		(property "Device Type" "R402H16"
			(at 0.064008 -5.517896 270)
			(unlocked yes)
			(layer "F.Fab")
			(hide yes)
			(effects
				(font
					(size 1.016 1.016)
					(thickness 0.1524)
				)
			)
		)
		(duplicate_pad_numbers_are_jumpers no)
		(fp_line
			(start -0.508 -0.9398)
			(end -0.508 0.9398)
			(stroke
				(width 0.1524)
				(type default)
			)
			(layer "F.SilkS")
		)
		(fp_line
			(start 0.508 -0.9398)
			(end -0.508 -0.9398)
			(stroke
				(width 0.1524)
				(type default)
			)
			(layer "F.SilkS")
		)
		(fp_rect
			(start -0.508 0.9398)
			(end 0.508 -0.9398)
			(stroke
				(width 0)
				(type default)
			)
			(fill no)
			(layer "F.CrtYd")
		)
		(fp_rect
			(start -0.508 0.9398)
			(end 0.508 -0.9398)
			(stroke
				(width 0)
				(type default)
			)
			(fill no)
			(layer "F.Fab")
		)
		(pad "1" smd custom
			(at 0 -0.4445 270)
			(size 0.1397 0.1397)
			(layers "F.Cu" "F.Mask" "F.Paste")
			(net "P3V3")
			(options
				(clearance outline)
				(anchor circle)
			)
			(primitives
				(gr_poly
					(pts
						(arc
							(start -0.1778 -0.2794)
							(mid -0.249642 -0.249642)
							(end -0.2794 -0.1778)
						)
						(arc
							(start -0.2794 0.1778)
							(mid -0.249642 0.249642)
							(end -0.1778 0.2794)
						)
						(arc
							(start 0.1778 0.2794)
							(mid 0.249642 0.249642)
							(end 0.2794 0.1778)
						)
						(arc
							(start 0.2794 -0.1778)
							(mid 0.249642 -0.249642)
							(end 0.1778 -0.2794)
						)
					)
					(width 0)
					(fill yes)
				)
			)
		)
		(pad "2" smd custom
			(at 0 0.4445 270)
			(size 0.1397 0.1397)
			(layers "F.Cu" "F.Mask" "F.Paste")
			(net "SCL_DR0")
			(options
				(clearance outline)
				(anchor circle)
			)
			(primitives
				(gr_poly
					(pts
						(arc
							(start -0.1778 -0.2794)
							(mid -0.249642 -0.249642)
							(end -0.2794 -0.1778)
						)
						(arc
							(start -0.2794 0.1778)
							(mid -0.249642 0.249642)
							(end -0.1778 0.2794)
						)
						(arc
							(start 0.1778 0.2794)
							(mid 0.249642 0.249642)
							(end 0.2794 0.1778)
						)
						(arc
							(start 0.2794 -0.1778)
							(mid 0.249642 -0.249642)
							(end 0.1778 -0.2794)
						)
					)
					(width 0)
					(fill yes)
				)
			)
		)
	)
	(footprint ""
		(layer "F.Cu")
		(at 37.0332 -394.2842)
		(property "Reference" "PC1243"
			(at 0 0 0)
			(layer "F.SilkS")
			(hide yes)
			(effects
				(font
					(size 1.27 1.27)
				)
			)
		)
		(property "Value" "SCD01U50V2KX-1GP"
			(at 1.1811 -2.7051 0)
			(unlocked yes)
			(layer "F.Fab")
			(hide yes)
			(effects
				(font
					(size 1.016 1.016)
					(thickness 0.1524)
				)
			)
		)
		(property "Device Type" "C402H22"
			(at 1.1811 -4.2291 0)
			(unlocked yes)
			(layer "F.Fab")
			(hide yes)
			(effects
				(font
					(size 1.016 1.016)
					(thickness 0.1524)
				)
			)
		)
		(duplicate_pad_numbers_are_jumpers no)
		(fp_rect
			(start -0.4318 0.9525)
			(end 0.4318 -0.9525)
			(stroke
				(width 0)
				(type default)
			)
			(fill no)
			(layer "F.CrtYd")
		)
		(fp_rect
			(start -0.4318 0.9525)
			(end 0.4318 -0.9525)
			(stroke
				(width 0)
				(type default)
			)
			(fill no)
			(layer "F.Fab")
		)
		(pad "1" smd custom
			(at 0 -0.4445)
			(size 0.1524 0.1524)
			(layers "F.Cu" "F.Mask" "F.Paste")
			(net "P12V_SSD6")
			(options
				(clearance outline)
				(anchor circle)
			)
			(primitives
				(gr_poly
					(pts
						(arc
							(start 0.3048 -0.2032)
							(mid 0.275042 -0.275042)
							(end 0.2032 -0.3048)
						)
						(arc
							(start -0.2032 -0.3048)
							(mid -0.275042 -0.275042)
							(end -0.3048 -0.2032)
						)
						(arc
							(start -0.3048 0.2032)
							(mid -0.275042 0.275042)
							(end -0.2032 0.3048)
						)
						(arc
							(start 0.2032 0.3048)
							(mid 0.275042 0.275042)
							(end 0.3048 0.2032)
						)
					)
					(width 0)
					(fill yes)
				)
			)
		)
		(pad "2" smd custom
			(at 0 0.4445)
			(size 0.1524 0.1524)
			(layers "F.Cu" "F.Mask" "F.Paste")
			(net "GND")
			(options
				(clearance outline)
				(anchor circle)
			)
			(primitives
				(gr_poly
					(pts
						(arc
							(start 0.3048 -0.2032)
							(mid 0.275042 -0.275042)
							(end 0.2032 -0.3048)
						)
						(arc
							(start -0.2032 -0.3048)
							(mid -0.275042 -0.275042)
							(end -0.3048 -0.2032)
						)
						(arc
							(start -0.3048 0.2032)
							(mid -0.275042 0.275042)
							(end -0.2032 0.3048)
						)
						(arc
							(start 0.2032 0.3048)
							(mid 0.275042 0.275042)
							(end 0.3048 0.2032)
						)
					)
					(width 0)
					(fill yes)
				)
			)
		)
	)
	(footprint ""
		(layer "F.Cu")
		(at 95.0722 -21.9456)
		(property "Reference" "C359"
			(at 0 0 0)
			(layer "F.SilkS")
			(hide yes)
			(effects
				(font
					(size 1.27 1.27)
				)
			)
		)
		(property "Value" "SCD1U16V2KX-3GP"
			(at 1.1811 -2.7051 0)
			(unlocked yes)
			(layer "F.Fab")
			(hide yes)
			(effects
				(font
					(size 1.016 1.016)
					(thickness 0.1524)
				)
			)
		)
		(property "Device Type" "C402H22"
			(at 1.1811 -4.2291 0)
			(unlocked yes)
			(layer "F.Fab")
			(hide yes)
			(effects
				(font
					(size 1.016 1.016)
					(thickness 0.1524)
				)
			)
		)
		(duplicate_pad_numbers_are_jumpers no)
		(fp_rect
			(start -0.4318 0.9525)
			(end 0.4318 -0.9525)
			(stroke
				(width 0)
				(type default)
			)
			(fill no)
			(layer "F.CrtYd")
		)
		(fp_rect
			(start -0.4318 0.9525)
			(end 0.4318 -0.9525)
			(stroke
				(width 0)
				(type default)
			)
			(fill no)
			(layer "F.Fab")
		)
		(pad "1" smd custom
			(at 0 -0.4445)
			(size 0.1524 0.1524)
			(layers "F.Cu" "F.Mask" "F.Paste")
			(net "P12V_SSD14_SENSE")
			(options
				(clearance outline)
				(anchor circle)
			)
			(primitives
				(gr_poly
					(pts
						(arc
							(start 0.3048 -0.2032)
							(mid 0.275042 -0.275042)
							(end 0.2032 -0.3048)
						)
						(arc
							(start -0.2032 -0.3048)
							(mid -0.275042 -0.275042)
							(end -0.3048 -0.2032)
						)
						(arc
							(start -0.3048 0.2032)
							(mid -0.275042 0.275042)
							(end -0.2032 0.3048)
						)
						(arc
							(start 0.2032 0.3048)
							(mid 0.275042 0.275042)
							(end 0.3048 0.2032)
						)
					)
					(width 0)
					(fill yes)
				)
			)
		)
		(pad "2" smd custom
			(at 0 0.4445)
			(size 0.1524 0.1524)
			(layers "F.Cu" "F.Mask" "F.Paste")
			(net "GND")
			(options
				(clearance outline)
				(anchor circle)
			)
			(primitives
				(gr_poly
					(pts
						(arc
							(start 0.3048 -0.2032)
							(mid 0.275042 -0.275042)
							(end 0.2032 -0.3048)
						)
						(arc
							(start -0.2032 -0.3048)
							(mid -0.275042 -0.275042)
							(end -0.3048 -0.2032)
						)
						(arc
							(start -0.3048 0.2032)
							(mid -0.275042 0.275042)
							(end -0.2032 0.3048)
						)
						(arc
							(start 0.2032 0.3048)
							(mid 0.275042 0.275042)
							(end 0.3048 0.2032)
						)
					)
					(width 0)
					(fill yes)
				)
			)
		)
	)
	(footprint ""
		(layer "F.Cu")
		(at 70.000114 -173.99762)
		(property "Reference" "H7"
			(at 0 0 0)
			(layer "F.SilkS")
			(hide yes)
			(effects
				(font
					(size 1.27 1.27)
				)
			)
		)
		(property "Value" "GEN276X162R197X296-6-F-A-GP"
			(at -6.7183 4.1402 0)
			(unlocked yes)
			(layer "F.Fab")
			(hide yes)
			(effects
				(font
					(size 1.016 1.016)
					(thickness 0.1524)
				)
			)
		)
		(property "Device Type" "GEN276X162R197X296-6-F-A"
			(at -6.7183 2.6162 0)
			(unlocked yes)
			(layer "F.Fab")
			(hide yes)
			(effects
				(font
					(size 1.016 1.016)
					(thickness 0.1524)
				)
			)
		)
		(duplicate_pad_numbers_are_jumpers no)
		(fp_poly
			(pts
				(arc
					(start 2.723642 4.777232)
					(mid -0.000169 6.508462)
					(end -2.723896 4.776978)
				)
				(arc
					(start -2.723896 4.776978)
					(mid 0.000173 -5.499012)
					(end 2.723642 4.777232)
				)
			)
			(stroke
				(width 0)
				(type default)
			)
			(fill no)
			(layer "B.CrtYd")
		)
		(fp_poly
			(pts
				(arc
					(start 2.723642 4.777232)
					(mid -0.000169 6.508462)
					(end -2.723896 4.776978)
				)
				(arc
					(start -2.723896 4.776978)
					(mid 0.000173 -5.499012)
					(end 2.723642 4.777232)
				)
			)
			(stroke
				(width 0)
				(type default)
			)
			(fill no)
			(layer "F.CrtYd")
		)
		(fp_poly
			(pts
				(arc
					(start 2.723642 4.777232)
					(mid -0.000169 6.508462)
					(end -2.723896 4.776978)
				)
				(arc
					(start -2.723896 4.776978)
					(mid 0.000173 -5.499012)
					(end 2.723642 4.777232)
				)
			)
			(stroke
				(width 0)
				(type default)
			)
			(fill no)
			(layer "B.Fab")
		)
		(fp_poly
			(pts
				(arc
					(start 2.723642 4.777232)
					(mid -0.000169 6.508462)
					(end -2.723896 4.776978)
				)
				(arc
					(start -2.723896 4.776978)
					(mid 0.000173 -5.499012)
					(end 2.723642 4.777232)
				)
			)
			(stroke
				(width 0)
				(type default)
			)
			(fill no)
			(layer "F.Fab")
		)
		(pad "" np_thru_hole circle
			(at 0 0)
			(size 0.254 0.254)
			(drill 0.0254)
			(layers "*.Cu" "*.Mask")
			(clearance 3.135376)
			(thermal_gap 3.135376)
		)
		(pad "1" thru_hole circle
			(at 2.549906 0)
			(size 0.8636 0.8636)
			(drill 0.508)
			(layers "*.Cu" "*.Mask")
			(remove_unused_layers no)
			(net "GND")
			(clearance 0.8255)
			(thermal_gap 0.8255)
		)
		(pad "2" thru_hole circle
			(at 2.210054 -1.27)
			(size 0.8636 0.8636)
			(drill 0.508)
			(layers "*.Cu" "*.Mask")
			(remove_unused_layers no)
			(net "GND")
			(clearance 0.8255)
			(thermal_gap 0.8255)
		)
		(pad "3" thru_hole circle
			(at 1.27 -2.210054)
			(size 0.8636 0.8636)
			(drill 0.508)
			(layers "*.Cu" "*.Mask")
			(remove_unused_layers no)
			(net "GND")
			(clearance 0.8255)
			(thermal_gap 0.8255)
		)
		(pad "4" thru_hole circle
			(at -1.279906 -2.210054)
			(size 0.8636 0.8636)
			(drill 0.508)
			(layers "*.Cu" "*.Mask")
			(remove_unused_layers no)
			(net "GND")
			(clearance 0.8255)
			(thermal_gap 0.8255)
		)
		(pad "5" thru_hole circle
			(at -2.210054 -1.27)
			(size 0.8636 0.8636)
			(drill 0.508)
			(layers "*.Cu" "*.Mask")
			(remove_unused_layers no)
			(net "GND")
			(clearance 0.8255)
			(thermal_gap 0.8255)
		)
		(pad "6" thru_hole circle
			(at -2.549906 0)
			(size 0.8636 0.8636)
			(drill 0.508)
			(layers "*.Cu" "*.Mask")
			(remove_unused_layers no)
			(net "GND")
			(clearance 0.8255)
			(thermal_gap 0.8255)
		)
		(zone
			(layers "F.Cu" "B.Cu" "In1.Cu" "In2.Cu" "In3.Cu" "In4.Cu" "In5.Cu" "In6.Cu")
			(hatch none 0.5)
			(connect_pads
				(clearance 0)
			)
			(min_thickness 0.25)
			(keepout
				(tracks allowed)
				(vias not_allowed)
				(pads allowed)
				(copperpour not_allowed)
				(footprints allowed)
			)
			(placement
				(enabled no)
				(sheetname "")
			)
			(fill
				(thermal_gap 0.5)
				(thermal_bridge_width 0.5)
				(island_removal_mode 0)
			)
			(polygon
				(pts
					(arc
						(start 74.318114 -174.000668)
						(mid 65.682114 -174.000668)
						(end 74.318114 -174.000668)
					)
				)
			)
		)
		(zone
			(layers "F.Cu" "B.Cu" "In1.Cu" "In2.Cu" "In3.Cu" "In4.Cu" "In5.Cu" "In6.Cu")
			(hatch none 0.5)
			(connect_pads
				(clearance 0)
			)
			(min_thickness 0.25)
			(keepout
				(tracks not_allowed)
				(vias allowed)
				(pads allowed)
				(copperpour not_allowed)
				(footprints allowed)
			)
			(placement
				(enabled no)
				(sheetname "")
			)
			(fill
				(thermal_gap 0.5)
				(thermal_bridge_width 0.5)
				(island_removal_mode 0)
			)
			(polygon
				(pts
					(arc
						(start 72.339454 -172.388276)
						(mid 70.000194 -167.489173)
						(end 67.66052 -172.388276)
					)
					(arc
						(start 67.66052 -172.388276)
						(mid 67.906487 -172.828642)
						(end 67.991736 -173.32579)
					)
					(arc
						(start 67.991736 -173.99762)
						(mid 70.000114 -176.005998)
						(end 72.008238 -173.99762)
					)
					(arc
						(start 72.008238 -173.32579)
						(mid 72.093473 -172.828636)
						(end 72.339454 -172.388276)
					)
				)
			)
		)
	)
	(footprint ""
		(layer "F.Cu")
		(at 40.5638 -313.4614 180)
		(property "Reference" "D29"
			(at 0 0 180)
			(layer "F.SilkS")
			(hide yes)
			(effects
				(font
					(size 1.27 1.27)
				)
			)
		)
		(property "Value" "RB551V30-1-GP"
			(at 0 -6.7818 180)
			(unlocked yes)
			(layer "F.Fab")
			(hide yes)
			(effects
				(font
					(size 1.016 1.016)
					(thickness 0.1524)
				)
			)
		)
		(property "Device Type" "SOD323AKH44"
			(at 0 -8.6868 180)
			(unlocked yes)
			(layer "F.Fab")
			(hide yes)
			(effects
				(font
					(size 1.016 1.016)
					(thickness 0.1524)
				)
			)
		)
		(duplicate_pad_numbers_are_jumpers no)
		(fp_line
			(start 0.889 2.159)
			(end -0.889 2.159)
			(stroke
				(width 0.1524)
				(type default)
			)
			(layer "F.SilkS")
		)
		(fp_line
			(start 0.889 -1.9304)
			(end 0.889 2.159)
			(stroke
				(width 0.1524)
				(type default)
			)
			(layer "F.SilkS")
		)
		(fp_line
			(start 0.762 2.0574)
			(end -0.762 2.0574)
			(stroke
				(width 0.508)
				(type default)
			)
			(layer "F.SilkS")
		)
		(fp_line
			(start -0.889 2.159)
			(end -0.889 -1.9304)
			(stroke
				(width 0.1524)
				(type default)
			)
			(layer "F.SilkS")
		)
		(fp_line
			(start -0.889 -1.9304)
			(end 0.889 -1.9304)
			(stroke
				(width 0.1524)
				(type default)
			)
			(layer "F.SilkS")
		)
		(fp_rect
			(start -1.016 2.3114)
			(end 1.016 -2.0066)
			(stroke
				(width 0)
				(type default)
			)
			(fill no)
			(layer "F.CrtYd")
		)
		(fp_poly
			(pts
				(xy -1.016 -2.0066) (xy 1.016 -2.0066) (xy 1.016 2.3114) (xy -1.016 2.3114)
			)
			(stroke
				(width 0)
				(type default)
			)
			(fill no)
			(layer "F.Fab")
		)
		(pad "A" smd rect
			(at 0 -1.143 180)
			(size 0.5588 1.016)
			(layers "F.Cu" "F.Mask" "F.Paste")
			(net "SW_SSD11_R")
		)
		(pad "K" smd rect
			(at 0 1.143 180)
			(size 0.5588 1.016)
			(layers "F.Cu" "F.Mask" "F.Paste")
			(net "SW_SSD11_N")
		)
	)
	(footprint ""
		(layer "F.Cu")
		(at 32.004 -374.65 180)
		(property "Reference" "R331"
			(at 0 0 180)
			(layer "F.SilkS")
			(hide yes)
			(effects
				(font
					(size 1.27 1.27)
				)
			)
		)
		(property "Value" "4K7R2F-GP"
			(at 0.064008 -3.993896 180)
			(unlocked yes)
			(layer "F.Fab")
			(hide yes)
			(effects
				(font
					(size 1.016 1.016)
					(thickness 0.1524)
				)
			)
		)
		(property "Device Type" "R402H16"
			(at 0.064008 -5.517896 180)
			(unlocked yes)
			(layer "F.Fab")
			(hide yes)
			(effects
				(font
					(size 1.016 1.016)
					(thickness 0.1524)
				)
			)
		)
		(duplicate_pad_numbers_are_jumpers no)
		(fp_line
			(start 0.508 -0.9398)
			(end -0.508 -0.9398)
			(stroke
				(width 0.1524)
				(type default)
			)
			(layer "F.SilkS")
		)
		(fp_line
			(start -0.508 -0.9398)
			(end -0.508 0.9398)
			(stroke
				(width 0.1524)
				(type default)
			)
			(layer "F.SilkS")
		)
		(fp_rect
			(start -0.508 0.9398)
			(end 0.508 -0.9398)
			(stroke
				(width 0)
				(type default)
			)
			(fill no)
			(layer "F.CrtYd")
		)
		(fp_rect
			(start -0.508 0.9398)
			(end 0.508 -0.9398)
			(stroke
				(width 0)
				(type default)
			)
			(fill no)
			(layer "F.Fab")
		)
		(pad "1" smd custom
			(at 0 -0.4445 180)
			(size 0.1397 0.1397)
			(layers "F.Cu" "F.Mask" "F.Paste")
			(net "P3V3")
			(options
				(clearance outline)
				(anchor circle)
			)
			(primitives
				(gr_poly
					(pts
						(arc
							(start -0.1778 -0.2794)
							(mid -0.249642 -0.249642)
							(end -0.2794 -0.1778)
						)
						(arc
							(start -0.2794 0.1778)
							(mid -0.249642 0.249642)
							(end -0.1778 0.2794)
						)
						(arc
							(start 0.1778 0.2794)
							(mid 0.249642 0.249642)
							(end 0.2794 0.1778)
						)
						(arc
							(start 0.2794 -0.1778)
							(mid 0.249642 -0.249642)
							(end 0.1778 -0.2794)
						)
					)
					(width 0)
					(fill yes)
				)
			)
		)
		(pad "2" smd custom
			(at 0 0.4445 180)
			(size 0.1397 0.1397)
			(layers "F.Cu" "F.Mask" "F.Paste")
			(net "I2C_B_TMP4_A2")
			(options
				(clearance outline)
				(anchor circle)
			)
			(primitives
				(gr_poly
					(pts
						(arc
							(start -0.1778 -0.2794)
							(mid -0.249642 -0.249642)
							(end -0.2794 -0.1778)
						)
						(arc
							(start -0.2794 0.1778)
							(mid -0.249642 0.249642)
							(end -0.1778 0.2794)
						)
						(arc
							(start 0.1778 0.2794)
							(mid 0.249642 0.249642)
							(end 0.2794 0.1778)
						)
						(arc
							(start 0.2794 -0.1778)
							(mid 0.249642 -0.249642)
							(end 0.1778 -0.2794)
						)
					)
					(width 0)
					(fill yes)
				)
			)
		)
	)
	(footprint ""
		(layer "F.Cu")
		(at 222.0468 -85.979)
		(property "Reference" "PC1203"
			(at 0 0 0)
			(layer "F.SilkS")
			(hide yes)
			(effects
				(font
					(size 1.27 1.27)
				)
			)
		)
		(property "Value" "SCD01U50V2KX-1GP"
			(at 1.1811 -2.7051 0)
			(unlocked yes)
			(layer "F.Fab")
			(hide yes)
			(effects
				(font
					(size 1.016 1.016)
					(thickness 0.1524)
				)
			)
		)
		(property "Device Type" "C402H22"
			(at 1.1811 -4.2291 0)
			(unlocked yes)
			(layer "F.Fab")
			(hide yes)
			(effects
				(font
					(size 1.016 1.016)
					(thickness 0.1524)
				)
			)
		)
		(duplicate_pad_numbers_are_jumpers no)
		(fp_rect
			(start -0.4318 0.9525)
			(end 0.4318 -0.9525)
			(stroke
				(width 0)
				(type default)
			)
			(fill no)
			(layer "F.CrtYd")
		)
		(fp_rect
			(start -0.4318 0.9525)
			(end 0.4318 -0.9525)
			(stroke
				(width 0)
				(type default)
			)
			(fill no)
			(layer "F.Fab")
		)
		(pad "1" smd custom
			(at 0 -0.4445)
			(size 0.1524 0.1524)
			(layers "F.Cu" "F.Mask" "F.Paste")
			(net "P12V_SSD4")
			(options
				(clearance outline)
				(anchor circle)
			)
			(primitives
				(gr_poly
					(pts
						(arc
							(start 0.3048 -0.2032)
							(mid 0.275042 -0.275042)
							(end 0.2032 -0.3048)
						)
						(arc
							(start -0.2032 -0.3048)
							(mid -0.275042 -0.275042)
							(end -0.3048 -0.2032)
						)
						(arc
							(start -0.3048 0.2032)
							(mid -0.275042 0.275042)
							(end -0.2032 0.3048)
						)
						(arc
							(start 0.2032 0.3048)
							(mid 0.275042 0.275042)
							(end 0.3048 0.2032)
						)
					)
					(width 0)
					(fill yes)
				)
			)
		)
		(pad "2" smd custom
			(at 0 0.4445)
			(size 0.1524 0.1524)
			(layers "F.Cu" "F.Mask" "F.Paste")
			(net "GND")
			(options
				(clearance outline)
				(anchor circle)
			)
			(primitives
				(gr_poly
					(pts
						(arc
							(start 0.3048 -0.2032)
							(mid 0.275042 -0.275042)
							(end 0.2032 -0.3048)
						)
						(arc
							(start -0.2032 -0.3048)
							(mid -0.275042 -0.275042)
							(end -0.3048 -0.2032)
						)
						(arc
							(start -0.3048 0.2032)
							(mid -0.275042 0.275042)
							(end -0.2032 0.3048)
						)
						(arc
							(start 0.2032 0.3048)
							(mid 0.275042 0.275042)
							(end 0.3048 0.2032)
						)
					)
					(width 0)
					(fill yes)
				)
			)
		)
	)
	(footprint ""
		(layer "F.Cu")
		(at 33.1089 -308.4449)
		(property "Reference" "R9852"
			(at 0 0 0)
			(layer "F.SilkS")
			(hide yes)
			(effects
				(font
					(size 1.27 1.27)
				)
			)
		)
		(property "Value" "47KR2J-2-GP"
			(at 0.064008 -3.993896 0)
			(unlocked yes)
			(layer "F.Fab")
			(hide yes)
			(effects
				(font
					(size 1.016 1.016)
					(thickness 0.1524)
				)
			)
		)
		(property "Device Type" "R402H16"
			(at 0.064008 -5.517896 0)
			(unlocked yes)
			(layer "F.Fab")
			(hide yes)
			(effects
				(font
					(size 1.016 1.016)
					(thickness 0.1524)
				)
			)
		)
		(duplicate_pad_numbers_are_jumpers no)
		(fp_line
			(start -0.508 -0.9398)
			(end -0.508 0.9398)
			(stroke
				(width 0.1524)
				(type default)
			)
			(layer "F.SilkS")
		)
		(fp_line
			(start 0.508 -0.9398)
			(end -0.508 -0.9398)
			(stroke
				(width 0.1524)
				(type default)
			)
			(layer "F.SilkS")
		)
		(fp_rect
			(start -0.508 0.9398)
			(end 0.508 -0.9398)
			(stroke
				(width 0)
				(type default)
			)
			(fill no)
			(layer "F.CrtYd")
		)
		(fp_rect
			(start -0.508 0.9398)
			(end 0.508 -0.9398)
			(stroke
				(width 0)
				(type default)
			)
			(fill no)
			(layer "F.Fab")
		)
		(pad "1" smd custom
			(at 0 -0.4445)
			(size 0.1397 0.1397)
			(layers "F.Cu" "F.Mask" "F.Paste")
			(net "P12V")
			(options
				(clearance outline)
				(anchor circle)
			)
			(primitives
				(gr_poly
					(pts
						(arc
							(start -0.1778 -0.2794)
							(mid -0.249642 -0.249642)
							(end -0.2794 -0.1778)
						)
						(arc
							(start -0.2794 0.1778)
							(mid -0.249642 0.249642)
							(end -0.1778 0.2794)
						)
						(arc
							(start 0.1778 0.2794)
							(mid 0.249642 0.249642)
							(end 0.2794 0.1778)
						)
						(arc
							(start 0.2794 -0.1778)
							(mid 0.249642 -0.249642)
							(end 0.1778 -0.2794)
						)
					)
					(width 0)
					(fill yes)
				)
			)
		)
		(pad "2" smd custom
			(at 0 0.4445)
			(size 0.1397 0.1397)
			(layers "F.Cu" "F.Mask" "F.Paste")
			(net "P12V_MOST11_GATE")
			(options
				(clearance outline)
				(anchor circle)
			)
			(primitives
				(gr_poly
					(pts
						(arc
							(start -0.1778 -0.2794)
							(mid -0.249642 -0.249642)
							(end -0.2794 -0.1778)
						)
						(arc
							(start -0.2794 0.1778)
							(mid -0.249642 0.249642)
							(end -0.1778 0.2794)
						)
						(arc
							(start 0.1778 0.2794)
							(mid 0.249642 0.249642)
							(end 0.2794 0.1778)
						)
						(arc
							(start 0.2794 -0.1778)
							(mid 0.249642 -0.249642)
							(end 0.1778 -0.2794)
						)
					)
					(width 0)
					(fill yes)
				)
			)
		)
	)
	(footprint ""
		(layer "F.Cu")
		(at 209.296 -87.122 180)
		(property "Reference" "R570"
			(at 0 0 180)
			(layer "F.SilkS")
			(hide yes)
			(effects
				(font
					(size 1.27 1.27)
				)
			)
		)
		(property "Value" "300KR2F-GP"
			(at 0.064008 -3.993896 180)
			(unlocked yes)
			(layer "F.Fab")
			(hide yes)
			(effects
				(font
					(size 1.016 1.016)
					(thickness 0.1524)
				)
			)
		)
		(property "Device Type" "R402H16"
			(at 0.064008 -5.517896 180)
			(unlocked yes)
			(layer "F.Fab")
			(hide yes)
			(effects
				(font
					(size 1.016 1.016)
					(thickness 0.1524)
				)
			)
		)
		(duplicate_pad_numbers_are_jumpers no)
		(fp_line
			(start 0.508 -0.9398)
			(end -0.508 -0.9398)
			(stroke
				(width 0.1524)
				(type default)
			)
			(layer "F.SilkS")
		)
		(fp_line
			(start -0.508 -0.9398)
			(end -0.508 0.9398)
			(stroke
				(width 0.1524)
				(type default)
			)
			(layer "F.SilkS")
		)
		(fp_rect
			(start -0.508 0.9398)
			(end 0.508 -0.9398)
			(stroke
				(width 0)
				(type default)
			)
			(fill no)
			(layer "F.CrtYd")
		)
		(fp_rect
			(start -0.508 0.9398)
			(end 0.508 -0.9398)
			(stroke
				(width 0)
				(type default)
			)
			(fill no)
			(layer "F.Fab")
		)
		(pad "1" smd custom
			(at 0 -0.4445 180)
			(size 0.1397 0.1397)
			(layers "F.Cu" "F.Mask" "F.Paste")
			(net "SW_SSD4_N")
			(options
				(clearance outline)
				(anchor circle)
			)
			(primitives
				(gr_poly
					(pts
						(arc
							(start -0.1778 -0.2794)
							(mid -0.249642 -0.249642)
							(end -0.2794 -0.1778)
						)
						(arc
							(start -0.2794 0.1778)
							(mid -0.249642 0.249642)
							(end -0.1778 0.2794)
						)
						(arc
							(start 0.1778 0.2794)
							(mid 0.249642 0.249642)
							(end 0.2794 0.1778)
						)
						(arc
							(start 0.2794 -0.1778)
							(mid 0.249642 -0.249642)
							(end 0.1778 -0.2794)
						)
					)
					(width 0)
					(fill yes)
				)
			)
		)
		(pad "2" smd custom
			(at 0 0.4445 180)
			(size 0.1397 0.1397)
			(layers "F.Cu" "F.Mask" "F.Paste")
			(net "P12V")
			(options
				(clearance outline)
				(anchor circle)
			)
			(primitives
				(gr_poly
					(pts
						(arc
							(start -0.1778 -0.2794)
							(mid -0.249642 -0.249642)
							(end -0.2794 -0.1778)
						)
						(arc
							(start -0.2794 0.1778)
							(mid -0.249642 0.249642)
							(end -0.1778 0.2794)
						)
						(arc
							(start 0.1778 0.2794)
							(mid 0.249642 0.249642)
							(end 0.2794 0.1778)
						)
						(arc
							(start 0.2794 -0.1778)
							(mid 0.249642 -0.249642)
							(end 0.1778 -0.2794)
						)
					)
					(width 0)
					(fill yes)
				)
			)
		)
	)
	(footprint ""
		(layer "F.Cu")
		(at 35.14725 -350.01454 -90)
		(property "Reference" "SR1133"
			(at 0 0 270)
			(layer "F.SilkS")
			(hide yes)
			(effects
				(font
					(size 1.27 1.27)
				)
			)
		)
		(property "Value" "4K7R2F-GP"
			(at 0.064008 -3.993896 270)
			(unlocked yes)
			(layer "F.Fab")
			(hide yes)
			(effects
				(font
					(size 1.016 1.016)
					(thickness 0.1524)
				)
			)
		)
		(property "Device Type" "R402H16"
			(at 0.064008 -5.517896 270)
			(unlocked yes)
			(layer "F.Fab")
			(hide yes)
			(effects
				(font
					(size 1.016 1.016)
					(thickness 0.1524)
				)
			)
		)
		(duplicate_pad_numbers_are_jumpers no)
		(fp_line
			(start -0.508 -0.9398)
			(end -0.508 0.9398)
			(stroke
				(width 0.1524)
				(type default)
			)
			(layer "F.SilkS")
		)
		(fp_line
			(start 0.508 -0.9398)
			(end -0.508 -0.9398)
			(stroke
				(width 0.1524)
				(type default)
			)
			(layer "F.SilkS")
		)
		(fp_rect
			(start -0.508 0.9398)
			(end 0.508 -0.9398)
			(stroke
				(width 0)
				(type default)
			)
			(fill no)
			(layer "F.CrtYd")
		)
		(fp_rect
			(start -0.508 0.9398)
			(end 0.508 -0.9398)
			(stroke
				(width 0)
				(type default)
			)
			(fill no)
			(layer "F.Fab")
		)
		(pad "1" smd custom
			(at 0 -0.4445 270)
			(size 0.1397 0.1397)
			(layers "F.Cu" "F.Mask" "F.Paste")
			(net "P3V3")
			(options
				(clearance outline)
				(anchor circle)
			)
			(primitives
				(gr_poly
					(pts
						(arc
							(start -0.1778 -0.2794)
							(mid -0.249642 -0.249642)
							(end -0.2794 -0.1778)
						)
						(arc
							(start -0.2794 0.1778)
							(mid -0.249642 0.249642)
							(end -0.1778 0.2794)
						)
						(arc
							(start 0.1778 0.2794)
							(mid 0.249642 0.249642)
							(end 0.2794 0.1778)
						)
						(arc
							(start 0.2794 -0.1778)
							(mid 0.249642 -0.249642)
							(end 0.1778 -0.2794)
						)
					)
					(width 0)
					(fill yes)
				)
			)
		)
		(pad "2" smd custom
			(at 0 0.4445 270)
			(size 0.1397 0.1397)
			(layers "F.Cu" "F.Mask" "F.Paste")
			(net "SSD6_CLK0_OE_MOS_N")
			(options
				(clearance outline)
				(anchor circle)
			)
			(primitives
				(gr_poly
					(pts
						(arc
							(start -0.1778 -0.2794)
							(mid -0.249642 -0.249642)
							(end -0.2794 -0.1778)
						)
						(arc
							(start -0.2794 0.1778)
							(mid -0.249642 0.249642)
							(end -0.1778 0.2794)
						)
						(arc
							(start 0.1778 0.2794)
							(mid 0.249642 0.249642)
							(end 0.2794 0.1778)
						)
						(arc
							(start 0.2794 -0.1778)
							(mid 0.249642 -0.249642)
							(end 0.1778 -0.2794)
						)
					)
					(width 0)
					(fill yes)
				)
			)
		)
	)
	(footprint ""
		(layer "F.Cu")
		(at 40.8686 -416.4584 180)
		(property "Reference" "D28"
			(at 0 0 180)
			(layer "F.SilkS")
			(hide yes)
			(effects
				(font
					(size 1.27 1.27)
				)
			)
		)
		(property "Value" "RB551V30-1-GP"
			(at 0 -6.7818 180)
			(unlocked yes)
			(layer "F.Fab")
			(hide yes)
			(effects
				(font
					(size 1.016 1.016)
					(thickness 0.1524)
				)
			)
		)
		(property "Device Type" "SOD323AKH44"
			(at 0 -8.6868 180)
			(unlocked yes)
			(layer "F.Fab")
			(hide yes)
			(effects
				(font
					(size 1.016 1.016)
					(thickness 0.1524)
				)
			)
		)
		(duplicate_pad_numbers_are_jumpers no)
		(fp_line
			(start 0.889 2.159)
			(end -0.889 2.159)
			(stroke
				(width 0.1524)
				(type default)
			)
			(layer "F.SilkS")
		)
		(fp_line
			(start 0.889 -1.9304)
			(end 0.889 2.159)
			(stroke
				(width 0.1524)
				(type default)
			)
			(layer "F.SilkS")
		)
		(fp_line
			(start 0.762 2.0574)
			(end -0.762 2.0574)
			(stroke
				(width 0.508)
				(type default)
			)
			(layer "F.SilkS")
		)
		(fp_line
			(start -0.889 2.159)
			(end -0.889 -1.9304)
			(stroke
				(width 0.1524)
				(type default)
			)
			(layer "F.SilkS")
		)
		(fp_line
			(start -0.889 -1.9304)
			(end 0.889 -1.9304)
			(stroke
				(width 0.1524)
				(type default)
			)
			(layer "F.SilkS")
		)
		(fp_rect
			(start -1.016 2.3114)
			(end 1.016 -2.0066)
			(stroke
				(width 0)
				(type default)
			)
			(fill no)
			(layer "F.CrtYd")
		)
		(fp_poly
			(pts
				(xy -1.016 -2.0066) (xy 1.016 -2.0066) (xy 1.016 2.3114) (xy -1.016 2.3114)
			)
			(stroke
				(width 0)
				(type default)
			)
			(fill no)
			(layer "F.Fab")
		)
		(pad "A" smd rect
			(at 0 -1.143 180)
			(size 0.5588 1.016)
			(layers "F.Cu" "F.Mask" "F.Paste")
			(net "SW_SSD10_R")
		)
		(pad "K" smd rect
			(at 0 1.143 180)
			(size 0.5588 1.016)
			(layers "F.Cu" "F.Mask" "F.Paste")
			(net "SW_SSD10_N")
		)
	)
	(footprint ""
		(layer "F.Cu")
		(at 87.122 -309.88)
		(property "Reference" "C8909"
			(at 0 0 0)
			(layer "F.SilkS")
			(hide yes)
			(effects
				(font
					(size 1.27 1.27)
				)
			)
		)
		(property "Value" "SC1U10V2KX-7-GP"
			(at 1.1811 -2.7051 0)
			(unlocked yes)
			(layer "F.Fab")
			(hide yes)
			(effects
				(font
					(size 1.016 1.016)
					(thickness 0.1524)
				)
			)
		)
		(property "Device Type" "C402H22"
			(at 1.1811 -4.2291 0)
			(unlocked yes)
			(layer "F.Fab")
			(hide yes)
			(effects
				(font
					(size 1.016 1.016)
					(thickness 0.1524)
				)
			)
		)
		(duplicate_pad_numbers_are_jumpers no)
		(fp_rect
			(start -0.4318 0.9525)
			(end 0.4318 -0.9525)
			(stroke
				(width 0)
				(type default)
			)
			(fill no)
			(layer "F.CrtYd")
		)
		(fp_rect
			(start -0.4318 0.9525)
			(end 0.4318 -0.9525)
			(stroke
				(width 0)
				(type default)
			)
			(fill no)
			(layer "F.Fab")
		)
		(pad "1" smd custom
			(at 0 -0.4445)
			(size 0.1524 0.1524)
			(layers "F.Cu" "F.Mask" "F.Paste")
			(net "VDDA_2")
			(options
				(clearance outline)
				(anchor circle)
			)
			(primitives
				(gr_poly
					(pts
						(arc
							(start 0.3048 -0.2032)
							(mid 0.275042 -0.275042)
							(end 0.2032 -0.3048)
						)
						(arc
							(start -0.2032 -0.3048)
							(mid -0.275042 -0.275042)
							(end -0.3048 -0.2032)
						)
						(arc
							(start -0.3048 0.2032)
							(mid -0.275042 0.275042)
							(end -0.2032 0.3048)
						)
						(arc
							(start 0.2032 0.3048)
							(mid 0.275042 0.275042)
							(end 0.3048 0.2032)
						)
					)
					(width 0)
					(fill yes)
				)
			)
		)
		(pad "2" smd custom
			(at 0 0.4445)
			(size 0.1524 0.1524)
			(layers "F.Cu" "F.Mask" "F.Paste")
			(net "GND")
			(options
				(clearance outline)
				(anchor circle)
			)
			(primitives
				(gr_poly
					(pts
						(arc
							(start 0.3048 -0.2032)
							(mid 0.275042 -0.275042)
							(end 0.2032 -0.3048)
						)
						(arc
							(start -0.2032 -0.3048)
							(mid -0.275042 -0.275042)
							(end -0.3048 -0.2032)
						)
						(arc
							(start -0.3048 0.2032)
							(mid -0.275042 0.275042)
							(end -0.2032 0.3048)
						)
						(arc
							(start 0.2032 0.3048)
							(mid 0.275042 0.275042)
							(end 0.3048 0.2032)
						)
					)
					(width 0)
					(fill yes)
				)
			)
		)
	)
	(footprint ""
		(layer "F.Cu")
		(at 85.471 -99.822 -90)
		(property "Reference" "PR9042"
			(at 0 0 270)
			(layer "F.SilkS")
			(hide yes)
			(effects
				(font
					(size 1.27 1.27)
				)
			)
		)
		(property "Value" "4K7R2F-GP"
			(at 0.064008 -3.993896 270)
			(unlocked yes)
			(layer "F.Fab")
			(hide yes)
			(effects
				(font
					(size 1.016 1.016)
					(thickness 0.1524)
				)
			)
		)
		(property "Device Type" "R402H16"
			(at 0.064008 -5.517896 270)
			(unlocked yes)
			(layer "F.Fab")
			(hide yes)
			(effects
				(font
					(size 1.016 1.016)
					(thickness 0.1524)
				)
			)
		)
		(duplicate_pad_numbers_are_jumpers no)
		(fp_line
			(start -0.508 -0.9398)
			(end -0.508 0.9398)
			(stroke
				(width 0.1524)
				(type default)
			)
			(layer "F.SilkS")
		)
		(fp_line
			(start 0.508 -0.9398)
			(end -0.508 -0.9398)
			(stroke
				(width 0.1524)
				(type default)
			)
			(layer "F.SilkS")
		)
		(fp_rect
			(start -0.508 0.9398)
			(end 0.508 -0.9398)
			(stroke
				(width 0)
				(type default)
			)
			(fill no)
			(layer "F.CrtYd")
		)
		(fp_rect
			(start -0.508 0.9398)
			(end 0.508 -0.9398)
			(stroke
				(width 0)
				(type default)
			)
			(fill no)
			(layer "F.Fab")
		)
		(pad "1" smd custom
			(at 0 -0.4445 270)
			(size 0.1397 0.1397)
			(layers "F.Cu" "F.Mask" "F.Paste")
			(net "CLK_BUF_EU4_SMB_A0_TRI")
			(options
				(clearance outline)
				(anchor circle)
			)
			(primitives
				(gr_poly
					(pts
						(arc
							(start -0.1778 -0.2794)
							(mid -0.249642 -0.249642)
							(end -0.2794 -0.1778)
						)
						(arc
							(start -0.2794 0.1778)
							(mid -0.249642 0.249642)
							(end -0.1778 0.2794)
						)
						(arc
							(start 0.1778 0.2794)
							(mid 0.249642 0.249642)
							(end 0.2794 0.1778)
						)
						(arc
							(start 0.2794 -0.1778)
							(mid 0.249642 -0.249642)
							(end 0.1778 -0.2794)
						)
					)
					(width 0)
					(fill yes)
				)
			)
		)
		(pad "2" smd custom
			(at 0 0.4445 270)
			(size 0.1397 0.1397)
			(layers "F.Cu" "F.Mask" "F.Paste")
			(net "GND")
			(options
				(clearance outline)
				(anchor circle)
			)
			(primitives
				(gr_poly
					(pts
						(arc
							(start -0.1778 -0.2794)
							(mid -0.249642 -0.249642)
							(end -0.2794 -0.1778)
						)
						(arc
							(start -0.2794 0.1778)
							(mid -0.249642 0.249642)
							(end -0.1778 0.2794)
						)
						(arc
							(start 0.1778 0.2794)
							(mid 0.249642 0.249642)
							(end 0.2794 0.1778)
						)
						(arc
							(start 0.2794 -0.1778)
							(mid 0.249642 -0.249642)
							(end 0.1778 -0.2794)
						)
					)
					(width 0)
					(fill yes)
				)
			)
		)
	)
	(footprint ""
		(layer "F.Cu")
		(at 216.789 -492.9632 -90)
		(property "Reference" "R384"
			(at 0 0 270)
			(layer "F.SilkS")
			(hide yes)
			(effects
				(font
					(size 1.27 1.27)
				)
			)
		)
		(property "Value" "0R2J-2-GP"
			(at 0.064008 -3.993896 270)
			(unlocked yes)
			(layer "F.Fab")
			(hide yes)
			(effects
				(font
					(size 1.016 1.016)
					(thickness 0.1524)
				)
			)
		)
		(property "Device Type" "R402H16"
			(at 0.064008 -5.517896 270)
			(unlocked yes)
			(layer "F.Fab")
			(hide yes)
			(effects
				(font
					(size 1.016 1.016)
					(thickness 0.1524)
				)
			)
		)
		(duplicate_pad_numbers_are_jumpers no)
		(fp_line
			(start -0.508 -0.9398)
			(end -0.508 0.9398)
			(stroke
				(width 0.1524)
				(type default)
			)
			(layer "F.SilkS")
		)
		(fp_line
			(start 0.508 -0.9398)
			(end -0.508 -0.9398)
			(stroke
				(width 0.1524)
				(type default)
			)
			(layer "F.SilkS")
		)
		(fp_rect
			(start -0.508 0.9398)
			(end 0.508 -0.9398)
			(stroke
				(width 0)
				(type default)
			)
			(fill no)
			(layer "F.CrtYd")
		)
		(fp_rect
			(start -0.508 0.9398)
			(end 0.508 -0.9398)
			(stroke
				(width 0)
				(type default)
			)
			(fill no)
			(layer "F.Fab")
		)
		(pad "1" smd custom
			(at 0 -0.4445 270)
			(size 0.1397 0.1397)
			(layers "F.Cu" "F.Mask" "F.Paste")
			(net "SDA_DR0_R")
			(options
				(clearance outline)
				(anchor circle)
			)
			(primitives
				(gr_poly
					(pts
						(arc
							(start -0.1778 -0.2794)
							(mid -0.249642 -0.249642)
							(end -0.2794 -0.1778)
						)
						(arc
							(start -0.2794 0.1778)
							(mid -0.249642 0.249642)
							(end -0.1778 0.2794)
						)
						(arc
							(start 0.1778 0.2794)
							(mid 0.249642 0.249642)
							(end 0.2794 0.1778)
						)
						(arc
							(start 0.2794 -0.1778)
							(mid 0.249642 -0.249642)
							(end 0.1778 -0.2794)
						)
					)
					(width 0)
					(fill yes)
				)
			)
		)
		(pad "2" smd custom
			(at 0 0.4445 270)
			(size 0.1397 0.1397)
			(layers "F.Cu" "F.Mask" "F.Paste")
			(net "SDA_DR0")
			(options
				(clearance outline)
				(anchor circle)
			)
			(primitives
				(gr_poly
					(pts
						(arc
							(start -0.1778 -0.2794)
							(mid -0.249642 -0.249642)
							(end -0.2794 -0.1778)
						)
						(arc
							(start -0.2794 0.1778)
							(mid -0.249642 0.249642)
							(end -0.1778 0.2794)
						)
						(arc
							(start 0.1778 0.2794)
							(mid 0.249642 0.249642)
							(end 0.2794 0.1778)
						)
						(arc
							(start 0.2794 -0.1778)
							(mid 0.249642 -0.249642)
							(end 0.1778 -0.2794)
						)
					)
					(width 0)
					(fill yes)
				)
			)
		)
	)
	(footprint ""
		(layer "F.Cu")
		(at 40.4876 -107.4674 180)
		(property "Reference" "D31"
			(at 0 0 180)
			(layer "F.SilkS")
			(hide yes)
			(effects
				(font
					(size 1.27 1.27)
				)
			)
		)
		(property "Value" "RB551V30-1-GP"
			(at 0 -6.7818 180)
			(unlocked yes)
			(layer "F.Fab")
			(hide yes)
			(effects
				(font
					(size 1.016 1.016)
					(thickness 0.1524)
				)
			)
		)
		(property "Device Type" "SOD323AKH44"
			(at 0 -8.6868 180)
			(unlocked yes)
			(layer "F.Fab")
			(hide yes)
			(effects
				(font
					(size 1.016 1.016)
					(thickness 0.1524)
				)
			)
		)
		(duplicate_pad_numbers_are_jumpers no)
		(fp_line
			(start 0.889 2.159)
			(end -0.889 2.159)
			(stroke
				(width 0.1524)
				(type default)
			)
			(layer "F.SilkS")
		)
		(fp_line
			(start 0.889 -1.9304)
			(end 0.889 2.159)
			(stroke
				(width 0.1524)
				(type default)
			)
			(layer "F.SilkS")
		)
		(fp_line
			(start 0.762 2.0574)
			(end -0.762 2.0574)
			(stroke
				(width 0.508)
				(type default)
			)
			(layer "F.SilkS")
		)
		(fp_line
			(start -0.889 2.159)
			(end -0.889 -1.9304)
			(stroke
				(width 0.1524)
				(type default)
			)
			(layer "F.SilkS")
		)
		(fp_line
			(start -0.889 -1.9304)
			(end 0.889 -1.9304)
			(stroke
				(width 0.1524)
				(type default)
			)
			(layer "F.SilkS")
		)
		(fp_rect
			(start -1.016 2.3114)
			(end 1.016 -2.0066)
			(stroke
				(width 0)
				(type default)
			)
			(fill no)
			(layer "F.CrtYd")
		)
		(fp_poly
			(pts
				(xy -1.016 -2.0066) (xy 1.016 -2.0066) (xy 1.016 2.3114) (xy -1.016 2.3114)
			)
			(stroke
				(width 0)
				(type default)
			)
			(fill no)
			(layer "F.Fab")
		)
		(pad "A" smd rect
			(at 0 -1.143 180)
			(size 0.5588 1.016)
			(layers "F.Cu" "F.Mask" "F.Paste")
			(net "SW_SSD13_R")
		)
		(pad "K" smd rect
			(at 0 1.143 180)
			(size 0.5588 1.016)
			(layers "F.Cu" "F.Mask" "F.Paste")
			(net "SW_SSD13_N")
		)
	)
	(footprint ""
		(layer "F.Cu")
		(at 48.641 -36.703 180)
		(property "Reference" "Q73"
			(at 0 0 180)
			(layer "F.SilkS")
			(hide yes)
			(effects
				(font
					(size 1.27 1.27)
				)
			)
		)
		(property "Value" "2N7002A-7-GP"
			(at 0.127 -8.9662 180)
			(unlocked yes)
			(layer "F.Fab")
			(hide yes)
			(effects
				(font
					(size 1.016 1.016)
					(thickness 0.1524)
				)
			)
		)
		(property "Device Type" "SOT23DGS2D4H48"
			(at 0.127 -10.4902 180)
			(unlocked yes)
			(layer "F.Fab")
			(hide yes)
			(effects
				(font
					(size 1.016 1.016)
					(thickness 0.1524)
				)
			)
		)
		(duplicate_pad_numbers_are_jumpers no)
		(fp_line
			(start 1.651 1.778)
			(end 1.651 -1.778)
			(stroke
				(width 0.1524)
				(type default)
			)
			(layer "F.SilkS")
		)
		(fp_line
			(start 1.651 -1.778)
			(end -1.651 -1.778)
			(stroke
				(width 0.1524)
				(type default)
			)
			(layer "F.SilkS")
		)
		(fp_line
			(start -1.651 1.778)
			(end 1.651 1.778)
			(stroke
				(width 0.1524)
				(type default)
			)
			(layer "F.SilkS")
		)
		(fp_line
			(start -1.651 -1.778)
			(end -1.651 1.778)
			(stroke
				(width 0.1524)
				(type default)
			)
			(layer "F.SilkS")
		)
		(fp_poly
			(pts
				(xy -1.778 1.8796) (xy -1.778 -1.8796) (xy 1.778 -1.8796) (xy 1.778 1.8796)
			)
			(stroke
				(width 0)
				(type default)
			)
			(fill no)
			(layer "F.CrtYd")
		)
		(fp_poly
			(pts
				(xy -1.778 1.8796) (xy -1.778 -1.8796) (xy 1.778 -1.8796) (xy 1.778 1.8796)
			)
			(stroke
				(width 0)
				(type default)
			)
			(fill no)
			(layer "F.Fab")
		)
		(pad "D" smd custom
			(at 0 -0.9525 180)
			(size 0.1905 0.1905)
			(layers "F.Cu" "F.Mask" "F.Paste")
			(net "SSD_ACT_DR9_MOS_N")
			(options
				(clearance outline)
				(anchor circle)
			)
			(primitives
				(gr_poly
					(pts
						(arc
							(start -0.1778 0.5715)
							(mid -0.321484 0.511984)
							(end -0.381 0.3683)
						)
						(arc
							(start -0.381 -0.3683)
							(mid -0.321484 -0.511984)
							(end -0.1778 -0.5715)
						)
						(arc
							(start 0.1778 -0.5715)
							(mid 0.321484 -0.511984)
							(end 0.381 -0.3683)
						)
						(arc
							(start 0.381 0.3683)
							(mid 0.321484 0.511984)
							(end 0.1778 0.5715)
						)
					)
					(width 0)
					(fill yes)
				)
			)
		)
		(pad "G" smd custom
			(at -0.98425 0.9525 180)
			(size 0.1905 0.1905)
			(layers "F.Cu" "F.Mask" "F.Paste")
			(net "ATTN_LED_DR9_AND_R")
			(options
				(clearance outline)
				(anchor circle)
			)
			(primitives
				(gr_poly
					(pts
						(arc
							(start -0.1778 0.5715)
							(mid -0.321484 0.511984)
							(end -0.381 0.3683)
						)
						(arc
							(start -0.381 -0.3683)
							(mid -0.321484 -0.511984)
							(end -0.1778 -0.5715)
						)
						(arc
							(start 0.1778 -0.5715)
							(mid 0.321484 -0.511984)
							(end 0.381 -0.3683)
						)
						(arc
							(start 0.381 0.3683)
							(mid 0.321484 0.511984)
							(end 0.1778 0.5715)
						)
					)
					(width 0)
					(fill yes)
				)
			)
		)
		(pad "S" smd custom
			(at 0.98425 0.9525 180)
			(size 0.1905 0.1905)
			(layers "F.Cu" "F.Mask" "F.Paste")
			(net "SSD_ACT_DR9_R")
			(options
				(clearance outline)
				(anchor circle)
			)
			(primitives
				(gr_poly
					(pts
						(arc
							(start -0.1778 0.5715)
							(mid -0.321484 0.511984)
							(end -0.381 0.3683)
						)
						(arc
							(start -0.381 -0.3683)
							(mid -0.321484 -0.511984)
							(end -0.1778 -0.5715)
						)
						(arc
							(start 0.1778 -0.5715)
							(mid 0.321484 -0.511984)
							(end 0.381 -0.3683)
						)
						(arc
							(start 0.381 0.3683)
							(mid 0.321484 0.511984)
							(end 0.1778 0.5715)
						)
					)
					(width 0)
					(fill yes)
				)
			)
		)
	)
	(footprint ""
		(layer "F.Cu")
		(at 43.50004 -453.099932)
		(property "Reference" "LED5"
			(at 0 0 0)
			(layer "F.SilkS")
			(hide yes)
			(effects
				(font
					(size 1.27 1.27)
				)
			)
		)
		(property "Value" "LED-RB-4-GP"
			(at 5.88899 1.80848 0)
			(unlocked yes)
			(layer "F.Fab")
			(hide yes)
			(effects
				(font
					(size 1.016 1.016)
					(thickness 0.1524)
				)
			)
		)
		(property "Device Type" "LED1613-4PH20"
			(at 5.88899 0.28448 0)
			(unlocked yes)
			(layer "F.Fab")
			(hide yes)
			(effects
				(font
					(size 1.016 1.016)
					(thickness 0.1524)
				)
			)
		)
		(duplicate_pad_numbers_are_jumpers no)
		(fp_line
			(start -1.4478 -0.9652)
			(end 1.4478 -0.9652)
			(stroke
				(width 0.1524)
				(type default)
			)
			(layer "F.SilkS")
		)
		(fp_line
			(start -1.4478 0.9652)
			(end -1.4478 -0.9652)
			(stroke
				(width 0.1524)
				(type default)
			)
			(layer "F.SilkS")
		)
		(fp_line
			(start -1.4478 0.9652)
			(end -1.4478 -0.9652)
			(stroke
				(width 0.508)
				(type default)
			)
			(layer "F.SilkS")
		)
		(fp_line
			(start 1.4478 -0.9652)
			(end 1.4478 0.9652)
			(stroke
				(width 0.1524)
				(type default)
			)
			(layer "F.SilkS")
		)
		(fp_line
			(start 1.4478 0.9652)
			(end -1.4478 0.9652)
			(stroke
				(width 0.1524)
				(type default)
			)
			(layer "F.SilkS")
		)
		(fp_rect
			(start -0.8001 0.6477)
			(end 0.8001 -0.6477)
			(stroke
				(width 0)
				(type default)
			)
			(fill no)
			(layer "F.CrtYd")
		)
		(fp_poly
			(pts
				(xy -1.7018 1.2192) (xy -1.7018 -0.06223) (xy -0.8001 -0.06223) (xy -0.8001 0.6477) (xy 0.8001 0.6477)
				(xy 0.8001 -0.6477) (xy -0.8001 -0.6477) (xy -0.8001 -0.0635) (xy -1.7018 -0.0635) (xy -1.7018 -1.2192)
				(xy 1.7018 -1.2192) (xy 1.7018 1.2192)
			)
			(stroke
				(width 0)
				(type default)
			)
			(fill no)
			(layer "F.CrtYd")
		)
		(fp_rect
			(start -1.7018 1.2192)
			(end 1.7018 -1.2192)
			(stroke
				(width 0)
				(type default)
			)
			(fill no)
			(layer "F.Fab")
		)
		(pad "1" smd rect
			(at -0.73025 0.4064)
			(size 0.9144 0.6096)
			(layers "F.Cu" "F.Mask" "F.Paste")
			(net "SSD_ACT_DR5_MOS_N")
		)
		(pad "2" smd rect
			(at -0.73025 -0.4064)
			(size 0.9144 0.6096)
			(layers "F.Cu" "F.Mask" "F.Paste")
			(net "ATTN_LED_DR5_MOS_N")
		)
		(pad "3" smd rect
			(at 0.73025 -0.4064)
			(size 0.9144 0.6096)
			(layers "F.Cu" "F.Mask" "F.Paste")
			(net "DRV_ATTN_5")
		)
		(pad "4" smd rect
			(at 0.73025 0.4064)
			(size 0.9144 0.6096)
			(layers "F.Cu" "F.Mask" "F.Paste")
			(net "DRV_ACT_5")
		)
	)
	(footprint ""
		(layer "F.Cu")
		(at 24.4094 -467.3346 90)
		(property "Reference" "SR1142"
			(at 0 0 90)
			(layer "F.SilkS")
			(hide yes)
			(effects
				(font
					(size 1.27 1.27)
				)
			)
		)
		(property "Value" "4K7R2J-2-GP"
			(at 0.064008 -3.993896 90)
			(unlocked yes)
			(layer "F.Fab")
			(hide yes)
			(effects
				(font
					(size 1.016 1.016)
					(thickness 0.1524)
				)
			)
		)
		(property "Device Type" "R402H16"
			(at 0.064008 -5.517896 90)
			(unlocked yes)
			(layer "F.Fab")
			(hide yes)
			(effects
				(font
					(size 1.016 1.016)
					(thickness 0.1524)
				)
			)
		)
		(duplicate_pad_numbers_are_jumpers no)
		(fp_line
			(start 0.508 -0.9398)
			(end -0.508 -0.9398)
			(stroke
				(width 0.1524)
				(type default)
			)
			(layer "F.SilkS")
		)
		(fp_line
			(start -0.508 -0.9398)
			(end -0.508 0.9398)
			(stroke
				(width 0.1524)
				(type default)
			)
			(layer "F.SilkS")
		)
		(fp_rect
			(start -0.508 0.9398)
			(end 0.508 -0.9398)
			(stroke
				(width 0)
				(type default)
			)
			(fill no)
			(layer "F.CrtYd")
		)
		(fp_rect
			(start -0.508 0.9398)
			(end 0.508 -0.9398)
			(stroke
				(width 0)
				(type default)
			)
			(fill no)
			(layer "F.Fab")
		)
		(pad "1" smd custom
			(at 0 -0.4445 90)
			(size 0.1397 0.1397)
			(layers "F.Cu" "F.Mask" "F.Paste")
			(net "P3V3")
			(options
				(clearance outline)
				(anchor circle)
			)
			(primitives
				(gr_poly
					(pts
						(arc
							(start -0.1778 -0.2794)
							(mid -0.249642 -0.249642)
							(end -0.2794 -0.1778)
						)
						(arc
							(start -0.2794 0.1778)
							(mid -0.249642 0.249642)
							(end -0.1778 0.2794)
						)
						(arc
							(start 0.1778 0.2794)
							(mid 0.249642 0.249642)
							(end 0.2794 0.1778)
						)
						(arc
							(start 0.2794 -0.1778)
							(mid 0.249642 -0.249642)
							(end 0.1778 -0.2794)
						)
					)
					(width 0)
					(fill yes)
				)
			)
		)
		(pad "2" smd custom
			(at 0 0.4445 90)
			(size 0.1397 0.1397)
			(layers "F.Cu" "F.Mask" "F.Paste")
			(net "SSD_ACT_DR10")
			(options
				(clearance outline)
				(anchor circle)
			)
			(primitives
				(gr_poly
					(pts
						(arc
							(start -0.1778 -0.2794)
							(mid -0.249642 -0.249642)
							(end -0.2794 -0.1778)
						)
						(arc
							(start -0.2794 0.1778)
							(mid -0.249642 0.249642)
							(end -0.1778 0.2794)
						)
						(arc
							(start 0.1778 0.2794)
							(mid 0.249642 0.249642)
							(end 0.2794 0.1778)
						)
						(arc
							(start 0.2794 -0.1778)
							(mid 0.249642 -0.249642)
							(end 0.1778 -0.2794)
						)
					)
					(width 0)
					(fill yes)
				)
			)
		)
	)
	(footprint ""
		(layer "F.Cu")
		(at 96.774 -225.806 90)
		(property "Reference" "R9504"
			(at 0 0 90)
			(layer "F.SilkS")
			(hide yes)
			(effects
				(font
					(size 1.27 1.27)
				)
			)
		)
		(property "Value" "4K7R2J-2-GP"
			(at 0.064008 -3.993896 90)
			(unlocked yes)
			(layer "F.Fab")
			(hide yes)
			(effects
				(font
					(size 1.016 1.016)
					(thickness 0.1524)
				)
			)
		)
		(property "Device Type" "R402H16"
			(at 0.064008 -5.517896 90)
			(unlocked yes)
			(layer "F.Fab")
			(hide yes)
			(effects
				(font
					(size 1.016 1.016)
					(thickness 0.1524)
				)
			)
		)
		(duplicate_pad_numbers_are_jumpers no)
		(fp_line
			(start 0.508 -0.9398)
			(end -0.508 -0.9398)
			(stroke
				(width 0.1524)
				(type default)
			)
			(layer "F.SilkS")
		)
		(fp_line
			(start -0.508 -0.9398)
			(end -0.508 0.9398)
			(stroke
				(width 0.1524)
				(type default)
			)
			(layer "F.SilkS")
		)
		(fp_rect
			(start -0.508 0.9398)
			(end 0.508 -0.9398)
			(stroke
				(width 0)
				(type default)
			)
			(fill no)
			(layer "F.CrtYd")
		)
		(fp_rect
			(start -0.508 0.9398)
			(end 0.508 -0.9398)
			(stroke
				(width 0)
				(type default)
			)
			(fill no)
			(layer "F.Fab")
		)
		(pad "1" smd custom
			(at 0 -0.4445 90)
			(size 0.1397 0.1397)
			(layers "F.Cu" "F.Mask" "F.Paste")
			(net "P3V3")
			(options
				(clearance outline)
				(anchor circle)
			)
			(primitives
				(gr_poly
					(pts
						(arc
							(start -0.1778 -0.2794)
							(mid -0.249642 -0.249642)
							(end -0.2794 -0.1778)
						)
						(arc
							(start -0.2794 0.1778)
							(mid -0.249642 0.249642)
							(end -0.1778 0.2794)
						)
						(arc
							(start 0.1778 0.2794)
							(mid 0.249642 0.249642)
							(end 0.2794 0.1778)
						)
						(arc
							(start 0.2794 -0.1778)
							(mid 0.249642 -0.249642)
							(end 0.1778 -0.2794)
						)
					)
					(width 0)
					(fill yes)
				)
			)
		)
		(pad "2" smd custom
			(at 0 0.4445 90)
			(size 0.1397 0.1397)
			(layers "F.Cu" "F.Mask" "F.Paste")
			(net "SSD7_CLK0_OE_N")
			(options
				(clearance outline)
				(anchor circle)
			)
			(primitives
				(gr_poly
					(pts
						(arc
							(start -0.1778 -0.2794)
							(mid -0.249642 -0.249642)
							(end -0.2794 -0.1778)
						)
						(arc
							(start -0.2794 0.1778)
							(mid -0.249642 0.249642)
							(end -0.1778 0.2794)
						)
						(arc
							(start 0.1778 0.2794)
							(mid 0.249642 0.249642)
							(end 0.2794 0.1778)
						)
						(arc
							(start 0.2794 -0.1778)
							(mid 0.249642 -0.249642)
							(end 0.1778 -0.2794)
						)
					)
					(width 0)
					(fill yes)
				)
			)
		)
	)
	(footprint ""
		(layer "F.Cu")
		(at 39.7383 -100.9269 -90)
		(property "Reference" "R9865"
			(at 0 0 270)
			(layer "F.SilkS")
			(hide yes)
			(effects
				(font
					(size 1.27 1.27)
				)
			)
		)
		(property "Value" "1KR2J-1-GP"
			(at 0.064008 -3.993896 270)
			(unlocked yes)
			(layer "F.Fab")
			(hide yes)
			(effects
				(font
					(size 1.016 1.016)
					(thickness 0.1524)
				)
			)
		)
		(property "Device Type" "R402H16"
			(at 0.064008 -5.517896 270)
			(unlocked yes)
			(layer "F.Fab")
			(hide yes)
			(effects
				(font
					(size 1.016 1.016)
					(thickness 0.1524)
				)
			)
		)
		(duplicate_pad_numbers_are_jumpers no)
		(fp_line
			(start -0.508 -0.9398)
			(end -0.508 0.9398)
			(stroke
				(width 0.1524)
				(type default)
			)
			(layer "F.SilkS")
		)
		(fp_line
			(start 0.508 -0.9398)
			(end -0.508 -0.9398)
			(stroke
				(width 0.1524)
				(type default)
			)
			(layer "F.SilkS")
		)
		(fp_rect
			(start -0.508 0.9398)
			(end 0.508 -0.9398)
			(stroke
				(width 0)
				(type default)
			)
			(fill no)
			(layer "F.CrtYd")
		)
		(fp_rect
			(start -0.508 0.9398)
			(end 0.508 -0.9398)
			(stroke
				(width 0)
				(type default)
			)
			(fill no)
			(layer "F.Fab")
		)
		(pad "1" smd custom
			(at 0 -0.4445 270)
			(size 0.1397 0.1397)
			(layers "F.Cu" "F.Mask" "F.Paste")
			(net "SSD13_PWREN")
			(options
				(clearance outline)
				(anchor circle)
			)
			(primitives
				(gr_poly
					(pts
						(arc
							(start -0.1778 -0.2794)
							(mid -0.249642 -0.249642)
							(end -0.2794 -0.1778)
						)
						(arc
							(start -0.2794 0.1778)
							(mid -0.249642 0.249642)
							(end -0.1778 0.2794)
						)
						(arc
							(start 0.1778 0.2794)
							(mid 0.249642 0.249642)
							(end 0.2794 0.1778)
						)
						(arc
							(start 0.2794 -0.1778)
							(mid 0.249642 -0.249642)
							(end 0.1778 -0.2794)
						)
					)
					(width 0)
					(fill yes)
				)
			)
		)
		(pad "2" smd custom
			(at 0 0.4445 270)
			(size 0.1397 0.1397)
			(layers "F.Cu" "F.Mask" "F.Paste")
			(net "SSD13_PWREN_R")
			(options
				(clearance outline)
				(anchor circle)
			)
			(primitives
				(gr_poly
					(pts
						(arc
							(start -0.1778 -0.2794)
							(mid -0.249642 -0.249642)
							(end -0.2794 -0.1778)
						)
						(arc
							(start -0.2794 0.1778)
							(mid -0.249642 0.249642)
							(end -0.1778 0.2794)
						)
						(arc
							(start 0.1778 0.2794)
							(mid 0.249642 0.249642)
							(end 0.2794 0.1778)
						)
						(arc
							(start 0.2794 -0.1778)
							(mid 0.249642 -0.249642)
							(end 0.1778 -0.2794)
						)
					)
					(width 0)
					(fill yes)
				)
			)
		)
	)
	(footprint ""
		(layer "F.Cu")
		(at 46.823884 -447.929 90)
		(property "Reference" "Q53"
			(at 0 0 90)
			(layer "F.SilkS")
			(hide yes)
			(effects
				(font
					(size 1.27 1.27)
				)
			)
		)
		(property "Value" "2N7002A-7-GP"
			(at 0.127 -8.9662 90)
			(unlocked yes)
			(layer "F.Fab")
			(hide yes)
			(effects
				(font
					(size 1.016 1.016)
					(thickness 0.1524)
				)
			)
		)
		(property "Device Type" "SOT23DGS2D4H48"
			(at 0.127 -10.4902 90)
			(unlocked yes)
			(layer "F.Fab")
			(hide yes)
			(effects
				(font
					(size 1.016 1.016)
					(thickness 0.1524)
				)
			)
		)
		(duplicate_pad_numbers_are_jumpers no)
		(fp_line
			(start 1.651 -1.778)
			(end -1.651 -1.778)
			(stroke
				(width 0.1524)
				(type default)
			)
			(layer "F.SilkS")
		)
		(fp_line
			(start -1.651 -1.778)
			(end -1.651 1.778)
			(stroke
				(width 0.1524)
				(type default)
			)
			(layer "F.SilkS")
		)
		(fp_line
			(start 1.651 1.778)
			(end 1.651 -1.778)
			(stroke
				(width 0.1524)
				(type default)
			)
			(layer "F.SilkS")
		)
		(fp_line
			(start -1.651 1.778)
			(end 1.651 1.778)
			(stroke
				(width 0.1524)
				(type default)
			)
			(layer "F.SilkS")
		)
		(fp_poly
			(pts
				(xy -1.778 1.8796) (xy -1.778 -1.8796) (xy 1.778 -1.8796) (xy 1.778 1.8796)
			)
			(stroke
				(width 0)
				(type default)
			)
			(fill no)
			(layer "F.CrtYd")
		)
		(fp_poly
			(pts
				(xy -1.778 1.8796) (xy -1.778 -1.8796) (xy 1.778 -1.8796) (xy 1.778 1.8796)
			)
			(stroke
				(width 0)
				(type default)
			)
			(fill no)
			(layer "F.Fab")
		)
		(pad "D" smd custom
			(at 0 -0.9525 90)
			(size 0.1905 0.1905)
			(layers "F.Cu" "F.Mask" "F.Paste")
			(net "SSD_ACT_DR5_MOS_N")
			(options
				(clearance outline)
				(anchor circle)
			)
			(primitives
				(gr_poly
					(pts
						(arc
							(start -0.1778 0.5715)
							(mid -0.321484 0.511984)
							(end -0.381 0.3683)
						)
						(arc
							(start -0.381 -0.3683)
							(mid -0.321484 -0.511984)
							(end -0.1778 -0.5715)
						)
						(arc
							(start 0.1778 -0.5715)
							(mid 0.321484 -0.511984)
							(end 0.381 -0.3683)
						)
						(arc
							(start 0.381 0.3683)
							(mid 0.321484 0.511984)
							(end 0.1778 0.5715)
						)
					)
					(width 0)
					(fill yes)
				)
			)
		)
		(pad "G" smd custom
			(at -0.98425 0.9525 90)
			(size 0.1905 0.1905)
			(layers "F.Cu" "F.Mask" "F.Paste")
			(net "ATTN_LED_DR5_AND_R")
			(options
				(clearance outline)
				(anchor circle)
			)
			(primitives
				(gr_poly
					(pts
						(arc
							(start -0.1778 0.5715)
							(mid -0.321484 0.511984)
							(end -0.381 0.3683)
						)
						(arc
							(start -0.381 -0.3683)
							(mid -0.321484 -0.511984)
							(end -0.1778 -0.5715)
						)
						(arc
							(start 0.1778 -0.5715)
							(mid 0.321484 -0.511984)
							(end 0.381 -0.3683)
						)
						(arc
							(start 0.381 0.3683)
							(mid 0.321484 0.511984)
							(end 0.1778 0.5715)
						)
					)
					(width 0)
					(fill yes)
				)
			)
		)
		(pad "S" smd custom
			(at 0.98425 0.9525 90)
			(size 0.1905 0.1905)
			(layers "F.Cu" "F.Mask" "F.Paste")
			(net "SSD_ACT_DR5_R")
			(options
				(clearance outline)
				(anchor circle)
			)
			(primitives
				(gr_poly
					(pts
						(arc
							(start -0.1778 0.5715)
							(mid -0.321484 0.511984)
							(end -0.381 0.3683)
						)
						(arc
							(start -0.381 -0.3683)
							(mid -0.321484 -0.511984)
							(end -0.1778 -0.5715)
						)
						(arc
							(start 0.1778 -0.5715)
							(mid 0.321484 -0.511984)
							(end 0.381 -0.3683)
						)
						(arc
							(start 0.381 0.3683)
							(mid 0.321484 0.511984)
							(end 0.1778 0.5715)
						)
					)
					(width 0)
					(fill yes)
				)
			)
		)
	)
	(footprint ""
		(layer "F.Cu")
		(at 36.576 -371.094 180)
		(property "Reference" "PC1244"
			(at 0 0 180)
			(layer "F.SilkS")
			(hide yes)
			(effects
				(font
					(size 1.27 1.27)
				)
			)
		)
		(property "Value" "SCD1U25V3KX-GP"
			(at 0 -2.8194 180)
			(unlocked yes)
			(layer "F.Fab")
			(hide yes)
			(effects
				(font
					(size 1.016 1.016)
					(thickness 0.1524)
				)
			)
		)
		(property "Device Type" "C603H36"
			(at 0 -4.3434 180)
			(unlocked yes)
			(layer "F.Fab")
			(hide yes)
			(effects
				(font
					(size 1.016 1.016)
					(thickness 0.1524)
				)
			)
		)
		(duplicate_pad_numbers_are_jumpers no)
		(fp_line
			(start 0.508 0)
			(end -0.508 0)
			(stroke
				(width 0.2032)
				(type default)
			)
			(layer "F.SilkS")
		)
		(fp_rect
			(start -0.5842 1.3335)
			(end 0.5842 -1.3335)
			(stroke
				(width 0)
				(type default)
			)
			(fill no)
			(layer "F.CrtYd")
		)
		(fp_rect
			(start -0.5842 1.3335)
			(end 0.5842 -1.3335)
			(stroke
				(width 0)
				(type default)
			)
			(fill no)
			(layer "F.Fab")
		)
		(pad "1" smd custom
			(at 0 -0.762 180)
			(size 0.2159 0.2159)
			(layers "F.Cu" "F.Mask" "F.Paste")
			(net "P3V3")
			(options
				(clearance outline)
				(anchor circle)
			)
			(primitives
				(gr_poly
					(pts
						(arc
							(start -0.3302 -0.4318)
							(mid -0.402042 -0.402042)
							(end -0.4318 -0.3302)
						)
						(arc
							(start -0.4318 0.3302)
							(mid -0.402042 0.402042)
							(end -0.3302 0.4318)
						)
						(arc
							(start 0.3302 0.4318)
							(mid 0.402042 0.402042)
							(end 0.4318 0.3302)
						)
						(arc
							(start 0.4318 -0.3302)
							(mid 0.402042 -0.402042)
							(end 0.3302 -0.4318)
						)
					)
					(width 0)
					(fill yes)
				)
			)
		)
		(pad "2" smd custom
			(at 0 0.762 180)
			(size 0.2159 0.2159)
			(layers "F.Cu" "F.Mask" "F.Paste")
			(net "GND")
			(options
				(clearance outline)
				(anchor circle)
			)
			(primitives
				(gr_poly
					(pts
						(arc
							(start -0.3302 -0.4318)
							(mid -0.402042 -0.402042)
							(end -0.4318 -0.3302)
						)
						(arc
							(start -0.4318 0.3302)
							(mid -0.402042 0.402042)
							(end -0.3302 0.4318)
						)
						(arc
							(start 0.3302 0.4318)
							(mid 0.402042 0.402042)
							(end 0.4318 0.3302)
						)
						(arc
							(start 0.4318 -0.3302)
							(mid 0.402042 -0.402042)
							(end 0.3302 -0.4318)
						)
					)
					(width 0)
					(fill yes)
				)
			)
		)
	)
	(footprint ""
		(layer "F.Cu")
		(at 221.996 -91.44 180)
		(property "Reference" "PC1200"
			(at 0 0 180)
			(layer "F.SilkS")
			(hide yes)
			(effects
				(font
					(size 1.27 1.27)
				)
			)
		)
		(property "Value" "SC22U25V6KX-GP-U"
			(at -2.860802 -5.279644 180)
			(unlocked yes)
			(layer "F.Fab")
			(hide yes)
			(effects
				(font
					(size 1.016 1.016)
					(thickness 0.1524)
				)
			)
		)
		(property "Device Type" "C1206-TO0D3H75"
			(at -2.860802 -6.803644 180)
			(unlocked yes)
			(layer "F.Fab")
			(hide yes)
			(effects
				(font
					(size 1.016 1.016)
					(thickness 0.1524)
				)
			)
		)
		(duplicate_pad_numbers_are_jumpers no)
		(fp_line
			(start 1.3081 2.3749)
			(end -1.3081 2.3749)
			(stroke
				(width 0.1524)
				(type default)
			)
			(layer "F.SilkS")
		)
		(fp_line
			(start 1.3081 -2.3749)
			(end 1.3081 2.3749)
			(stroke
				(width 0.1524)
				(type default)
			)
			(layer "F.SilkS")
		)
		(fp_line
			(start -1.3081 2.3749)
			(end -1.3081 -2.3749)
			(stroke
				(width 0.1524)
				(type default)
			)
			(layer "F.SilkS")
		)
		(fp_line
			(start -1.3081 -2.3749)
			(end 1.3081 -2.3749)
			(stroke
				(width 0.1524)
				(type default)
			)
			(layer "F.SilkS")
		)
		(fp_rect
			(start -0.8001 1.6002)
			(end 0.8001 -1.6002)
			(stroke
				(width 0)
				(type default)
			)
			(fill no)
			(layer "F.CrtYd")
		)
		(fp_poly
			(pts
				(xy -1.5621 2.4511) (xy -1.5621 1.6002) (xy 0.8001 1.6002) (xy 0.8001 -1.6002) (xy -0.8001 -1.6002)
				(xy -0.8001 1.5875) (xy -1.5621 1.5875) (xy -1.5621 -2.4511) (xy 1.5621 -2.4511) (xy 1.5621 2.4511)
			)
			(stroke
				(width 0)
				(type default)
			)
			(fill no)
			(layer "F.CrtYd")
		)
		(fp_rect
			(start -1.5621 2.4511)
			(end 1.5621 -2.4511)
			(stroke
				(width 0)
				(type default)
			)
			(fill no)
			(layer "F.Fab")
		)
		(pad "1" smd rect
			(at 0 -1.392936 180)
			(size 2.1082 1.4478)
			(layers "F.Cu" "F.Mask" "F.Paste")
			(net "P12V_SSD4")
		)
		(pad "2" smd rect
			(at 0 1.392936 180)
			(size 2.1082 1.4478)
			(layers "F.Cu" "F.Mask" "F.Paste")
			(net "GND")
		)
	)
	(footprint ""
		(layer "F.Cu")
		(at 38.0746 -414.8074)
		(property "Reference" "Q18"
			(at 0 0 0)
			(layer "F.SilkS")
			(hide yes)
			(effects
				(font
					(size 1.27 1.27)
				)
			)
		)
		(property "Value" "2N7002A-7-GP"
			(at 0.127 -8.9662 0)
			(unlocked yes)
			(layer "F.Fab")
			(hide yes)
			(effects
				(font
					(size 1.016 1.016)
					(thickness 0.1524)
				)
			)
		)
		(property "Device Type" "SOT23DGS2D4H48"
			(at 0.127 -10.4902 0)
			(unlocked yes)
			(layer "F.Fab")
			(hide yes)
			(effects
				(font
					(size 1.016 1.016)
					(thickness 0.1524)
				)
			)
		)
		(duplicate_pad_numbers_are_jumpers no)
		(fp_line
			(start -1.651 -1.778)
			(end -1.651 1.778)
			(stroke
				(width 0.1524)
				(type default)
			)
			(layer "F.SilkS")
		)
		(fp_line
			(start -1.651 1.778)
			(end 1.651 1.778)
			(stroke
				(width 0.1524)
				(type default)
			)
			(layer "F.SilkS")
		)
		(fp_line
			(start 1.651 -1.778)
			(end -1.651 -1.778)
			(stroke
				(width 0.1524)
				(type default)
			)
			(layer "F.SilkS")
		)
		(fp_line
			(start 1.651 1.778)
			(end 1.651 -1.778)
			(stroke
				(width 0.1524)
				(type default)
			)
			(layer "F.SilkS")
		)
		(fp_poly
			(pts
				(xy -1.778 1.8796) (xy -1.778 -1.8796) (xy 1.778 -1.8796) (xy 1.778 1.8796)
			)
			(stroke
				(width 0)
				(type default)
			)
			(fill no)
			(layer "F.CrtYd")
		)
		(fp_poly
			(pts
				(xy -1.778 1.8796) (xy -1.778 -1.8796) (xy 1.778 -1.8796) (xy 1.778 1.8796)
			)
			(stroke
				(width 0)
				(type default)
			)
			(fill no)
			(layer "F.Fab")
		)
		(pad "D" smd custom
			(at 0 -0.9525)
			(size 0.1905 0.1905)
			(layers "F.Cu" "F.Mask" "F.Paste")
			(net "SW_SSD10_R")
			(options
				(clearance outline)
				(anchor circle)
			)
			(primitives
				(gr_poly
					(pts
						(arc
							(start -0.1778 0.5715)
							(mid -0.321484 0.511984)
							(end -0.381 0.3683)
						)
						(arc
							(start -0.381 -0.3683)
							(mid -0.321484 -0.511984)
							(end -0.1778 -0.5715)
						)
						(arc
							(start 0.1778 -0.5715)
							(mid 0.321484 -0.511984)
							(end 0.381 -0.3683)
						)
						(arc
							(start 0.381 0.3683)
							(mid 0.321484 0.511984)
							(end 0.1778 0.5715)
						)
					)
					(width 0)
					(fill yes)
				)
			)
		)
		(pad "G" smd custom
			(at -0.98425 0.9525)
			(size 0.1905 0.1905)
			(layers "F.Cu" "F.Mask" "F.Paste")
			(net "SSD10_PWREN")
			(options
				(clearance outline)
				(anchor circle)
			)
			(primitives
				(gr_poly
					(pts
						(arc
							(start -0.1778 0.5715)
							(mid -0.321484 0.511984)
							(end -0.381 0.3683)
						)
						(arc
							(start -0.381 -0.3683)
							(mid -0.321484 -0.511984)
							(end -0.1778 -0.5715)
						)
						(arc
							(start 0.1778 -0.5715)
							(mid 0.321484 -0.511984)
							(end 0.381 -0.3683)
						)
						(arc
							(start 0.381 0.3683)
							(mid 0.321484 0.511984)
							(end 0.1778 0.5715)
						)
					)
					(width 0)
					(fill yes)
				)
			)
		)
		(pad "S" smd custom
			(at 0.98425 0.9525)
			(size 0.1905 0.1905)
			(layers "F.Cu" "F.Mask" "F.Paste")
			(net "GND")
			(options
				(clearance outline)
				(anchor circle)
			)
			(primitives
				(gr_poly
					(pts
						(arc
							(start -0.1778 0.5715)
							(mid -0.321484 0.511984)
							(end -0.381 0.3683)
						)
						(arc
							(start -0.381 -0.3683)
							(mid -0.321484 -0.511984)
							(end -0.1778 -0.5715)
						)
						(arc
							(start 0.1778 -0.5715)
							(mid 0.321484 -0.511984)
							(end 0.381 -0.3683)
						)
						(arc
							(start 0.381 0.3683)
							(mid 0.321484 0.511984)
							(end 0.1778 0.5715)
						)
					)
					(width 0)
					(fill yes)
				)
			)
		)
	)
	(footprint ""
		(layer "F.Cu")
		(at 94.996 -197.358 180)
		(property "Reference" "R9596"
			(at 0 0 180)
			(layer "F.SilkS")
			(hide yes)
			(effects
				(font
					(size 1.27 1.27)
				)
			)
		)
		(property "Value" "10R2F-L-GP"
			(at 0.064008 -3.993896 180)
			(unlocked yes)
			(layer "F.Fab")
			(hide yes)
			(effects
				(font
					(size 1.016 1.016)
					(thickness 0.1524)
				)
			)
		)
		(property "Device Type" "R402H14"
			(at 0.064008 -5.517896 180)
			(unlocked yes)
			(layer "F.Fab")
			(hide yes)
			(effects
				(font
					(size 1.016 1.016)
					(thickness 0.1524)
				)
			)
		)
		(duplicate_pad_numbers_are_jumpers no)
		(fp_line
			(start 0.508 -0.9398)
			(end -0.508 -0.9398)
			(stroke
				(width 0.1524)
				(type default)
			)
			(layer "F.SilkS")
		)
		(fp_line
			(start -0.508 -0.9398)
			(end -0.508 0.9398)
			(stroke
				(width 0.1524)
				(type default)
			)
			(layer "F.SilkS")
		)
		(fp_rect
			(start -0.508 0.9398)
			(end 0.508 -0.9398)
			(stroke
				(width 0)
				(type default)
			)
			(fill no)
			(layer "F.CrtYd")
		)
		(fp_rect
			(start -0.508 0.9398)
			(end 0.508 -0.9398)
			(stroke
				(width 0)
				(type default)
			)
			(fill no)
			(layer "F.Fab")
		)
		(pad "1" smd custom
			(at 0 -0.4445 180)
			(size 0.1397 0.1397)
			(layers "F.Cu" "F.Mask" "F.Paste")
			(net "SSD_PRSNT_NET4")
			(options
				(clearance outline)
				(anchor circle)
			)
			(primitives
				(gr_poly
					(pts
						(arc
							(start -0.1778 -0.2794)
							(mid -0.249642 -0.249642)
							(end -0.2794 -0.1778)
						)
						(arc
							(start -0.2794 0.1778)
							(mid -0.249642 0.249642)
							(end -0.1778 0.2794)
						)
						(arc
							(start 0.1778 0.2794)
							(mid 0.249642 0.249642)
							(end 0.2794 0.1778)
						)
						(arc
							(start 0.2794 -0.1778)
							(mid 0.249642 -0.249642)
							(end 0.1778 -0.2794)
						)
					)
					(width 0)
					(fill yes)
				)
			)
		)
		(pad "2" smd custom
			(at 0 0.4445 180)
			(size 0.1397 0.1397)
			(layers "F.Cu" "F.Mask" "F.Paste")
			(net "SSD_PRSNT4")
			(options
				(clearance outline)
				(anchor circle)
			)
			(primitives
				(gr_poly
					(pts
						(arc
							(start -0.1778 -0.2794)
							(mid -0.249642 -0.249642)
							(end -0.2794 -0.1778)
						)
						(arc
							(start -0.2794 0.1778)
							(mid -0.249642 0.249642)
							(end -0.1778 0.2794)
						)
						(arc
							(start 0.1778 0.2794)
							(mid 0.249642 0.249642)
							(end 0.2794 0.1778)
						)
						(arc
							(start 0.2794 -0.1778)
							(mid 0.249642 -0.249642)
							(end 0.1778 -0.2794)
						)
					)
					(width 0)
					(fill yes)
				)
			)
		)
	)
	(footprint ""
		(layer "F.Cu")
		(at 36.7538 -315.8744 180)
		(property "Reference" "C393"
			(at 0 0 180)
			(layer "F.SilkS")
			(hide yes)
			(effects
				(font
					(size 1.27 1.27)
				)
			)
		)
		(property "Value" "SCD1U25V2KX-2-GP"
			(at 1.1811 -2.7051 180)
			(unlocked yes)
			(layer "F.Fab")
			(hide yes)
			(effects
				(font
					(size 1.016 1.016)
					(thickness 0.1524)
				)
			)
		)
		(property "Device Type" "C402H22"
			(at 1.1811 -4.2291 180)
			(unlocked yes)
			(layer "F.Fab")
			(hide yes)
			(effects
				(font
					(size 1.016 1.016)
					(thickness 0.1524)
				)
			)
		)
		(duplicate_pad_numbers_are_jumpers no)
		(fp_rect
			(start -0.4318 0.9525)
			(end 0.4318 -0.9525)
			(stroke
				(width 0)
				(type default)
			)
			(fill no)
			(layer "F.CrtYd")
		)
		(fp_rect
			(start -0.4318 0.9525)
			(end 0.4318 -0.9525)
			(stroke
				(width 0)
				(type default)
			)
			(fill no)
			(layer "F.Fab")
		)
		(pad "1" smd custom
			(at 0 -0.4445 180)
			(size 0.1524 0.1524)
			(layers "F.Cu" "F.Mask" "F.Paste")
			(net "P12V")
			(options
				(clearance outline)
				(anchor circle)
			)
			(primitives
				(gr_poly
					(pts
						(arc
							(start 0.3048 -0.2032)
							(mid 0.275042 -0.275042)
							(end 0.2032 -0.3048)
						)
						(arc
							(start -0.2032 -0.3048)
							(mid -0.275042 -0.275042)
							(end -0.3048 -0.2032)
						)
						(arc
							(start -0.3048 0.2032)
							(mid -0.275042 0.275042)
							(end -0.2032 0.3048)
						)
						(arc
							(start 0.2032 0.3048)
							(mid 0.275042 0.275042)
							(end 0.3048 0.2032)
						)
					)
					(width 0)
					(fill yes)
				)
			)
		)
		(pad "2" smd custom
			(at 0 0.4445 180)
			(size 0.1524 0.1524)
			(layers "F.Cu" "F.Mask" "F.Paste")
			(net "SW_SSD11_N")
			(options
				(clearance outline)
				(anchor circle)
			)
			(primitives
				(gr_poly
					(pts
						(arc
							(start 0.3048 -0.2032)
							(mid 0.275042 -0.275042)
							(end 0.2032 -0.3048)
						)
						(arc
							(start -0.2032 -0.3048)
							(mid -0.275042 -0.275042)
							(end -0.3048 -0.2032)
						)
						(arc
							(start -0.3048 0.2032)
							(mid -0.275042 0.275042)
							(end -0.2032 0.3048)
						)
						(arc
							(start 0.2032 0.3048)
							(mid 0.275042 0.275042)
							(end 0.3048 0.2032)
						)
					)
					(width 0)
					(fill yes)
				)
			)
		)
	)
	(footprint ""
		(layer "F.Cu")
		(at 80.264 -154.178)
		(property "Reference" "SR976"
			(at 0 0 0)
			(layer "F.SilkS")
			(hide yes)
			(effects
				(font
					(size 1.27 1.27)
				)
			)
		)
		(property "Value" "2KR2F-3-GP"
			(at 0.064008 -3.993896 0)
			(unlocked yes)
			(layer "F.Fab")
			(hide yes)
			(effects
				(font
					(size 1.016 1.016)
					(thickness 0.1524)
				)
			)
		)
		(property "Device Type" "R402H16"
			(at 0.064008 -5.517896 0)
			(unlocked yes)
			(layer "F.Fab")
			(hide yes)
			(effects
				(font
					(size 1.016 1.016)
					(thickness 0.1524)
				)
			)
		)
		(duplicate_pad_numbers_are_jumpers no)
		(fp_line
			(start -0.508 -0.9398)
			(end -0.508 0.9398)
			(stroke
				(width 0.1524)
				(type default)
			)
			(layer "F.SilkS")
		)
		(fp_line
			(start 0.508 -0.9398)
			(end -0.508 -0.9398)
			(stroke
				(width 0.1524)
				(type default)
			)
			(layer "F.SilkS")
		)
		(fp_rect
			(start -0.508 0.9398)
			(end 0.508 -0.9398)
			(stroke
				(width 0)
				(type default)
			)
			(fill no)
			(layer "F.CrtYd")
		)
		(fp_rect
			(start -0.508 0.9398)
			(end 0.508 -0.9398)
			(stroke
				(width 0)
				(type default)
			)
			(fill no)
			(layer "F.Fab")
		)
		(pad "1" smd custom
			(at 0 -0.4445)
			(size 0.1397 0.1397)
			(layers "F.Cu" "F.Mask" "F.Paste")
			(net "P3V3")
			(options
				(clearance outline)
				(anchor circle)
			)
			(primitives
				(gr_poly
					(pts
						(arc
							(start -0.1778 -0.2794)
							(mid -0.249642 -0.249642)
							(end -0.2794 -0.1778)
						)
						(arc
							(start -0.2794 0.1778)
							(mid -0.249642 0.249642)
							(end -0.1778 0.2794)
						)
						(arc
							(start 0.1778 0.2794)
							(mid 0.249642 0.249642)
							(end 0.2794 0.1778)
						)
						(arc
							(start 0.2794 -0.1778)
							(mid 0.249642 -0.249642)
							(end 0.1778 -0.2794)
						)
					)
					(width 0)
					(fill yes)
				)
			)
		)
		(pad "2" smd custom
			(at 0 0.4445)
			(size 0.1397 0.1397)
			(layers "F.Cu" "F.Mask" "F.Paste")
			(net "SDA_DR3")
			(options
				(clearance outline)
				(anchor circle)
			)
			(primitives
				(gr_poly
					(pts
						(arc
							(start -0.1778 -0.2794)
							(mid -0.249642 -0.249642)
							(end -0.2794 -0.1778)
						)
						(arc
							(start -0.2794 0.1778)
							(mid -0.249642 0.249642)
							(end -0.1778 0.2794)
						)
						(arc
							(start 0.1778 0.2794)
							(mid 0.249642 0.249642)
							(end 0.2794 0.1778)
						)
						(arc
							(start 0.2794 -0.1778)
							(mid 0.249642 -0.249642)
							(end 0.1778 -0.2794)
						)
					)
					(width 0)
					(fill yes)
				)
			)
		)
	)
	(footprint ""
		(layer "F.Cu")
		(at 87.757 -446.786 90)
		(property "Reference" "R9500"
			(at 0 0 90)
			(layer "F.SilkS")
			(hide yes)
			(effects
				(font
					(size 1.27 1.27)
				)
			)
		)
		(property "Value" "4K7R2J-2-GP"
			(at 0.064008 -3.993896 90)
			(unlocked yes)
			(layer "F.Fab")
			(hide yes)
			(effects
				(font
					(size 1.016 1.016)
					(thickness 0.1524)
				)
			)
		)
		(property "Device Type" "R402H16"
			(at 0.064008 -5.517896 90)
			(unlocked yes)
			(layer "F.Fab")
			(hide yes)
			(effects
				(font
					(size 1.016 1.016)
					(thickness 0.1524)
				)
			)
		)
		(duplicate_pad_numbers_are_jumpers no)
		(fp_line
			(start 0.508 -0.9398)
			(end -0.508 -0.9398)
			(stroke
				(width 0.1524)
				(type default)
			)
			(layer "F.SilkS")
		)
		(fp_line
			(start -0.508 -0.9398)
			(end -0.508 0.9398)
			(stroke
				(width 0.1524)
				(type default)
			)
			(layer "F.SilkS")
		)
		(fp_rect
			(start -0.508 0.9398)
			(end 0.508 -0.9398)
			(stroke
				(width 0)
				(type default)
			)
			(fill no)
			(layer "F.CrtYd")
		)
		(fp_rect
			(start -0.508 0.9398)
			(end 0.508 -0.9398)
			(stroke
				(width 0)
				(type default)
			)
			(fill no)
			(layer "F.Fab")
		)
		(pad "1" smd custom
			(at 0 -0.4445 90)
			(size 0.1397 0.1397)
			(layers "F.Cu" "F.Mask" "F.Paste")
			(net "P3V3")
			(options
				(clearance outline)
				(anchor circle)
			)
			(primitives
				(gr_poly
					(pts
						(arc
							(start -0.1778 -0.2794)
							(mid -0.249642 -0.249642)
							(end -0.2794 -0.1778)
						)
						(arc
							(start -0.2794 0.1778)
							(mid -0.249642 0.249642)
							(end -0.1778 0.2794)
						)
						(arc
							(start 0.1778 0.2794)
							(mid 0.249642 0.249642)
							(end 0.2794 0.1778)
						)
						(arc
							(start 0.2794 -0.1778)
							(mid 0.249642 -0.249642)
							(end 0.1778 -0.2794)
						)
					)
					(width 0)
					(fill yes)
				)
			)
		)
		(pad "2" smd custom
			(at 0 0.4445 90)
			(size 0.1397 0.1397)
			(layers "F.Cu" "F.Mask" "F.Paste")
			(net "SSD5_CLK0_OE_N")
			(options
				(clearance outline)
				(anchor circle)
			)
			(primitives
				(gr_poly
					(pts
						(arc
							(start -0.1778 -0.2794)
							(mid -0.249642 -0.249642)
							(end -0.2794 -0.1778)
						)
						(arc
							(start -0.2794 0.1778)
							(mid -0.249642 0.249642)
							(end -0.1778 0.2794)
						)
						(arc
							(start 0.1778 0.2794)
							(mid 0.249642 0.249642)
							(end 0.2794 0.1778)
						)
						(arc
							(start 0.2794 -0.1778)
							(mid 0.249642 -0.249642)
							(end 0.1778 -0.2794)
						)
					)
					(width 0)
					(fill yes)
				)
			)
		)
	)
	(footprint ""
		(layer "F.Cu")
		(at 88.011 -106.299)
		(property "Reference" "C8932"
			(at 0 0 0)
			(layer "F.SilkS")
			(hide yes)
			(effects
				(font
					(size 1.27 1.27)
				)
			)
		)
		(property "Value" "SCD1U16V2KX-3GP"
			(at 1.1811 -2.7051 0)
			(unlocked yes)
			(layer "F.Fab")
			(hide yes)
			(effects
				(font
					(size 1.016 1.016)
					(thickness 0.1524)
				)
			)
		)
		(property "Device Type" "C402H22"
			(at 1.1811 -4.2291 0)
			(unlocked yes)
			(layer "F.Fab")
			(hide yes)
			(effects
				(font
					(size 1.016 1.016)
					(thickness 0.1524)
				)
			)
		)
		(duplicate_pad_numbers_are_jumpers no)
		(fp_rect
			(start -0.4318 0.9525)
			(end 0.4318 -0.9525)
			(stroke
				(width 0)
				(type default)
			)
			(fill no)
			(layer "F.CrtYd")
		)
		(fp_rect
			(start -0.4318 0.9525)
			(end 0.4318 -0.9525)
			(stroke
				(width 0)
				(type default)
			)
			(fill no)
			(layer "F.Fab")
		)
		(pad "1" smd custom
			(at 0 -0.4445)
			(size 0.1524 0.1524)
			(layers "F.Cu" "F.Mask" "F.Paste")
			(net "VDDA_4")
			(options
				(clearance outline)
				(anchor circle)
			)
			(primitives
				(gr_poly
					(pts
						(arc
							(start 0.3048 -0.2032)
							(mid 0.275042 -0.275042)
							(end 0.2032 -0.3048)
						)
						(arc
							(start -0.2032 -0.3048)
							(mid -0.275042 -0.275042)
							(end -0.3048 -0.2032)
						)
						(arc
							(start -0.3048 0.2032)
							(mid -0.275042 0.275042)
							(end -0.2032 0.3048)
						)
						(arc
							(start 0.2032 0.3048)
							(mid 0.275042 0.275042)
							(end 0.3048 0.2032)
						)
					)
					(width 0)
					(fill yes)
				)
			)
		)
		(pad "2" smd custom
			(at 0 0.4445)
			(size 0.1524 0.1524)
			(layers "F.Cu" "F.Mask" "F.Paste")
			(net "GND")
			(options
				(clearance outline)
				(anchor circle)
			)
			(primitives
				(gr_poly
					(pts
						(arc
							(start 0.3048 -0.2032)
							(mid 0.275042 -0.275042)
							(end 0.2032 -0.3048)
						)
						(arc
							(start -0.2032 -0.3048)
							(mid -0.275042 -0.275042)
							(end -0.3048 -0.2032)
						)
						(arc
							(start -0.3048 0.2032)
							(mid -0.275042 0.275042)
							(end -0.2032 0.3048)
						)
						(arc
							(start 0.2032 0.3048)
							(mid 0.275042 0.275042)
							(end 0.3048 0.2032)
						)
					)
					(width 0)
					(fill yes)
				)
			)
		)
	)
	(footprint ""
		(layer "F.Cu")
		(at 225.552 -39.878 90)
		(property "Reference" "R9808"
			(at 0 0 90)
			(layer "F.SilkS")
			(hide yes)
			(effects
				(font
					(size 1.27 1.27)
				)
			)
		)
		(property "Value" "0R2J-2-GP"
			(at 0.064008 -3.993896 90)
			(unlocked yes)
			(layer "F.Fab")
			(hide yes)
			(effects
				(font
					(size 1.016 1.016)
					(thickness 0.1524)
				)
			)
		)
		(property "Device Type" "R402H16"
			(at 0.064008 -5.517896 90)
			(unlocked yes)
			(layer "F.Fab")
			(hide yes)
			(effects
				(font
					(size 1.016 1.016)
					(thickness 0.1524)
				)
			)
		)
		(duplicate_pad_numbers_are_jumpers no)
		(fp_line
			(start 0.508 -0.9398)
			(end -0.508 -0.9398)
			(stroke
				(width 0.1524)
				(type default)
			)
			(layer "F.SilkS")
		)
		(fp_line
			(start -0.508 -0.9398)
			(end -0.508 0.9398)
			(stroke
				(width 0.1524)
				(type default)
			)
			(layer "F.SilkS")
		)
		(fp_rect
			(start -0.508 0.9398)
			(end 0.508 -0.9398)
			(stroke
				(width 0)
				(type default)
			)
			(fill no)
			(layer "F.CrtYd")
		)
		(fp_rect
			(start -0.508 0.9398)
			(end 0.508 -0.9398)
			(stroke
				(width 0)
				(type default)
			)
			(fill no)
			(layer "F.Fab")
		)
		(pad "1" smd custom
			(at 0 -0.4445 90)
			(size 0.1397 0.1397)
			(layers "F.Cu" "F.Mask" "F.Paste")
			(net "ATTN_LED_DR4_R")
			(options
				(clearance outline)
				(anchor circle)
			)
			(primitives
				(gr_poly
					(pts
						(arc
							(start -0.1778 -0.2794)
							(mid -0.249642 -0.249642)
							(end -0.2794 -0.1778)
						)
						(arc
							(start -0.2794 0.1778)
							(mid -0.249642 0.249642)
							(end -0.1778 0.2794)
						)
						(arc
							(start 0.1778 0.2794)
							(mid 0.249642 0.249642)
							(end 0.2794 0.1778)
						)
						(arc
							(start 0.2794 -0.1778)
							(mid 0.249642 -0.249642)
							(end 0.1778 -0.2794)
						)
					)
					(width 0)
					(fill yes)
				)
			)
		)
		(pad "2" smd custom
			(at 0 0.4445 90)
			(size 0.1397 0.1397)
			(layers "F.Cu" "F.Mask" "F.Paste")
			(net "ATTN_LED_DR4_N")
			(options
				(clearance outline)
				(anchor circle)
			)
			(primitives
				(gr_poly
					(pts
						(arc
							(start -0.1778 -0.2794)
							(mid -0.249642 -0.249642)
							(end -0.2794 -0.1778)
						)
						(arc
							(start -0.2794 0.1778)
							(mid -0.249642 0.249642)
							(end -0.1778 0.2794)
						)
						(arc
							(start 0.1778 0.2794)
							(mid 0.249642 0.249642)
							(end 0.2794 0.1778)
						)
						(arc
							(start 0.2794 -0.1778)
							(mid 0.249642 -0.249642)
							(end 0.1778 -0.2794)
						)
					)
					(width 0)
					(fill yes)
				)
			)
		)
	)
	(footprint ""
		(layer "F.Cu")
		(at 21.231606 -368.1095 180)
		(property "Reference" "R9923"
			(at 0 0 180)
			(layer "F.SilkS")
			(hide yes)
			(effects
				(font
					(size 1.27 1.27)
				)
			)
		)
		(property "Value" "47KR2J-2-GP"
			(at 0.064008 -3.993896 180)
			(unlocked yes)
			(layer "F.Fab")
			(hide yes)
			(effects
				(font
					(size 1.016 1.016)
					(thickness 0.1524)
				)
			)
		)
		(property "Device Type" "R402H16"
			(at 0.064008 -5.517896 180)
			(unlocked yes)
			(layer "F.Fab")
			(hide yes)
			(effects
				(font
					(size 1.016 1.016)
					(thickness 0.1524)
				)
			)
		)
		(duplicate_pad_numbers_are_jumpers no)
		(fp_line
			(start 0.508 -0.9398)
			(end -0.508 -0.9398)
			(stroke
				(width 0.1524)
				(type default)
			)
			(layer "F.SilkS")
		)
		(fp_line
			(start -0.508 -0.9398)
			(end -0.508 0.9398)
			(stroke
				(width 0.1524)
				(type default)
			)
			(layer "F.SilkS")
		)
		(fp_rect
			(start -0.508 0.9398)
			(end 0.508 -0.9398)
			(stroke
				(width 0)
				(type default)
			)
			(fill no)
			(layer "F.CrtYd")
		)
		(fp_rect
			(start -0.508 0.9398)
			(end 0.508 -0.9398)
			(stroke
				(width 0)
				(type default)
			)
			(fill no)
			(layer "F.Fab")
		)
		(pad "1" smd custom
			(at 0 -0.4445 180)
			(size 0.1397 0.1397)
			(layers "F.Cu" "F.Mask" "F.Paste")
			(net "P3V3")
			(options
				(clearance outline)
				(anchor circle)
			)
			(primitives
				(gr_poly
					(pts
						(arc
							(start -0.1778 -0.2794)
							(mid -0.249642 -0.249642)
							(end -0.2794 -0.1778)
						)
						(arc
							(start -0.2794 0.1778)
							(mid -0.249642 0.249642)
							(end -0.1778 0.2794)
						)
						(arc
							(start 0.1778 0.2794)
							(mid 0.249642 0.249642)
							(end 0.2794 0.1778)
						)
						(arc
							(start 0.2794 -0.1778)
							(mid 0.249642 -0.249642)
							(end 0.1778 -0.2794)
						)
					)
					(width 0)
					(fill yes)
				)
			)
		)
		(pad "2" smd custom
			(at 0 0.4445 180)
			(size 0.1397 0.1397)
			(layers "F.Cu" "F.Mask" "F.Paste")
			(net "ATTN_LED_DR11_N")
			(options
				(clearance outline)
				(anchor circle)
			)
			(primitives
				(gr_poly
					(pts
						(arc
							(start -0.1778 -0.2794)
							(mid -0.249642 -0.249642)
							(end -0.2794 -0.1778)
						)
						(arc
							(start -0.2794 0.1778)
							(mid -0.249642 0.249642)
							(end -0.1778 0.2794)
						)
						(arc
							(start 0.1778 0.2794)
							(mid 0.249642 0.249642)
							(end 0.2794 0.1778)
						)
						(arc
							(start 0.2794 -0.1778)
							(mid 0.249642 -0.249642)
							(end 0.1778 -0.2794)
						)
					)
					(width 0)
					(fill yes)
				)
			)
		)
	)
	(footprint ""
		(layer "F.Cu")
		(at 27.0002 -110.744 180)
		(property "Reference" "PC1211"
			(at 0 0 180)
			(layer "F.SilkS")
			(hide yes)
			(effects
				(font
					(size 1.27 1.27)
				)
			)
		)
		(property "Value" "SC22U25V6KX-GP-U"
			(at -2.860802 -5.279644 180)
			(unlocked yes)
			(layer "F.Fab")
			(hide yes)
			(effects
				(font
					(size 1.016 1.016)
					(thickness 0.1524)
				)
			)
		)
		(property "Device Type" "C1206-TO0D3H75"
			(at -2.860802 -6.803644 180)
			(unlocked yes)
			(layer "F.Fab")
			(hide yes)
			(effects
				(font
					(size 1.016 1.016)
					(thickness 0.1524)
				)
			)
		)
		(duplicate_pad_numbers_are_jumpers no)
		(fp_line
			(start 1.3081 2.3749)
			(end -1.3081 2.3749)
			(stroke
				(width 0.1524)
				(type default)
			)
			(layer "F.SilkS")
		)
		(fp_line
			(start 1.3081 -2.3749)
			(end 1.3081 2.3749)
			(stroke
				(width 0.1524)
				(type default)
			)
			(layer "F.SilkS")
		)
		(fp_line
			(start -1.3081 2.3749)
			(end -1.3081 -2.3749)
			(stroke
				(width 0.1524)
				(type default)
			)
			(layer "F.SilkS")
		)
		(fp_line
			(start -1.3081 -2.3749)
			(end 1.3081 -2.3749)
			(stroke
				(width 0.1524)
				(type default)
			)
			(layer "F.SilkS")
		)
		(fp_rect
			(start -0.8001 1.6002)
			(end 0.8001 -1.6002)
			(stroke
				(width 0)
				(type default)
			)
			(fill no)
			(layer "F.CrtYd")
		)
		(fp_poly
			(pts
				(xy -1.5621 2.4511) (xy -1.5621 1.6002) (xy 0.8001 1.6002) (xy 0.8001 -1.6002) (xy -0.8001 -1.6002)
				(xy -0.8001 1.5875) (xy -1.5621 1.5875) (xy -1.5621 -2.4511) (xy 1.5621 -2.4511) (xy 1.5621 2.4511)
			)
			(stroke
				(width 0)
				(type default)
			)
			(fill no)
			(layer "F.CrtYd")
		)
		(fp_rect
			(start -1.5621 2.4511)
			(end 1.5621 -2.4511)
			(stroke
				(width 0)
				(type default)
			)
			(fill no)
			(layer "F.Fab")
		)
		(pad "1" smd rect
			(at 0 -1.392936 180)
			(size 2.1082 1.4478)
			(layers "F.Cu" "F.Mask" "F.Paste")
			(net "P12V_SSD13")
		)
		(pad "2" smd rect
			(at 0 1.392936 180)
			(size 2.1082 1.4478)
			(layers "F.Cu" "F.Mask" "F.Paste")
			(net "GND")
		)
	)
	(footprint ""
		(layer "F.Cu")
		(at 79.0956 -107.3404 90)
		(property "Reference" "FB10"
			(at 0 0 90)
			(layer "F.SilkS")
			(hide yes)
			(effects
				(font
					(size 1.27 1.27)
				)
			)
		)
		(property "Value" "BLM21PG331SN1D-2-GP"
			(at 0 -4.2418 90)
			(unlocked yes)
			(layer "F.Fab")
			(hide yes)
			(effects
				(font
					(size 1.016 1.016)
					(thickness 0.1524)
				)
			)
		)
		(property "Device Type" "L805H42"
			(at 0 -5.7912 90)
			(unlocked yes)
			(layer "F.Fab")
			(hide yes)
			(effects
				(font
					(size 1.016 1.016)
					(thickness 0.1524)
				)
			)
		)
		(duplicate_pad_numbers_are_jumpers no)
		(fp_line
			(start 0.889 -1.7018)
			(end 0.889 1.7018)
			(stroke
				(width 0.1524)
				(type default)
			)
			(layer "F.SilkS")
		)
		(fp_line
			(start -0.889 -1.7018)
			(end 0.889 -1.7018)
			(stroke
				(width 0.1524)
				(type default)
			)
			(layer "F.SilkS")
		)
		(fp_line
			(start 0.889 1.7018)
			(end -0.889 1.7018)
			(stroke
				(width 0.1524)
				(type default)
			)
			(layer "F.SilkS")
		)
		(fp_line
			(start -0.889 1.7018)
			(end -0.889 -1.7018)
			(stroke
				(width 0.1524)
				(type default)
			)
			(layer "F.SilkS")
		)
		(fp_rect
			(start -0.9652 1.778)
			(end 0.9652 -1.778)
			(stroke
				(width 0)
				(type default)
			)
			(fill no)
			(layer "F.CrtYd")
		)
		(fp_rect
			(start -0.9652 1.778)
			(end 0.9652 -1.778)
			(stroke
				(width 0)
				(type default)
			)
			(fill no)
			(layer "F.Fab")
		)
		(pad "1" smd rect
			(at 0 -0.9652 90)
			(size 1.397 1.143)
			(layers "F.Cu" "F.Mask" "F.Paste")
			(net "P3V3")
		)
		(pad "2" smd rect
			(at 0 0.9652 90)
			(size 1.397 1.143)
			(layers "F.Cu" "F.Mask" "F.Paste")
			(net "VDD_DIFF_4")
		)
	)
	(footprint ""
		(layer "F.Cu")
		(at 231.267 -434.467 180)
		(property "Reference" "PC1263"
			(at 0 0 180)
			(layer "F.SilkS")
			(hide yes)
			(effects
				(font
					(size 1.27 1.27)
				)
			)
		)
		(property "Value" "SC1U16V3KX-5GP"
			(at 0 -2.8194 180)
			(unlocked yes)
			(layer "F.Fab")
			(hide yes)
			(effects
				(font
					(size 1.016 1.016)
					(thickness 0.1524)
				)
			)
		)
		(property "Device Type" "C603H36"
			(at 0 -4.3434 180)
			(unlocked yes)
			(layer "F.Fab")
			(hide yes)
			(effects
				(font
					(size 1.016 1.016)
					(thickness 0.1524)
				)
			)
		)
		(duplicate_pad_numbers_are_jumpers no)
		(fp_line
			(start 0.508 0)
			(end -0.508 0)
			(stroke
				(width 0.2032)
				(type default)
			)
			(layer "F.SilkS")
		)
		(fp_rect
			(start -0.5842 1.3335)
			(end 0.5842 -1.3335)
			(stroke
				(width 0)
				(type default)
			)
			(fill no)
			(layer "F.CrtYd")
		)
		(fp_rect
			(start -0.5842 1.3335)
			(end 0.5842 -1.3335)
			(stroke
				(width 0)
				(type default)
			)
			(fill no)
			(layer "F.Fab")
		)
		(pad "1" smd custom
			(at 0 -0.762 180)
			(size 0.2159 0.2159)
			(layers "F.Cu" "F.Mask" "F.Paste")
			(net "P3V3_VRG5")
			(options
				(clearance outline)
				(anchor circle)
			)
			(primitives
				(gr_poly
					(pts
						(arc
							(start -0.3302 -0.4318)
							(mid -0.402042 -0.402042)
							(end -0.4318 -0.3302)
						)
						(arc
							(start -0.4318 0.3302)
							(mid -0.402042 0.402042)
							(end -0.3302 0.4318)
						)
						(arc
							(start 0.3302 0.4318)
							(mid 0.402042 0.402042)
							(end 0.4318 0.3302)
						)
						(arc
							(start 0.4318 -0.3302)
							(mid 0.402042 -0.402042)
							(end 0.3302 -0.4318)
						)
					)
					(width 0)
					(fill yes)
				)
			)
		)
		(pad "2" smd custom
			(at 0 0.762 180)
			(size 0.2159 0.2159)
			(layers "F.Cu" "F.Mask" "F.Paste")
			(net "GND")
			(options
				(clearance outline)
				(anchor circle)
			)
			(primitives
				(gr_poly
					(pts
						(arc
							(start -0.3302 -0.4318)
							(mid -0.402042 -0.402042)
							(end -0.4318 -0.3302)
						)
						(arc
							(start -0.4318 0.3302)
							(mid -0.402042 0.402042)
							(end -0.3302 0.4318)
						)
						(arc
							(start 0.3302 0.4318)
							(mid 0.402042 0.402042)
							(end 0.4318 0.3302)
						)
						(arc
							(start 0.4318 -0.3302)
							(mid 0.402042 -0.402042)
							(end 0.3302 -0.4318)
						)
					)
					(width 0)
					(fill yes)
				)
			)
		)
	)
	(footprint ""
		(layer "F.Cu")
		(at 42.29862 -248.851166 90)
		(property "Reference" "R9941"
			(at 0 0 90)
			(layer "F.SilkS")
			(hide yes)
			(effects
				(font
					(size 1.27 1.27)
				)
			)
		)
		(property "Value" "4K7R2J-2-GP"
			(at 0.064008 -3.993896 90)
			(unlocked yes)
			(layer "F.Fab")
			(hide yes)
			(effects
				(font
					(size 1.016 1.016)
					(thickness 0.1524)
				)
			)
		)
		(property "Device Type" "R402H16"
			(at 0.064008 -5.517896 90)
			(unlocked yes)
			(layer "F.Fab")
			(hide yes)
			(effects
				(font
					(size 1.016 1.016)
					(thickness 0.1524)
				)
			)
		)
		(duplicate_pad_numbers_are_jumpers no)
		(fp_line
			(start 0.508 -0.9398)
			(end -0.508 -0.9398)
			(stroke
				(width 0.1524)
				(type default)
			)
			(layer "F.SilkS")
		)
		(fp_line
			(start -0.508 -0.9398)
			(end -0.508 0.9398)
			(stroke
				(width 0.1524)
				(type default)
			)
			(layer "F.SilkS")
		)
		(fp_rect
			(start -0.508 0.9398)
			(end 0.508 -0.9398)
			(stroke
				(width 0)
				(type default)
			)
			(fill no)
			(layer "F.CrtYd")
		)
		(fp_rect
			(start -0.508 0.9398)
			(end 0.508 -0.9398)
			(stroke
				(width 0)
				(type default)
			)
			(fill no)
			(layer "F.Fab")
		)
		(pad "1" smd custom
			(at 0 -0.4445 90)
			(size 0.1397 0.1397)
			(layers "F.Cu" "F.Mask" "F.Paste")
			(net "P3V3")
			(options
				(clearance outline)
				(anchor circle)
			)
			(primitives
				(gr_poly
					(pts
						(arc
							(start -0.1778 -0.2794)
							(mid -0.249642 -0.249642)
							(end -0.2794 -0.1778)
						)
						(arc
							(start -0.2794 0.1778)
							(mid -0.249642 0.249642)
							(end -0.1778 0.2794)
						)
						(arc
							(start 0.1778 0.2794)
							(mid 0.249642 0.249642)
							(end 0.2794 0.1778)
						)
						(arc
							(start 0.2794 -0.1778)
							(mid 0.249642 -0.249642)
							(end 0.1778 -0.2794)
						)
					)
					(width 0)
					(fill yes)
				)
			)
		)
		(pad "2" smd custom
			(at 0 0.4445 90)
			(size 0.1397 0.1397)
			(layers "F.Cu" "F.Mask" "F.Paste")
			(net "ATTN_LED_DR7_MOS_N")
			(options
				(clearance outline)
				(anchor circle)
			)
			(primitives
				(gr_poly
					(pts
						(arc
							(start -0.1778 -0.2794)
							(mid -0.249642 -0.249642)
							(end -0.2794 -0.1778)
						)
						(arc
							(start -0.2794 0.1778)
							(mid -0.249642 0.249642)
							(end -0.1778 0.2794)
						)
						(arc
							(start 0.1778 0.2794)
							(mid 0.249642 0.249642)
							(end 0.2794 0.1778)
						)
						(arc
							(start 0.2794 -0.1778)
							(mid 0.249642 -0.249642)
							(end 0.1778 -0.2794)
						)
					)
					(width 0)
					(fill yes)
				)
			)
		)
	)
	(footprint ""
		(layer "F.Cu")
		(at 207.096106 -498.654578)
		(property "Reference" "R9775"
			(at 0 0 0)
			(layer "F.SilkS")
			(hide yes)
			(effects
				(font
					(size 1.27 1.27)
				)
			)
		)
		(property "Value" "2K2R5F-GP"
			(at 0 -8.9535 0)
			(unlocked yes)
			(layer "F.Fab")
			(hide yes)
			(effects
				(font
					(size 1.27 1.016)
					(thickness 0.1524)
				)
			)
		)
		(property "Device Type" "R805H24"
			(at 0 -10.6299 0)
			(unlocked yes)
			(layer "F.Fab")
			(hide yes)
			(effects
				(font
					(size 1.27 1.016)
					(thickness 0.1524)
				)
			)
		)
		(duplicate_pad_numbers_are_jumpers no)
		(fp_line
			(start -0.889 -1.7018)
			(end -0.889 0.2794)
			(stroke
				(width 0.1524)
				(type default)
			)
			(layer "F.SilkS")
		)
		(fp_line
			(start -0.889 0.0762)
			(end -0.889 1.7018)
			(stroke
				(width 0.1524)
				(type default)
			)
			(layer "F.SilkS")
		)
		(fp_line
			(start -0.889 1.7018)
			(end 0.889 1.7018)
			(stroke
				(width 0.1524)
				(type default)
			)
			(layer "F.SilkS")
		)
		(fp_line
			(start 0.889 -1.7018)
			(end -0.889 -1.7018)
			(stroke
				(width 0.1524)
				(type default)
			)
			(layer "F.SilkS")
		)
		(fp_line
			(start 0.889 -1.7018)
			(end 0.889 -0.381)
			(stroke
				(width 0.1524)
				(type default)
			)
			(layer "F.SilkS")
		)
		(fp_line
			(start 0.889 1.7018)
			(end 0.889 -0.508)
			(stroke
				(width 0.1524)
				(type default)
			)
			(layer "F.SilkS")
		)
		(fp_poly
			(pts
				(xy 0.9652 -1.778) (xy 0.9652 1.778) (xy -0.9652 1.778) (xy -0.9652 -1.778)
			)
			(stroke
				(width 0)
				(type default)
			)
			(fill no)
			(layer "F.CrtYd")
		)
		(fp_rect
			(start -0.9652 1.778)
			(end 0.9652 -1.778)
			(stroke
				(width 0)
				(type default)
			)
			(fill no)
			(layer "F.Fab")
		)
		(pad "1" smd rect
			(at 0 -0.9652)
			(size 1.397 1.143)
			(layers "F.Cu" "F.Mask" "F.Paste")
			(net "P12V_SSD0")
		)
		(pad "2" smd rect
			(at 0 0.9652)
			(size 1.397 1.143)
			(layers "F.Cu" "F.Mask" "F.Paste")
			(net "P12V_MOST0_GATE_D")
		)
	)
	(footprint ""
		(layer "F.Cu")
		(at 234.061 -143.637 -90)
		(property "Reference" "R9443"
			(at 0 0 270)
			(layer "F.SilkS")
			(hide yes)
			(effects
				(font
					(size 1.27 1.27)
				)
			)
		)
		(property "Value" "100R2J-2-GP"
			(at 0.064008 -3.993896 270)
			(unlocked yes)
			(layer "F.Fab")
			(hide yes)
			(effects
				(font
					(size 1.016 1.016)
					(thickness 0.1524)
				)
			)
		)
		(property "Device Type" "R402H14"
			(at 0.064008 -5.517896 270)
			(unlocked yes)
			(layer "F.Fab")
			(hide yes)
			(effects
				(font
					(size 1.016 1.016)
					(thickness 0.1524)
				)
			)
		)
		(duplicate_pad_numbers_are_jumpers no)
		(fp_line
			(start -0.508 -0.9398)
			(end -0.508 0.9398)
			(stroke
				(width 0.1524)
				(type default)
			)
			(layer "F.SilkS")
		)
		(fp_line
			(start 0.508 -0.9398)
			(end -0.508 -0.9398)
			(stroke
				(width 0.1524)
				(type default)
			)
			(layer "F.SilkS")
		)
		(fp_rect
			(start -0.508 0.9398)
			(end 0.508 -0.9398)
			(stroke
				(width 0)
				(type default)
			)
			(fill no)
			(layer "F.CrtYd")
		)
		(fp_rect
			(start -0.508 0.9398)
			(end 0.508 -0.9398)
			(stroke
				(width 0)
				(type default)
			)
			(fill no)
			(layer "F.Fab")
		)
		(pad "1" smd custom
			(at 0 -0.4445 270)
			(size 0.1397 0.1397)
			(layers "F.Cu" "F.Mask" "F.Paste")
			(net "P3V3")
			(options
				(clearance outline)
				(anchor circle)
			)
			(primitives
				(gr_poly
					(pts
						(arc
							(start -0.1778 -0.2794)
							(mid -0.249642 -0.249642)
							(end -0.2794 -0.1778)
						)
						(arc
							(start -0.2794 0.1778)
							(mid -0.249642 0.249642)
							(end -0.1778 0.2794)
						)
						(arc
							(start 0.1778 0.2794)
							(mid 0.249642 0.249642)
							(end 0.2794 0.1778)
						)
						(arc
							(start 0.2794 -0.1778)
							(mid 0.249642 -0.249642)
							(end 0.1778 -0.2794)
						)
					)
					(width 0)
					(fill yes)
				)
			)
		)
		(pad "2" smd custom
			(at 0 0.4445 270)
			(size 0.1397 0.1397)
			(layers "F.Cu" "F.Mask" "F.Paste")
			(net "DRV_ACT_3")
			(options
				(clearance outline)
				(anchor circle)
			)
			(primitives
				(gr_poly
					(pts
						(arc
							(start -0.1778 -0.2794)
							(mid -0.249642 -0.249642)
							(end -0.2794 -0.1778)
						)
						(arc
							(start -0.2794 0.1778)
							(mid -0.249642 0.249642)
							(end -0.1778 0.2794)
						)
						(arc
							(start 0.1778 0.2794)
							(mid 0.249642 0.249642)
							(end 0.2794 0.1778)
						)
						(arc
							(start 0.2794 -0.1778)
							(mid 0.249642 -0.249642)
							(end 0.1778 -0.2794)
						)
					)
					(width 0)
					(fill yes)
				)
			)
		)
	)
	(footprint ""
		(layer "F.Cu")
		(at 209.296 -400.177 180)
		(property "Reference" "Q9"
			(at 0 0 180)
			(layer "F.SilkS")
			(hide yes)
			(effects
				(font
					(size 1.27 1.27)
				)
			)
		)
		(property "Value" "2N7002A-7-GP"
			(at 0.127 -8.9662 180)
			(unlocked yes)
			(layer "F.Fab")
			(hide yes)
			(effects
				(font
					(size 1.016 1.016)
					(thickness 0.1524)
				)
			)
		)
		(property "Device Type" "SOT23DGS2D4H48"
			(at 0.127 -10.4902 180)
			(unlocked yes)
			(layer "F.Fab")
			(hide yes)
			(effects
				(font
					(size 1.016 1.016)
					(thickness 0.1524)
				)
			)
		)
		(duplicate_pad_numbers_are_jumpers no)
		(fp_line
			(start 1.651 1.778)
			(end 1.651 -1.778)
			(stroke
				(width 0.1524)
				(type default)
			)
			(layer "F.SilkS")
		)
		(fp_line
			(start 1.651 -1.778)
			(end -1.651 -1.778)
			(stroke
				(width 0.1524)
				(type default)
			)
			(layer "F.SilkS")
		)
		(fp_line
			(start -1.651 1.778)
			(end 1.651 1.778)
			(stroke
				(width 0.1524)
				(type default)
			)
			(layer "F.SilkS")
		)
		(fp_line
			(start -1.651 -1.778)
			(end -1.651 1.778)
			(stroke
				(width 0.1524)
				(type default)
			)
			(layer "F.SilkS")
		)
		(fp_poly
			(pts
				(xy -1.778 1.8796) (xy -1.778 -1.8796) (xy 1.778 -1.8796) (xy 1.778 1.8796)
			)
			(stroke
				(width 0)
				(type default)
			)
			(fill no)
			(layer "F.CrtYd")
		)
		(fp_poly
			(pts
				(xy -1.778 1.8796) (xy -1.778 -1.8796) (xy 1.778 -1.8796) (xy 1.778 1.8796)
			)
			(stroke
				(width 0)
				(type default)
			)
			(fill no)
			(layer "F.Fab")
		)
		(pad "D" smd custom
			(at 0 -0.9525 180)
			(size 0.1905 0.1905)
			(layers "F.Cu" "F.Mask" "F.Paste")
			(net "SW_SSD1_R")
			(options
				(clearance outline)
				(anchor circle)
			)
			(primitives
				(gr_poly
					(pts
						(arc
							(start -0.1778 0.5715)
							(mid -0.321484 0.511984)
							(end -0.381 0.3683)
						)
						(arc
							(start -0.381 -0.3683)
							(mid -0.321484 -0.511984)
							(end -0.1778 -0.5715)
						)
						(arc
							(start 0.1778 -0.5715)
							(mid 0.321484 -0.511984)
							(end 0.381 -0.3683)
						)
						(arc
							(start 0.381 0.3683)
							(mid 0.321484 0.511984)
							(end 0.1778 0.5715)
						)
					)
					(width 0)
					(fill yes)
				)
			)
		)
		(pad "G" smd custom
			(at -0.98425 0.9525 180)
			(size 0.1905 0.1905)
			(layers "F.Cu" "F.Mask" "F.Paste")
			(net "SSD1_PWREN")
			(options
				(clearance outline)
				(anchor circle)
			)
			(primitives
				(gr_poly
					(pts
						(arc
							(start -0.1778 0.5715)
							(mid -0.321484 0.511984)
							(end -0.381 0.3683)
						)
						(arc
							(start -0.381 -0.3683)
							(mid -0.321484 -0.511984)
							(end -0.1778 -0.5715)
						)
						(arc
							(start 0.1778 -0.5715)
							(mid 0.321484 -0.511984)
							(end 0.381 -0.3683)
						)
						(arc
							(start 0.381 0.3683)
							(mid 0.321484 0.511984)
							(end 0.1778 0.5715)
						)
					)
					(width 0)
					(fill yes)
				)
			)
		)
		(pad "S" smd custom
			(at 0.98425 0.9525 180)
			(size 0.1905 0.1905)
			(layers "F.Cu" "F.Mask" "F.Paste")
			(net "GND")
			(options
				(clearance outline)
				(anchor circle)
			)
			(primitives
				(gr_poly
					(pts
						(arc
							(start -0.1778 0.5715)
							(mid -0.321484 0.511984)
							(end -0.381 0.3683)
						)
						(arc
							(start -0.381 -0.3683)
							(mid -0.321484 -0.511984)
							(end -0.1778 -0.5715)
						)
						(arc
							(start 0.1778 -0.5715)
							(mid 0.321484 -0.511984)
							(end 0.381 -0.3683)
						)
						(arc
							(start 0.381 0.3683)
							(mid 0.321484 0.511984)
							(end 0.1778 0.5715)
						)
					)
					(width 0)
					(fill yes)
				)
			)
		)
	)
	(footprint ""
		(layer "F.Cu")
		(at 234.061 -247.771158 -90)
		(property "Reference" "R9400"
			(at 0 0 270)
			(layer "F.SilkS")
			(hide yes)
			(effects
				(font
					(size 1.27 1.27)
				)
			)
		)
		(property "Value" "330R2F-GP"
			(at 0.064008 -3.993896 270)
			(unlocked yes)
			(layer "F.Fab")
			(hide yes)
			(effects
				(font
					(size 1.016 1.016)
					(thickness 0.1524)
				)
			)
		)
		(property "Device Type" "R402H16"
			(at 0.064008 -5.517896 270)
			(unlocked yes)
			(layer "F.Fab")
			(hide yes)
			(effects
				(font
					(size 1.016 1.016)
					(thickness 0.1524)
				)
			)
		)
		(duplicate_pad_numbers_are_jumpers no)
		(fp_line
			(start -0.508 -0.9398)
			(end -0.508 0.9398)
			(stroke
				(width 0.1524)
				(type default)
			)
			(layer "F.SilkS")
		)
		(fp_line
			(start 0.508 -0.9398)
			(end -0.508 -0.9398)
			(stroke
				(width 0.1524)
				(type default)
			)
			(layer "F.SilkS")
		)
		(fp_rect
			(start -0.508 0.9398)
			(end 0.508 -0.9398)
			(stroke
				(width 0)
				(type default)
			)
			(fill no)
			(layer "F.CrtYd")
		)
		(fp_rect
			(start -0.508 0.9398)
			(end 0.508 -0.9398)
			(stroke
				(width 0)
				(type default)
			)
			(fill no)
			(layer "F.Fab")
		)
		(pad "1" smd custom
			(at 0 -0.4445 270)
			(size 0.1397 0.1397)
			(layers "F.Cu" "F.Mask" "F.Paste")
			(net "P3V3")
			(options
				(clearance outline)
				(anchor circle)
			)
			(primitives
				(gr_poly
					(pts
						(arc
							(start -0.1778 -0.2794)
							(mid -0.249642 -0.249642)
							(end -0.2794 -0.1778)
						)
						(arc
							(start -0.2794 0.1778)
							(mid -0.249642 0.249642)
							(end -0.1778 0.2794)
						)
						(arc
							(start 0.1778 0.2794)
							(mid 0.249642 0.249642)
							(end 0.2794 0.1778)
						)
						(arc
							(start 0.2794 -0.1778)
							(mid 0.249642 -0.249642)
							(end 0.1778 -0.2794)
						)
					)
					(width 0)
					(fill yes)
				)
			)
		)
		(pad "2" smd custom
			(at 0 0.4445 270)
			(size 0.1397 0.1397)
			(layers "F.Cu" "F.Mask" "F.Paste")
			(net "DRV_ATTN_2")
			(options
				(clearance outline)
				(anchor circle)
			)
			(primitives
				(gr_poly
					(pts
						(arc
							(start -0.1778 -0.2794)
							(mid -0.249642 -0.249642)
							(end -0.2794 -0.1778)
						)
						(arc
							(start -0.2794 0.1778)
							(mid -0.249642 0.249642)
							(end -0.1778 0.2794)
						)
						(arc
							(start 0.1778 0.2794)
							(mid 0.249642 0.249642)
							(end 0.2794 0.1778)
						)
						(arc
							(start 0.2794 -0.1778)
							(mid 0.249642 -0.249642)
							(end 0.1778 -0.2794)
						)
					)
					(width 0)
					(fill yes)
				)
			)
		)
	)
	(footprint ""
		(layer "F.Cu")
		(at 94.615 -424.688)
		(property "Reference" "C9514"
			(at 0 0 0)
			(layer "F.SilkS")
			(hide yes)
			(effects
				(font
					(size 1.27 1.27)
				)
			)
		)
		(property "Value" "SCD1U16V2KX-3GP"
			(at 1.1811 -2.7051 0)
			(unlocked yes)
			(layer "F.Fab")
			(hide yes)
			(effects
				(font
					(size 1.016 1.016)
					(thickness 0.1524)
				)
			)
		)
		(property "Device Type" "C402H22"
			(at 1.1811 -4.2291 0)
			(unlocked yes)
			(layer "F.Fab")
			(hide yes)
			(effects
				(font
					(size 1.016 1.016)
					(thickness 0.1524)
				)
			)
		)
		(duplicate_pad_numbers_are_jumpers no)
		(fp_rect
			(start -0.4318 0.9525)
			(end 0.4318 -0.9525)
			(stroke
				(width 0)
				(type default)
			)
			(fill no)
			(layer "F.CrtYd")
		)
		(fp_rect
			(start -0.4318 0.9525)
			(end 0.4318 -0.9525)
			(stroke
				(width 0)
				(type default)
			)
			(fill no)
			(layer "F.Fab")
		)
		(pad "1" smd custom
			(at 0 -0.4445)
			(size 0.1524 0.1524)
			(layers "F.Cu" "F.Mask" "F.Paste")
			(net "VDD_DIFF_1")
			(options
				(clearance outline)
				(anchor circle)
			)
			(primitives
				(gr_poly
					(pts
						(arc
							(start 0.3048 -0.2032)
							(mid 0.275042 -0.275042)
							(end 0.2032 -0.3048)
						)
						(arc
							(start -0.2032 -0.3048)
							(mid -0.275042 -0.275042)
							(end -0.3048 -0.2032)
						)
						(arc
							(start -0.3048 0.2032)
							(mid -0.275042 0.275042)
							(end -0.2032 0.3048)
						)
						(arc
							(start 0.2032 0.3048)
							(mid 0.275042 0.275042)
							(end 0.3048 0.2032)
						)
					)
					(width 0)
					(fill yes)
				)
			)
		)
		(pad "2" smd custom
			(at 0 0.4445)
			(size 0.1524 0.1524)
			(layers "F.Cu" "F.Mask" "F.Paste")
			(net "GND")
			(options
				(clearance outline)
				(anchor circle)
			)
			(primitives
				(gr_poly
					(pts
						(arc
							(start 0.3048 -0.2032)
							(mid 0.275042 -0.275042)
							(end 0.2032 -0.3048)
						)
						(arc
							(start -0.2032 -0.3048)
							(mid -0.275042 -0.275042)
							(end -0.3048 -0.2032)
						)
						(arc
							(start -0.3048 0.2032)
							(mid -0.275042 0.275042)
							(end -0.2032 0.3048)
						)
						(arc
							(start 0.2032 0.3048)
							(mid 0.275042 0.275042)
							(end 0.3048 0.2032)
						)
					)
					(width 0)
					(fill yes)
				)
			)
		)
	)
	(footprint ""
		(layer "F.Cu")
		(at 18.50009 -52.900072)
		(property "Reference" "LED14"
			(at 0 0 0)
			(layer "F.SilkS")
			(hide yes)
			(effects
				(font
					(size 1.27 1.27)
				)
			)
		)
		(property "Value" "LED-RB-4-GP"
			(at 5.88899 1.80848 0)
			(unlocked yes)
			(layer "F.Fab")
			(hide yes)
			(effects
				(font
					(size 1.016 1.016)
					(thickness 0.1524)
				)
			)
		)
		(property "Device Type" "LED1613-4PH20"
			(at 5.88899 0.28448 0)
			(unlocked yes)
			(layer "F.Fab")
			(hide yes)
			(effects
				(font
					(size 1.016 1.016)
					(thickness 0.1524)
				)
			)
		)
		(duplicate_pad_numbers_are_jumpers no)
		(fp_line
			(start -1.4478 -0.9652)
			(end 1.4478 -0.9652)
			(stroke
				(width 0.1524)
				(type default)
			)
			(layer "F.SilkS")
		)
		(fp_line
			(start -1.4478 0.9652)
			(end -1.4478 -0.9652)
			(stroke
				(width 0.1524)
				(type default)
			)
			(layer "F.SilkS")
		)
		(fp_line
			(start -1.4478 0.9652)
			(end -1.4478 -0.9652)
			(stroke
				(width 0.508)
				(type default)
			)
			(layer "F.SilkS")
		)
		(fp_line
			(start 1.4478 -0.9652)
			(end 1.4478 0.9652)
			(stroke
				(width 0.1524)
				(type default)
			)
			(layer "F.SilkS")
		)
		(fp_line
			(start 1.4478 0.9652)
			(end -1.4478 0.9652)
			(stroke
				(width 0.1524)
				(type default)
			)
			(layer "F.SilkS")
		)
		(fp_rect
			(start -0.8001 0.6477)
			(end 0.8001 -0.6477)
			(stroke
				(width 0)
				(type default)
			)
			(fill no)
			(layer "F.CrtYd")
		)
		(fp_poly
			(pts
				(xy -1.7018 1.2192) (xy -1.7018 -0.06223) (xy -0.8001 -0.06223) (xy -0.8001 0.6477) (xy 0.8001 0.6477)
				(xy 0.8001 -0.6477) (xy -0.8001 -0.6477) (xy -0.8001 -0.0635) (xy -1.7018 -0.0635) (xy -1.7018 -1.2192)
				(xy 1.7018 -1.2192) (xy 1.7018 1.2192)
			)
			(stroke
				(width 0)
				(type default)
			)
			(fill no)
			(layer "F.CrtYd")
		)
		(fp_rect
			(start -1.7018 1.2192)
			(end 1.7018 -1.2192)
			(stroke
				(width 0)
				(type default)
			)
			(fill no)
			(layer "F.Fab")
		)
		(pad "1" smd rect
			(at -0.73025 0.4064)
			(size 0.9144 0.6096)
			(layers "F.Cu" "F.Mask" "F.Paste")
			(net "SSD_ACT_DR14_MOS_N")
		)
		(pad "2" smd rect
			(at -0.73025 -0.4064)
			(size 0.9144 0.6096)
			(layers "F.Cu" "F.Mask" "F.Paste")
			(net "ATTN_LED_DR14_MOS_N")
		)
		(pad "3" smd rect
			(at 0.73025 -0.4064)
			(size 0.9144 0.6096)
			(layers "F.Cu" "F.Mask" "F.Paste")
			(net "DRV_ATTN_14")
		)
		(pad "4" smd rect
			(at 0.73025 0.4064)
			(size 0.9144 0.6096)
			(layers "F.Cu" "F.Mask" "F.Paste")
			(net "DRV_ACT_14")
		)
	)
	(footprint ""
		(layer "F.Cu")
		(at 100.5078 -431.546 180)
		(property "Reference" "C9419"
			(at 0 0 180)
			(layer "F.SilkS")
			(hide yes)
			(effects
				(font
					(size 1.27 1.27)
				)
			)
		)
		(property "Value" "SCD1U16V2KX-3GP"
			(at 1.1811 -2.7051 180)
			(unlocked yes)
			(layer "F.Fab")
			(hide yes)
			(effects
				(font
					(size 1.016 1.016)
					(thickness 0.1524)
				)
			)
		)
		(property "Device Type" "C402H22"
			(at 1.1811 -4.2291 180)
			(unlocked yes)
			(layer "F.Fab")
			(hide yes)
			(effects
				(font
					(size 1.016 1.016)
					(thickness 0.1524)
				)
			)
		)
		(duplicate_pad_numbers_are_jumpers no)
		(fp_rect
			(start -0.4318 0.9525)
			(end 0.4318 -0.9525)
			(stroke
				(width 0)
				(type default)
			)
			(fill no)
			(layer "F.CrtYd")
		)
		(fp_rect
			(start -0.4318 0.9525)
			(end 0.4318 -0.9525)
			(stroke
				(width 0)
				(type default)
			)
			(fill no)
			(layer "F.Fab")
		)
		(pad "1" smd custom
			(at 0 -0.4445 180)
			(size 0.1524 0.1524)
			(layers "F.Cu" "F.Mask" "F.Paste")
			(net "VDD_DIFF_1")
			(options
				(clearance outline)
				(anchor circle)
			)
			(primitives
				(gr_poly
					(pts
						(arc
							(start 0.3048 -0.2032)
							(mid 0.275042 -0.275042)
							(end 0.2032 -0.3048)
						)
						(arc
							(start -0.2032 -0.3048)
							(mid -0.275042 -0.275042)
							(end -0.3048 -0.2032)
						)
						(arc
							(start -0.3048 0.2032)
							(mid -0.275042 0.275042)
							(end -0.2032 0.3048)
						)
						(arc
							(start 0.2032 0.3048)
							(mid 0.275042 0.275042)
							(end 0.3048 0.2032)
						)
					)
					(width 0)
					(fill yes)
				)
			)
		)
		(pad "2" smd custom
			(at 0 0.4445 180)
			(size 0.1524 0.1524)
			(layers "F.Cu" "F.Mask" "F.Paste")
			(net "GND")
			(options
				(clearance outline)
				(anchor circle)
			)
			(primitives
				(gr_poly
					(pts
						(arc
							(start 0.3048 -0.2032)
							(mid 0.275042 -0.275042)
							(end 0.2032 -0.3048)
						)
						(arc
							(start -0.2032 -0.3048)
							(mid -0.275042 -0.275042)
							(end -0.3048 -0.2032)
						)
						(arc
							(start -0.3048 0.2032)
							(mid -0.275042 0.275042)
							(end -0.2032 0.3048)
						)
						(arc
							(start 0.2032 0.3048)
							(mid 0.275042 0.275042)
							(end 0.3048 0.2032)
						)
					)
					(width 0)
					(fill yes)
				)
			)
		)
	)
	(footprint ""
		(layer "F.Cu")
		(at 82.931 -438.15 90)
		(property "Reference" "R9350"
			(at 0 0 90)
			(layer "F.SilkS")
			(hide yes)
			(effects
				(font
					(size 1.27 1.27)
				)
			)
		)
		(property "Value" "2D2R2F-GP"
			(at 0.064008 -3.993896 90)
			(unlocked yes)
			(layer "F.Fab")
			(hide yes)
			(effects
				(font
					(size 1.016 1.016)
					(thickness 0.1524)
				)
			)
		)
		(property "Device Type" "R402H16"
			(at 0.064008 -5.517896 90)
			(unlocked yes)
			(layer "F.Fab")
			(hide yes)
			(effects
				(font
					(size 1.016 1.016)
					(thickness 0.1524)
				)
			)
		)
		(duplicate_pad_numbers_are_jumpers no)
		(fp_line
			(start 0.508 -0.9398)
			(end -0.508 -0.9398)
			(stroke
				(width 0.1524)
				(type default)
			)
			(layer "F.SilkS")
		)
		(fp_line
			(start -0.508 -0.9398)
			(end -0.508 0.9398)
			(stroke
				(width 0.1524)
				(type default)
			)
			(layer "F.SilkS")
		)
		(fp_rect
			(start -0.508 0.9398)
			(end 0.508 -0.9398)
			(stroke
				(width 0)
				(type default)
			)
			(fill no)
			(layer "F.CrtYd")
		)
		(fp_rect
			(start -0.508 0.9398)
			(end 0.508 -0.9398)
			(stroke
				(width 0)
				(type default)
			)
			(fill no)
			(layer "F.Fab")
		)
		(pad "1" smd custom
			(at 0 -0.4445 90)
			(size 0.1397 0.1397)
			(layers "F.Cu" "F.Mask" "F.Paste")
			(net "VDD_DIFF_1")
			(options
				(clearance outline)
				(anchor circle)
			)
			(primitives
				(gr_poly
					(pts
						(arc
							(start -0.1778 -0.2794)
							(mid -0.249642 -0.249642)
							(end -0.2794 -0.1778)
						)
						(arc
							(start -0.2794 0.1778)
							(mid -0.249642 0.249642)
							(end -0.1778 0.2794)
						)
						(arc
							(start 0.1778 0.2794)
							(mid 0.249642 0.249642)
							(end 0.2794 0.1778)
						)
						(arc
							(start 0.2794 -0.1778)
							(mid 0.249642 -0.249642)
							(end 0.1778 -0.2794)
						)
					)
					(width 0)
					(fill yes)
				)
			)
		)
		(pad "2" smd custom
			(at 0 0.4445 90)
			(size 0.1397 0.1397)
			(layers "F.Cu" "F.Mask" "F.Paste")
			(net "VDDA_1")
			(options
				(clearance outline)
				(anchor circle)
			)
			(primitives
				(gr_poly
					(pts
						(arc
							(start -0.1778 -0.2794)
							(mid -0.249642 -0.249642)
							(end -0.2794 -0.1778)
						)
						(arc
							(start -0.2794 0.1778)
							(mid -0.249642 0.249642)
							(end -0.1778 0.2794)
						)
						(arc
							(start 0.1778 0.2794)
							(mid 0.249642 0.249642)
							(end 0.2794 0.1778)
						)
						(arc
							(start 0.2794 -0.1778)
							(mid 0.249642 -0.249642)
							(end 0.1778 -0.2794)
						)
					)
					(width 0)
					(fill yes)
				)
			)
		)
	)
	(footprint ""
		(layer "F.Cu")
		(at 234.061 -348.488 -90)
		(property "Reference" "R9893"
			(at 0 0 270)
			(layer "F.SilkS")
			(hide yes)
			(effects
				(font
					(size 1.27 1.27)
				)
			)
		)
		(property "Value" "1K82R2F-1-GP"
			(at 0.064008 -3.993896 270)
			(unlocked yes)
			(layer "F.Fab")
			(hide yes)
			(effects
				(font
					(size 1.016 1.016)
					(thickness 0.1524)
				)
			)
		)
		(property "Device Type" "R402H16"
			(at 0.064008 -5.517896 270)
			(unlocked yes)
			(layer "F.Fab")
			(hide yes)
			(effects
				(font
					(size 1.016 1.016)
					(thickness 0.1524)
				)
			)
		)
		(duplicate_pad_numbers_are_jumpers no)
		(fp_line
			(start -0.508 -0.9398)
			(end -0.508 0.9398)
			(stroke
				(width 0.1524)
				(type default)
			)
			(layer "F.SilkS")
		)
		(fp_line
			(start 0.508 -0.9398)
			(end -0.508 -0.9398)
			(stroke
				(width 0.1524)
				(type default)
			)
			(layer "F.SilkS")
		)
		(fp_rect
			(start -0.508 0.9398)
			(end 0.508 -0.9398)
			(stroke
				(width 0)
				(type default)
			)
			(fill no)
			(layer "F.CrtYd")
		)
		(fp_rect
			(start -0.508 0.9398)
			(end 0.508 -0.9398)
			(stroke
				(width 0)
				(type default)
			)
			(fill no)
			(layer "F.Fab")
		)
		(pad "1" smd custom
			(at 0 -0.4445 270)
			(size 0.1397 0.1397)
			(layers "F.Cu" "F.Mask" "F.Paste")
			(net "P12V")
			(options
				(clearance outline)
				(anchor circle)
			)
			(primitives
				(gr_poly
					(pts
						(arc
							(start -0.1778 -0.2794)
							(mid -0.249642 -0.249642)
							(end -0.2794 -0.1778)
						)
						(arc
							(start -0.2794 0.1778)
							(mid -0.249642 0.249642)
							(end -0.1778 0.2794)
						)
						(arc
							(start 0.1778 0.2794)
							(mid 0.249642 0.249642)
							(end 0.2794 0.1778)
						)
						(arc
							(start 0.2794 -0.1778)
							(mid 0.249642 -0.249642)
							(end 0.1778 -0.2794)
						)
					)
					(width 0)
					(fill yes)
				)
			)
		)
		(pad "2" smd custom
			(at 0 0.4445 270)
			(size 0.1397 0.1397)
			(layers "F.Cu" "F.Mask" "F.Paste")
			(net "DRV_ACT_1")
			(options
				(clearance outline)
				(anchor circle)
			)
			(primitives
				(gr_poly
					(pts
						(arc
							(start -0.1778 -0.2794)
							(mid -0.249642 -0.249642)
							(end -0.2794 -0.1778)
						)
						(arc
							(start -0.2794 0.1778)
							(mid -0.249642 0.249642)
							(end -0.1778 0.2794)
						)
						(arc
							(start 0.1778 0.2794)
							(mid 0.249642 0.249642)
							(end 0.2794 0.1778)
						)
						(arc
							(start 0.2794 -0.1778)
							(mid 0.249642 -0.249642)
							(end 0.1778 -0.2794)
						)
					)
					(width 0)
					(fill yes)
				)
			)
		)
	)
	(footprint ""
		(layer "F.Cu")
		(at 24.13 -397.891 180)
		(property "Reference" "Q14"
			(at 0 0 180)
			(layer "F.SilkS")
			(hide yes)
			(effects
				(font
					(size 1.27 1.27)
				)
			)
		)
		(property "Value" "2N7002A-7-GP"
			(at 0.127 -8.9662 180)
			(unlocked yes)
			(layer "F.Fab")
			(hide yes)
			(effects
				(font
					(size 1.016 1.016)
					(thickness 0.1524)
				)
			)
		)
		(property "Device Type" "SOT23DGS2D4H48"
			(at 0.127 -10.4902 180)
			(unlocked yes)
			(layer "F.Fab")
			(hide yes)
			(effects
				(font
					(size 1.016 1.016)
					(thickness 0.1524)
				)
			)
		)
		(duplicate_pad_numbers_are_jumpers no)
		(fp_line
			(start 1.651 1.778)
			(end 1.651 -1.778)
			(stroke
				(width 0.1524)
				(type default)
			)
			(layer "F.SilkS")
		)
		(fp_line
			(start 1.651 -1.778)
			(end -1.651 -1.778)
			(stroke
				(width 0.1524)
				(type default)
			)
			(layer "F.SilkS")
		)
		(fp_line
			(start -1.651 1.778)
			(end 1.651 1.778)
			(stroke
				(width 0.1524)
				(type default)
			)
			(layer "F.SilkS")
		)
		(fp_line
			(start -1.651 -1.778)
			(end -1.651 1.778)
			(stroke
				(width 0.1524)
				(type default)
			)
			(layer "F.SilkS")
		)
		(fp_poly
			(pts
				(xy -1.778 1.8796) (xy -1.778 -1.8796) (xy 1.778 -1.8796) (xy 1.778 1.8796)
			)
			(stroke
				(width 0)
				(type default)
			)
			(fill no)
			(layer "F.CrtYd")
		)
		(fp_poly
			(pts
				(xy -1.778 1.8796) (xy -1.778 -1.8796) (xy 1.778 -1.8796) (xy 1.778 1.8796)
			)
			(stroke
				(width 0)
				(type default)
			)
			(fill no)
			(layer "F.Fab")
		)
		(pad "D" smd custom
			(at 0 -0.9525 180)
			(size 0.1905 0.1905)
			(layers "F.Cu" "F.Mask" "F.Paste")
			(net "SW_SSD6_R")
			(options
				(clearance outline)
				(anchor circle)
			)
			(primitives
				(gr_poly
					(pts
						(arc
							(start -0.1778 0.5715)
							(mid -0.321484 0.511984)
							(end -0.381 0.3683)
						)
						(arc
							(start -0.381 -0.3683)
							(mid -0.321484 -0.511984)
							(end -0.1778 -0.5715)
						)
						(arc
							(start 0.1778 -0.5715)
							(mid 0.321484 -0.511984)
							(end 0.381 -0.3683)
						)
						(arc
							(start 0.381 0.3683)
							(mid 0.321484 0.511984)
							(end 0.1778 0.5715)
						)
					)
					(width 0)
					(fill yes)
				)
			)
		)
		(pad "G" smd custom
			(at -0.98425 0.9525 180)
			(size 0.1905 0.1905)
			(layers "F.Cu" "F.Mask" "F.Paste")
			(net "SSD6_PWREN")
			(options
				(clearance outline)
				(anchor circle)
			)
			(primitives
				(gr_poly
					(pts
						(arc
							(start -0.1778 0.5715)
							(mid -0.321484 0.511984)
							(end -0.381 0.3683)
						)
						(arc
							(start -0.381 -0.3683)
							(mid -0.321484 -0.511984)
							(end -0.1778 -0.5715)
						)
						(arc
							(start 0.1778 -0.5715)
							(mid 0.321484 -0.511984)
							(end 0.381 -0.3683)
						)
						(arc
							(start 0.381 0.3683)
							(mid 0.321484 0.511984)
							(end 0.1778 0.5715)
						)
					)
					(width 0)
					(fill yes)
				)
			)
		)
		(pad "S" smd custom
			(at 0.98425 0.9525 180)
			(size 0.1905 0.1905)
			(layers "F.Cu" "F.Mask" "F.Paste")
			(net "GND")
			(options
				(clearance outline)
				(anchor circle)
			)
			(primitives
				(gr_poly
					(pts
						(arc
							(start -0.1778 0.5715)
							(mid -0.321484 0.511984)
							(end -0.381 0.3683)
						)
						(arc
							(start -0.381 -0.3683)
							(mid -0.321484 -0.511984)
							(end -0.1778 -0.5715)
						)
						(arc
							(start 0.1778 -0.5715)
							(mid 0.321484 -0.511984)
							(end 0.381 -0.3683)
						)
						(arc
							(start 0.381 0.3683)
							(mid 0.321484 0.511984)
							(end 0.1778 0.5715)
						)
					)
					(width 0)
					(fill yes)
				)
			)
		)
	)
	(footprint ""
		(layer "F.Cu")
		(at 18.50009 -361.899962)
		(property "Reference" "LED11"
			(at 0 0 0)
			(layer "F.SilkS")
			(hide yes)
			(effects
				(font
					(size 1.27 1.27)
				)
			)
		)
		(property "Value" "LED-RB-4-GP"
			(at 5.88899 1.80848 0)
			(unlocked yes)
			(layer "F.Fab")
			(hide yes)
			(effects
				(font
					(size 1.016 1.016)
					(thickness 0.1524)
				)
			)
		)
		(property "Device Type" "LED1613-4PH20"
			(at 5.88899 0.28448 0)
			(unlocked yes)
			(layer "F.Fab")
			(hide yes)
			(effects
				(font
					(size 1.016 1.016)
					(thickness 0.1524)
				)
			)
		)
		(duplicate_pad_numbers_are_jumpers no)
		(fp_line
			(start -1.4478 -0.9652)
			(end 1.4478 -0.9652)
			(stroke
				(width 0.1524)
				(type default)
			)
			(layer "F.SilkS")
		)
		(fp_line
			(start -1.4478 0.9652)
			(end -1.4478 -0.9652)
			(stroke
				(width 0.1524)
				(type default)
			)
			(layer "F.SilkS")
		)
		(fp_line
			(start -1.4478 0.9652)
			(end -1.4478 -0.9652)
			(stroke
				(width 0.508)
				(type default)
			)
			(layer "F.SilkS")
		)
		(fp_line
			(start 1.4478 -0.9652)
			(end 1.4478 0.9652)
			(stroke
				(width 0.1524)
				(type default)
			)
			(layer "F.SilkS")
		)
		(fp_line
			(start 1.4478 0.9652)
			(end -1.4478 0.9652)
			(stroke
				(width 0.1524)
				(type default)
			)
			(layer "F.SilkS")
		)
		(fp_rect
			(start -0.8001 0.6477)
			(end 0.8001 -0.6477)
			(stroke
				(width 0)
				(type default)
			)
			(fill no)
			(layer "F.CrtYd")
		)
		(fp_poly
			(pts
				(xy -1.7018 1.2192) (xy -1.7018 -0.06223) (xy -0.8001 -0.06223) (xy -0.8001 0.6477) (xy 0.8001 0.6477)
				(xy 0.8001 -0.6477) (xy -0.8001 -0.6477) (xy -0.8001 -0.0635) (xy -1.7018 -0.0635) (xy -1.7018 -1.2192)
				(xy 1.7018 -1.2192) (xy 1.7018 1.2192)
			)
			(stroke
				(width 0)
				(type default)
			)
			(fill no)
			(layer "F.CrtYd")
		)
		(fp_rect
			(start -1.7018 1.2192)
			(end 1.7018 -1.2192)
			(stroke
				(width 0)
				(type default)
			)
			(fill no)
			(layer "F.Fab")
		)
		(pad "1" smd rect
			(at -0.73025 0.4064)
			(size 0.9144 0.6096)
			(layers "F.Cu" "F.Mask" "F.Paste")
			(net "SSD_ACT_DR11_MOS_N")
		)
		(pad "2" smd rect
			(at -0.73025 -0.4064)
			(size 0.9144 0.6096)
			(layers "F.Cu" "F.Mask" "F.Paste")
			(net "ATTN_LED_DR11_MOS_N")
		)
		(pad "3" smd rect
			(at 0.73025 -0.4064)
			(size 0.9144 0.6096)
			(layers "F.Cu" "F.Mask" "F.Paste")
			(net "DRV_ATTN_11")
		)
		(pad "4" smd rect
			(at 0.73025 0.4064)
			(size 0.9144 0.6096)
			(layers "F.Cu" "F.Mask" "F.Paste")
			(net "DRV_ACT_11")
		)
	)
	(footprint ""
		(layer "F.Cu")
		(at 19.5072 -103.4288 180)
		(property "Reference" "R9246"
			(at 0 0 180)
			(layer "F.SilkS")
			(hide yes)
			(effects
				(font
					(size 1.27 1.27)
				)
			)
		)
		(property "Value" "2R2010F-GP"
			(at 0.0762 -4.5466 180)
			(unlocked yes)
			(layer "F.Fab")
			(hide yes)
			(effects
				(font
					(size 1.016 1.016)
					(thickness 0.1524)
				)
			)
		)
		(property "Device Type" "R2010H26"
			(at 0.0762 -6.1468 180)
			(unlocked yes)
			(layer "F.Fab")
			(hide yes)
			(effects
				(font
					(size 1.016 1.016)
					(thickness 0.1524)
				)
			)
		)
		(duplicate_pad_numbers_are_jumpers no)
		(fp_line
			(start 3.302 1.651)
			(end 3.302 -1.651)
			(stroke
				(width 0.1524)
				(type default)
			)
			(layer "F.SilkS")
		)
		(fp_line
			(start 3.302 -1.651)
			(end -3.302 -1.651)
			(stroke
				(width 0.1524)
				(type default)
			)
			(layer "F.SilkS")
		)
		(fp_line
			(start -3.302 1.651)
			(end 3.302 1.651)
			(stroke
				(width 0.1524)
				(type default)
			)
			(layer "F.SilkS")
		)
		(fp_line
			(start -3.302 -1.651)
			(end -3.302 1.651)
			(stroke
				(width 0.1524)
				(type default)
			)
			(layer "F.SilkS")
		)
		(fp_rect
			(start -3.3782 1.7272)
			(end 3.3782 -1.7272)
			(stroke
				(width 0)
				(type default)
			)
			(fill no)
			(layer "F.CrtYd")
		)
		(fp_poly
			(pts
				(xy 3.3782 -1.7272) (xy -3.3782 -1.7272) (xy -3.3782 1.7272) (xy 3.3782 1.7272)
			)
			(stroke
				(width 0)
				(type default)
			)
			(fill no)
			(layer "F.Fab")
		)
		(pad "1" smd rect
			(at -2.3495 0 180)
			(size 1.143 2.794)
			(layers "F.Cu" "F.Mask" "F.Paste")
			(net "P12V_SSD13")
		)
		(pad "2" smd rect
			(at 2.3495 0 180)
			(size 1.143 2.794)
			(layers "F.Cu" "F.Mask" "F.Paste")
			(net "12V_PRECH_SSD13")
		)
	)
	(footprint ""
		(layer "F.Cu")
		(at 35.4584 -13.6652 180)
		(property "Reference" "PC1230"
			(at 0 0 180)
			(layer "F.SilkS")
			(hide yes)
			(effects
				(font
					(size 1.27 1.27)
				)
			)
		)
		(property "Value" "SC22U25V6KX-GP-U"
			(at -2.860802 -5.279644 180)
			(unlocked yes)
			(layer "F.Fab")
			(hide yes)
			(effects
				(font
					(size 1.016 1.016)
					(thickness 0.1524)
				)
			)
		)
		(property "Device Type" "C1206-TO0D3H75"
			(at -2.860802 -6.803644 180)
			(unlocked yes)
			(layer "F.Fab")
			(hide yes)
			(effects
				(font
					(size 1.016 1.016)
					(thickness 0.1524)
				)
			)
		)
		(duplicate_pad_numbers_are_jumpers no)
		(fp_line
			(start 1.3081 2.3749)
			(end -1.3081 2.3749)
			(stroke
				(width 0.1524)
				(type default)
			)
			(layer "F.SilkS")
		)
		(fp_line
			(start 1.3081 -2.3749)
			(end 1.3081 2.3749)
			(stroke
				(width 0.1524)
				(type default)
			)
			(layer "F.SilkS")
		)
		(fp_line
			(start -1.3081 2.3749)
			(end -1.3081 -2.3749)
			(stroke
				(width 0.1524)
				(type default)
			)
			(layer "F.SilkS")
		)
		(fp_line
			(start -1.3081 -2.3749)
			(end 1.3081 -2.3749)
			(stroke
				(width 0.1524)
				(type default)
			)
			(layer "F.SilkS")
		)
		(fp_rect
			(start -0.8001 1.6002)
			(end 0.8001 -1.6002)
			(stroke
				(width 0)
				(type default)
			)
			(fill no)
			(layer "F.CrtYd")
		)
		(fp_poly
			(pts
				(xy -1.5621 2.4511) (xy -1.5621 1.6002) (xy 0.8001 1.6002) (xy 0.8001 -1.6002) (xy -0.8001 -1.6002)
				(xy -0.8001 1.5875) (xy -1.5621 1.5875) (xy -1.5621 -2.4511) (xy 1.5621 -2.4511) (xy 1.5621 2.4511)
			)
			(stroke
				(width 0)
				(type default)
			)
			(fill no)
			(layer "F.CrtYd")
		)
		(fp_rect
			(start -1.5621 2.4511)
			(end 1.5621 -2.4511)
			(stroke
				(width 0)
				(type default)
			)
			(fill no)
			(layer "F.Fab")
		)
		(pad "1" smd rect
			(at 0 -1.392936 180)
			(size 2.1082 1.4478)
			(layers "F.Cu" "F.Mask" "F.Paste")
			(net "P12V_SSD14")
		)
		(pad "2" smd rect
			(at 0 1.392936 180)
			(size 2.1082 1.4478)
			(layers "F.Cu" "F.Mask" "F.Paste")
			(net "GND")
		)
	)
	(footprint ""
		(layer "F.Cu")
		(at 31.369 -300.9646 -90)
		(property "Reference" "Q61"
			(at 0 0 270)
			(layer "F.SilkS")
			(hide yes)
			(effects
				(font
					(size 1.27 1.27)
				)
			)
		)
		(property "Value" "2N7002A-7-GP"
			(at 0.127 -8.9662 270)
			(unlocked yes)
			(layer "F.Fab")
			(hide yes)
			(effects
				(font
					(size 1.016 1.016)
					(thickness 0.1524)
				)
			)
		)
		(property "Device Type" "SOT23DGS2D4H48"
			(at 0.127 -10.4902 270)
			(unlocked yes)
			(layer "F.Fab")
			(hide yes)
			(effects
				(font
					(size 1.016 1.016)
					(thickness 0.1524)
				)
			)
		)
		(duplicate_pad_numbers_are_jumpers no)
		(fp_line
			(start -1.651 1.778)
			(end 1.651 1.778)
			(stroke
				(width 0.1524)
				(type default)
			)
			(layer "F.SilkS")
		)
		(fp_line
			(start 1.651 1.778)
			(end 1.651 -1.778)
			(stroke
				(width 0.1524)
				(type default)
			)
			(layer "F.SilkS")
		)
		(fp_line
			(start -1.651 -1.778)
			(end -1.651 1.778)
			(stroke
				(width 0.1524)
				(type default)
			)
			(layer "F.SilkS")
		)
		(fp_line
			(start 1.651 -1.778)
			(end -1.651 -1.778)
			(stroke
				(width 0.1524)
				(type default)
			)
			(layer "F.SilkS")
		)
		(fp_poly
			(pts
				(xy -1.778 1.8796) (xy -1.778 -1.8796) (xy 1.778 -1.8796) (xy 1.778 1.8796)
			)
			(stroke
				(width 0)
				(type default)
			)
			(fill no)
			(layer "F.CrtYd")
		)
		(fp_poly
			(pts
				(xy -1.778 1.8796) (xy -1.778 -1.8796) (xy 1.778 -1.8796) (xy 1.778 1.8796)
			)
			(stroke
				(width 0)
				(type default)
			)
			(fill no)
			(layer "F.Fab")
		)
		(pad "D" smd custom
			(at 0 -0.9525 270)
			(size 0.1905 0.1905)
			(layers "F.Cu" "F.Mask" "F.Paste")
			(net "P12V_MOST7_GATE_D")
			(options
				(clearance outline)
				(anchor circle)
			)
			(primitives
				(gr_poly
					(pts
						(arc
							(start -0.1778 0.5715)
							(mid -0.321484 0.511984)
							(end -0.381 0.3683)
						)
						(arc
							(start -0.381 -0.3683)
							(mid -0.321484 -0.511984)
							(end -0.1778 -0.5715)
						)
						(arc
							(start 0.1778 -0.5715)
							(mid 0.321484 -0.511984)
							(end 0.381 -0.3683)
						)
						(arc
							(start 0.381 0.3683)
							(mid 0.321484 0.511984)
							(end 0.1778 0.5715)
						)
					)
					(width 0)
					(fill yes)
				)
			)
		)
		(pad "G" smd custom
			(at -0.98425 0.9525 270)
			(size 0.1905 0.1905)
			(layers "F.Cu" "F.Mask" "F.Paste")
			(net "P12V_MOST7_GATE")
			(options
				(clearance outline)
				(anchor circle)
			)
			(primitives
				(gr_poly
					(pts
						(arc
							(start -0.1778 0.5715)
							(mid -0.321484 0.511984)
							(end -0.381 0.3683)
						)
						(arc
							(start -0.381 -0.3683)
							(mid -0.321484 -0.511984)
							(end -0.1778 -0.5715)
						)
						(arc
							(start 0.1778 -0.5715)
							(mid 0.321484 -0.511984)
							(end 0.381 -0.3683)
						)
						(arc
							(start 0.381 0.3683)
							(mid 0.321484 0.511984)
							(end 0.1778 0.5715)
						)
					)
					(width 0)
					(fill yes)
				)
			)
		)
		(pad "S" smd custom
			(at 0.98425 0.9525 270)
			(size 0.1905 0.1905)
			(layers "F.Cu" "F.Mask" "F.Paste")
			(net "GND")
			(options
				(clearance outline)
				(anchor circle)
			)
			(primitives
				(gr_poly
					(pts
						(arc
							(start -0.1778 0.5715)
							(mid -0.321484 0.511984)
							(end -0.381 0.3683)
						)
						(arc
							(start -0.381 -0.3683)
							(mid -0.321484 -0.511984)
							(end -0.1778 -0.5715)
						)
						(arc
							(start 0.1778 -0.5715)
							(mid 0.321484 -0.511984)
							(end 0.381 -0.3683)
						)
						(arc
							(start 0.381 0.3683)
							(mid 0.321484 0.511984)
							(end 0.1778 0.5715)
						)
					)
					(width 0)
					(fill yes)
				)
			)
		)
	)
	(footprint ""
		(layer "F.Cu")
		(at 32.95015 -402.57095)
		(property "Reference" "R9818"
			(at 0 0 0)
			(layer "F.SilkS")
			(hide yes)
			(effects
				(font
					(size 1.27 1.27)
				)
			)
		)
		(property "Value" "2K2R5F-GP"
			(at 0 -8.9535 0)
			(unlocked yes)
			(layer "F.Fab")
			(hide yes)
			(effects
				(font
					(size 1.27 1.016)
					(thickness 0.1524)
				)
			)
		)
		(property "Device Type" "R805H24"
			(at 0 -10.6299 0)
			(unlocked yes)
			(layer "F.Fab")
			(hide yes)
			(effects
				(font
					(size 1.27 1.016)
					(thickness 0.1524)
				)
			)
		)
		(duplicate_pad_numbers_are_jumpers no)
		(fp_line
			(start -0.889 -1.7018)
			(end -0.889 0.2794)
			(stroke
				(width 0.1524)
				(type default)
			)
			(layer "F.SilkS")
		)
		(fp_line
			(start -0.889 0.0762)
			(end -0.889 1.7018)
			(stroke
				(width 0.1524)
				(type default)
			)
			(layer "F.SilkS")
		)
		(fp_line
			(start -0.889 1.7018)
			(end 0.889 1.7018)
			(stroke
				(width 0.1524)
				(type default)
			)
			(layer "F.SilkS")
		)
		(fp_line
			(start 0.889 -1.7018)
			(end -0.889 -1.7018)
			(stroke
				(width 0.1524)
				(type default)
			)
			(layer "F.SilkS")
		)
		(fp_line
			(start 0.889 -1.7018)
			(end 0.889 -0.381)
			(stroke
				(width 0.1524)
				(type default)
			)
			(layer "F.SilkS")
		)
		(fp_line
			(start 0.889 1.7018)
			(end 0.889 -0.508)
			(stroke
				(width 0.1524)
				(type default)
			)
			(layer "F.SilkS")
		)
		(fp_poly
			(pts
				(xy 0.9652 -1.778) (xy 0.9652 1.778) (xy -0.9652 1.778) (xy -0.9652 -1.778)
			)
			(stroke
				(width 0)
				(type default)
			)
			(fill no)
			(layer "F.CrtYd")
		)
		(fp_rect
			(start -0.9652 1.778)
			(end 0.9652 -1.778)
			(stroke
				(width 0)
				(type default)
			)
			(fill no)
			(layer "F.Fab")
		)
		(pad "1" smd rect
			(at 0 -0.9652)
			(size 1.397 1.143)
			(layers "F.Cu" "F.Mask" "F.Paste")
			(net "P12V_SSD6")
		)
		(pad "2" smd rect
			(at 0 0.9652)
			(size 1.397 1.143)
			(layers "F.Cu" "F.Mask" "F.Paste")
			(net "P12V_MOST6_GATE_D")
		)
	)
	(footprint ""
		(layer "F.Cu")
		(at 217.043 -185.801 -90)
		(property "Reference" "R394"
			(at 0 0 270)
			(layer "F.SilkS")
			(hide yes)
			(effects
				(font
					(size 1.27 1.27)
				)
			)
		)
		(property "Value" "0R2J-2-GP"
			(at 0.064008 -3.993896 270)
			(unlocked yes)
			(layer "F.Fab")
			(hide yes)
			(effects
				(font
					(size 1.016 1.016)
					(thickness 0.1524)
				)
			)
		)
		(property "Device Type" "R402H16"
			(at 0.064008 -5.517896 270)
			(unlocked yes)
			(layer "F.Fab")
			(hide yes)
			(effects
				(font
					(size 1.016 1.016)
					(thickness 0.1524)
				)
			)
		)
		(duplicate_pad_numbers_are_jumpers no)
		(fp_line
			(start -0.508 -0.9398)
			(end -0.508 0.9398)
			(stroke
				(width 0.1524)
				(type default)
			)
			(layer "F.SilkS")
		)
		(fp_line
			(start 0.508 -0.9398)
			(end -0.508 -0.9398)
			(stroke
				(width 0.1524)
				(type default)
			)
			(layer "F.SilkS")
		)
		(fp_rect
			(start -0.508 0.9398)
			(end 0.508 -0.9398)
			(stroke
				(width 0)
				(type default)
			)
			(fill no)
			(layer "F.CrtYd")
		)
		(fp_rect
			(start -0.508 0.9398)
			(end 0.508 -0.9398)
			(stroke
				(width 0)
				(type default)
			)
			(fill no)
			(layer "F.Fab")
		)
		(pad "1" smd custom
			(at 0 -0.4445 270)
			(size 0.1397 0.1397)
			(layers "F.Cu" "F.Mask" "F.Paste")
			(net "SDA_DR3_R")
			(options
				(clearance outline)
				(anchor circle)
			)
			(primitives
				(gr_poly
					(pts
						(arc
							(start -0.1778 -0.2794)
							(mid -0.249642 -0.249642)
							(end -0.2794 -0.1778)
						)
						(arc
							(start -0.2794 0.1778)
							(mid -0.249642 0.249642)
							(end -0.1778 0.2794)
						)
						(arc
							(start 0.1778 0.2794)
							(mid 0.249642 0.249642)
							(end 0.2794 0.1778)
						)
						(arc
							(start 0.2794 -0.1778)
							(mid 0.249642 -0.249642)
							(end 0.1778 -0.2794)
						)
					)
					(width 0)
					(fill yes)
				)
			)
		)
		(pad "2" smd custom
			(at 0 0.4445 270)
			(size 0.1397 0.1397)
			(layers "F.Cu" "F.Mask" "F.Paste")
			(net "SDA_DR3")
			(options
				(clearance outline)
				(anchor circle)
			)
			(primitives
				(gr_poly
					(pts
						(arc
							(start -0.1778 -0.2794)
							(mid -0.249642 -0.249642)
							(end -0.2794 -0.1778)
						)
						(arc
							(start -0.2794 0.1778)
							(mid -0.249642 0.249642)
							(end -0.1778 0.2794)
						)
						(arc
							(start 0.1778 0.2794)
							(mid 0.249642 0.249642)
							(end 0.2794 0.1778)
						)
						(arc
							(start 0.2794 -0.1778)
							(mid 0.249642 -0.249642)
							(end 0.1778 -0.2794)
						)
					)
					(width 0)
					(fill yes)
				)
			)
		)
	)
	(footprint ""
		(layer "F.Cu")
		(at 8.8138 -476.885 90)
		(property "Reference" "PC1167"
			(at 0 0 90)
			(layer "F.SilkS")
			(hide yes)
			(effects
				(font
					(size 1.27 1.27)
				)
			)
		)
		(property "Value" "SC22U25V6KX-GP-U"
			(at -2.860802 -5.279644 90)
			(unlocked yes)
			(layer "F.Fab")
			(hide yes)
			(effects
				(font
					(size 1.016 1.016)
					(thickness 0.1524)
				)
			)
		)
		(property "Device Type" "C1206-TO0D3H75"
			(at -2.860802 -6.803644 90)
			(unlocked yes)
			(layer "F.Fab")
			(hide yes)
			(effects
				(font
					(size 1.016 1.016)
					(thickness 0.1524)
				)
			)
		)
		(duplicate_pad_numbers_are_jumpers no)
		(fp_line
			(start 1.3081 -2.3749)
			(end 1.3081 2.3749)
			(stroke
				(width 0.1524)
				(type default)
			)
			(layer "F.SilkS")
		)
		(fp_line
			(start -1.3081 -2.3749)
			(end 1.3081 -2.3749)
			(stroke
				(width 0.1524)
				(type default)
			)
			(layer "F.SilkS")
		)
		(fp_line
			(start 1.3081 2.3749)
			(end -1.3081 2.3749)
			(stroke
				(width 0.1524)
				(type default)
			)
			(layer "F.SilkS")
		)
		(fp_line
			(start -1.3081 2.3749)
			(end -1.3081 -2.3749)
			(stroke
				(width 0.1524)
				(type default)
			)
			(layer "F.SilkS")
		)
		(fp_rect
			(start -0.8001 1.6002)
			(end 0.8001 -1.6002)
			(stroke
				(width 0)
				(type default)
			)
			(fill no)
			(layer "F.CrtYd")
		)
		(fp_poly
			(pts
				(xy -1.5621 2.4511) (xy -1.5621 1.6002) (xy 0.8001 1.6002) (xy 0.8001 -1.6002) (xy -0.8001 -1.6002)
				(xy -0.8001 1.5875) (xy -1.5621 1.5875) (xy -1.5621 -2.4511) (xy 1.5621 -2.4511) (xy 1.5621 2.4511)
			)
			(stroke
				(width 0)
				(type default)
			)
			(fill no)
			(layer "F.CrtYd")
		)
		(fp_rect
			(start -1.5621 2.4511)
			(end 1.5621 -2.4511)
			(stroke
				(width 0)
				(type default)
			)
			(fill no)
			(layer "F.Fab")
		)
		(pad "1" smd rect
			(at 0 -1.392936 90)
			(size 2.1082 1.4478)
			(layers "F.Cu" "F.Mask" "F.Paste")
			(net "P12V")
		)
		(pad "2" smd rect
			(at 0 1.392936 90)
			(size 2.1082 1.4478)
			(layers "F.Cu" "F.Mask" "F.Paste")
			(net "GND")
		)
	)
	(footprint ""
		(layer "F.Cu")
		(at 233.807 -241.802158 180)
		(property "Reference" "Q38"
			(at 0 0 180)
			(layer "F.SilkS")
			(hide yes)
			(effects
				(font
					(size 1.27 1.27)
				)
			)
		)
		(property "Value" "2N7002A-7-GP"
			(at 0.127 -8.9662 180)
			(unlocked yes)
			(layer "F.Fab")
			(hide yes)
			(effects
				(font
					(size 1.016 1.016)
					(thickness 0.1524)
				)
			)
		)
		(property "Device Type" "SOT23DGS2D4H48"
			(at 0.127 -10.4902 180)
			(unlocked yes)
			(layer "F.Fab")
			(hide yes)
			(effects
				(font
					(size 1.016 1.016)
					(thickness 0.1524)
				)
			)
		)
		(duplicate_pad_numbers_are_jumpers no)
		(fp_line
			(start 1.651 1.778)
			(end 1.651 -1.778)
			(stroke
				(width 0.1524)
				(type default)
			)
			(layer "F.SilkS")
		)
		(fp_line
			(start 1.651 -1.778)
			(end -1.651 -1.778)
			(stroke
				(width 0.1524)
				(type default)
			)
			(layer "F.SilkS")
		)
		(fp_line
			(start -1.651 1.778)
			(end 1.651 1.778)
			(stroke
				(width 0.1524)
				(type default)
			)
			(layer "F.SilkS")
		)
		(fp_line
			(start -1.651 -1.778)
			(end -1.651 1.778)
			(stroke
				(width 0.1524)
				(type default)
			)
			(layer "F.SilkS")
		)
		(fp_poly
			(pts
				(xy -1.778 1.8796) (xy -1.778 -1.8796) (xy 1.778 -1.8796) (xy 1.778 1.8796)
			)
			(stroke
				(width 0)
				(type default)
			)
			(fill no)
			(layer "F.CrtYd")
		)
		(fp_poly
			(pts
				(xy -1.778 1.8796) (xy -1.778 -1.8796) (xy 1.778 -1.8796) (xy 1.778 1.8796)
			)
			(stroke
				(width 0)
				(type default)
			)
			(fill no)
			(layer "F.Fab")
		)
		(pad "D" smd custom
			(at 0 -0.9525 180)
			(size 0.1905 0.1905)
			(layers "F.Cu" "F.Mask" "F.Paste")
			(net "SSD_ACT_DR2_MOS_N")
			(options
				(clearance outline)
				(anchor circle)
			)
			(primitives
				(gr_poly
					(pts
						(arc
							(start -0.1778 0.5715)
							(mid -0.321484 0.511984)
							(end -0.381 0.3683)
						)
						(arc
							(start -0.381 -0.3683)
							(mid -0.321484 -0.511984)
							(end -0.1778 -0.5715)
						)
						(arc
							(start 0.1778 -0.5715)
							(mid 0.321484 -0.511984)
							(end 0.381 -0.3683)
						)
						(arc
							(start 0.381 0.3683)
							(mid 0.321484 0.511984)
							(end 0.1778 0.5715)
						)
					)
					(width 0)
					(fill yes)
				)
			)
		)
		(pad "G" smd custom
			(at -0.98425 0.9525 180)
			(size 0.1905 0.1905)
			(layers "F.Cu" "F.Mask" "F.Paste")
			(net "ATTN_LED_DR2_AND_R")
			(options
				(clearance outline)
				(anchor circle)
			)
			(primitives
				(gr_poly
					(pts
						(arc
							(start -0.1778 0.5715)
							(mid -0.321484 0.511984)
							(end -0.381 0.3683)
						)
						(arc
							(start -0.381 -0.3683)
							(mid -0.321484 -0.511984)
							(end -0.1778 -0.5715)
						)
						(arc
							(start 0.1778 -0.5715)
							(mid 0.321484 -0.511984)
							(end 0.381 -0.3683)
						)
						(arc
							(start 0.381 0.3683)
							(mid 0.321484 0.511984)
							(end 0.1778 0.5715)
						)
					)
					(width 0)
					(fill yes)
				)
			)
		)
		(pad "S" smd custom
			(at 0.98425 0.9525 180)
			(size 0.1905 0.1905)
			(layers "F.Cu" "F.Mask" "F.Paste")
			(net "SSD_ACT_DR2_R")
			(options
				(clearance outline)
				(anchor circle)
			)
			(primitives
				(gr_poly
					(pts
						(arc
							(start -0.1778 0.5715)
							(mid -0.321484 0.511984)
							(end -0.381 0.3683)
						)
						(arc
							(start -0.381 -0.3683)
							(mid -0.321484 -0.511984)
							(end -0.1778 -0.5715)
						)
						(arc
							(start 0.1778 -0.5715)
							(mid 0.321484 -0.511984)
							(end 0.381 -0.3683)
						)
						(arc
							(start 0.381 0.3683)
							(mid 0.321484 0.511984)
							(end 0.1778 0.5715)
						)
					)
					(width 0)
					(fill yes)
				)
			)
		)
	)
	(footprint ""
		(layer "F.Cu")
		(at 220.726 -241.040158)
		(property "Reference" "Q39"
			(at 0 0 0)
			(layer "F.SilkS")
			(hide yes)
			(effects
				(font
					(size 1.27 1.27)
				)
			)
		)
		(property "Value" "2N7002A-7-GP"
			(at 0.127 -8.9662 0)
			(unlocked yes)
			(layer "F.Fab")
			(hide yes)
			(effects
				(font
					(size 1.016 1.016)
					(thickness 0.1524)
				)
			)
		)
		(property "Device Type" "SOT23DGS2D4H48"
			(at 0.127 -10.4902 0)
			(unlocked yes)
			(layer "F.Fab")
			(hide yes)
			(effects
				(font
					(size 1.016 1.016)
					(thickness 0.1524)
				)
			)
		)
		(duplicate_pad_numbers_are_jumpers no)
		(fp_line
			(start -1.651 -1.778)
			(end -1.651 1.778)
			(stroke
				(width 0.1524)
				(type default)
			)
			(layer "F.SilkS")
		)
		(fp_line
			(start -1.651 1.778)
			(end 1.651 1.778)
			(stroke
				(width 0.1524)
				(type default)
			)
			(layer "F.SilkS")
		)
		(fp_line
			(start 1.651 -1.778)
			(end -1.651 -1.778)
			(stroke
				(width 0.1524)
				(type default)
			)
			(layer "F.SilkS")
		)
		(fp_line
			(start 1.651 1.778)
			(end 1.651 -1.778)
			(stroke
				(width 0.1524)
				(type default)
			)
			(layer "F.SilkS")
		)
		(fp_poly
			(pts
				(xy -1.778 1.8796) (xy -1.778 -1.8796) (xy 1.778 -1.8796) (xy 1.778 1.8796)
			)
			(stroke
				(width 0)
				(type default)
			)
			(fill no)
			(layer "F.CrtYd")
		)
		(fp_poly
			(pts
				(xy -1.778 1.8796) (xy -1.778 -1.8796) (xy 1.778 -1.8796) (xy 1.778 1.8796)
			)
			(stroke
				(width 0)
				(type default)
			)
			(fill no)
			(layer "F.Fab")
		)
		(pad "D" smd custom
			(at 0 -0.9525)
			(size 0.1905 0.1905)
			(layers "F.Cu" "F.Mask" "F.Paste")
			(net "SSD2_CLK0_OE_MOS_N")
			(options
				(clearance outline)
				(anchor circle)
			)
			(primitives
				(gr_poly
					(pts
						(arc
							(start -0.1778 0.5715)
							(mid -0.321484 0.511984)
							(end -0.381 0.3683)
						)
						(arc
							(start -0.381 -0.3683)
							(mid -0.321484 -0.511984)
							(end -0.1778 -0.5715)
						)
						(arc
							(start 0.1778 -0.5715)
							(mid 0.321484 -0.511984)
							(end 0.381 -0.3683)
						)
						(arc
							(start 0.381 0.3683)
							(mid 0.321484 0.511984)
							(end 0.1778 0.5715)
						)
					)
					(width 0)
					(fill yes)
				)
			)
		)
		(pad "G" smd custom
			(at -0.98425 0.9525)
			(size 0.1905 0.1905)
			(layers "F.Cu" "F.Mask" "F.Paste")
			(net "SSD2_CLK0_OE_R_N")
			(options
				(clearance outline)
				(anchor circle)
			)
			(primitives
				(gr_poly
					(pts
						(arc
							(start -0.1778 0.5715)
							(mid -0.321484 0.511984)
							(end -0.381 0.3683)
						)
						(arc
							(start -0.381 -0.3683)
							(mid -0.321484 -0.511984)
							(end -0.1778 -0.5715)
						)
						(arc
							(start 0.1778 -0.5715)
							(mid 0.321484 -0.511984)
							(end 0.381 -0.3683)
						)
						(arc
							(start 0.381 0.3683)
							(mid 0.321484 0.511984)
							(end 0.1778 0.5715)
						)
					)
					(width 0)
					(fill yes)
				)
			)
		)
		(pad "S" smd custom
			(at 0.98425 0.9525)
			(size 0.1905 0.1905)
			(layers "F.Cu" "F.Mask" "F.Paste")
			(net "GND")
			(options
				(clearance outline)
				(anchor circle)
			)
			(primitives
				(gr_poly
					(pts
						(arc
							(start -0.1778 0.5715)
							(mid -0.321484 0.511984)
							(end -0.381 0.3683)
						)
						(arc
							(start -0.381 -0.3683)
							(mid -0.321484 -0.511984)
							(end -0.1778 -0.5715)
						)
						(arc
							(start 0.1778 -0.5715)
							(mid 0.321484 -0.511984)
							(end 0.381 -0.3683)
						)
						(arc
							(start 0.381 0.3683)
							(mid 0.321484 0.511984)
							(end 0.1778 0.5715)
						)
					)
					(width 0)
					(fill yes)
				)
			)
		)
	)
	(footprint ""
		(layer "F.Cu")
		(at 37.719 -297.561 180)
		(property "Reference" "PC1247"
			(at 0 0 180)
			(layer "F.SilkS")
			(hide yes)
			(effects
				(font
					(size 1.27 1.27)
				)
			)
		)
		(property "Value" "SCD1U50V3KX-GP"
			(at 0 -2.8194 180)
			(unlocked yes)
			(layer "F.Fab")
			(hide yes)
			(effects
				(font
					(size 1.016 1.016)
					(thickness 0.1524)
				)
			)
		)
		(property "Device Type" "C603H36"
			(at 0 -4.3434 180)
			(unlocked yes)
			(layer "F.Fab")
			(hide yes)
			(effects
				(font
					(size 1.016 1.016)
					(thickness 0.1524)
				)
			)
		)
		(duplicate_pad_numbers_are_jumpers no)
		(fp_line
			(start 0.508 0)
			(end -0.508 0)
			(stroke
				(width 0.2032)
				(type default)
			)
			(layer "F.SilkS")
		)
		(fp_rect
			(start -0.5842 1.3335)
			(end 0.5842 -1.3335)
			(stroke
				(width 0)
				(type default)
			)
			(fill no)
			(layer "F.CrtYd")
		)
		(fp_rect
			(start -0.5842 1.3335)
			(end 0.5842 -1.3335)
			(stroke
				(width 0)
				(type default)
			)
			(fill no)
			(layer "F.Fab")
		)
		(pad "1" smd custom
			(at 0 -0.762 180)
			(size 0.2159 0.2159)
			(layers "F.Cu" "F.Mask" "F.Paste")
			(net "P12V_SSD7")
			(options
				(clearance outline)
				(anchor circle)
			)
			(primitives
				(gr_poly
					(pts
						(arc
							(start -0.3302 -0.4318)
							(mid -0.402042 -0.402042)
							(end -0.4318 -0.3302)
						)
						(arc
							(start -0.4318 0.3302)
							(mid -0.402042 0.402042)
							(end -0.3302 0.4318)
						)
						(arc
							(start 0.3302 0.4318)
							(mid 0.402042 0.402042)
							(end 0.4318 0.3302)
						)
						(arc
							(start 0.4318 -0.3302)
							(mid 0.402042 -0.402042)
							(end 0.3302 -0.4318)
						)
					)
					(width 0)
					(fill yes)
				)
			)
		)
		(pad "2" smd custom
			(at 0 0.762 180)
			(size 0.2159 0.2159)
			(layers "F.Cu" "F.Mask" "F.Paste")
			(net "GND")
			(options
				(clearance outline)
				(anchor circle)
			)
			(primitives
				(gr_poly
					(pts
						(arc
							(start -0.3302 -0.4318)
							(mid -0.402042 -0.402042)
							(end -0.4318 -0.3302)
						)
						(arc
							(start -0.4318 0.3302)
							(mid -0.402042 0.402042)
							(end -0.3302 0.4318)
						)
						(arc
							(start 0.3302 0.4318)
							(mid 0.402042 0.402042)
							(end 0.4318 0.3302)
						)
						(arc
							(start 0.4318 -0.3302)
							(mid 0.402042 -0.402042)
							(end 0.3302 -0.4318)
						)
					)
					(width 0)
					(fill yes)
				)
			)
		)
	)
	(footprint ""
		(layer "F.Cu")
		(at 214.9348 -187.579)
		(property "Reference" "SR1097"
			(at 0 0 0)
			(layer "F.SilkS")
			(hide yes)
			(effects
				(font
					(size 1.27 1.27)
				)
			)
		)
		(property "Value" "4K7R2F-GP"
			(at 0.064008 -3.993896 0)
			(unlocked yes)
			(layer "F.Fab")
			(hide yes)
			(effects
				(font
					(size 1.016 1.016)
					(thickness 0.1524)
				)
			)
		)
		(property "Device Type" "R402H16"
			(at 0.064008 -5.517896 0)
			(unlocked yes)
			(layer "F.Fab")
			(hide yes)
			(effects
				(font
					(size 1.016 1.016)
					(thickness 0.1524)
				)
			)
		)
		(duplicate_pad_numbers_are_jumpers no)
		(fp_line
			(start -0.508 -0.9398)
			(end -0.508 0.9398)
			(stroke
				(width 0.1524)
				(type default)
			)
			(layer "F.SilkS")
		)
		(fp_line
			(start 0.508 -0.9398)
			(end -0.508 -0.9398)
			(stroke
				(width 0.1524)
				(type default)
			)
			(layer "F.SilkS")
		)
		(fp_rect
			(start -0.508 0.9398)
			(end 0.508 -0.9398)
			(stroke
				(width 0)
				(type default)
			)
			(fill no)
			(layer "F.CrtYd")
		)
		(fp_rect
			(start -0.508 0.9398)
			(end 0.508 -0.9398)
			(stroke
				(width 0)
				(type default)
			)
			(fill no)
			(layer "F.Fab")
		)
		(pad "1" smd custom
			(at 0 -0.4445)
			(size 0.1397 0.1397)
			(layers "F.Cu" "F.Mask" "F.Paste")
			(net "P3V3")
			(options
				(clearance outline)
				(anchor circle)
			)
			(primitives
				(gr_poly
					(pts
						(arc
							(start -0.1778 -0.2794)
							(mid -0.249642 -0.249642)
							(end -0.2794 -0.1778)
						)
						(arc
							(start -0.2794 0.1778)
							(mid -0.249642 0.249642)
							(end -0.1778 0.2794)
						)
						(arc
							(start 0.1778 0.2794)
							(mid 0.249642 0.249642)
							(end 0.2794 0.1778)
						)
						(arc
							(start 0.2794 -0.1778)
							(mid 0.249642 -0.249642)
							(end 0.1778 -0.2794)
						)
					)
					(width 0)
					(fill yes)
				)
			)
		)
		(pad "2" smd custom
			(at 0 0.4445)
			(size 0.1397 0.1397)
			(layers "F.Cu" "F.Mask" "F.Paste")
			(net "DUALPORTEN#3")
			(options
				(clearance outline)
				(anchor circle)
			)
			(primitives
				(gr_poly
					(pts
						(arc
							(start -0.1778 -0.2794)
							(mid -0.249642 -0.249642)
							(end -0.2794 -0.1778)
						)
						(arc
							(start -0.2794 0.1778)
							(mid -0.249642 0.249642)
							(end -0.1778 0.2794)
						)
						(arc
							(start 0.1778 0.2794)
							(mid 0.249642 0.249642)
							(end 0.2794 0.1778)
						)
						(arc
							(start 0.2794 -0.1778)
							(mid 0.249642 -0.249642)
							(end 0.1778 -0.2794)
						)
					)
					(width 0)
					(fill yes)
				)
			)
		)
	)
	(footprint ""
		(layer "F.Cu")
		(at 211.582 -51.562 -90)
		(property "Reference" "C342"
			(at 0 0 270)
			(layer "F.SilkS")
			(hide yes)
			(effects
				(font
					(size 1.27 1.27)
				)
			)
		)
		(property "Value" "SCD1U16V2KX-3GP"
			(at 1.1811 -2.7051 270)
			(unlocked yes)
			(layer "F.Fab")
			(hide yes)
			(effects
				(font
					(size 1.016 1.016)
					(thickness 0.1524)
				)
			)
		)
		(property "Device Type" "C402H22"
			(at 1.1811 -4.2291 270)
			(unlocked yes)
			(layer "F.Fab")
			(hide yes)
			(effects
				(font
					(size 1.016 1.016)
					(thickness 0.1524)
				)
			)
		)
		(duplicate_pad_numbers_are_jumpers no)
		(fp_rect
			(start -0.4318 0.9525)
			(end 0.4318 -0.9525)
			(stroke
				(width 0)
				(type default)
			)
			(fill no)
			(layer "F.CrtYd")
		)
		(fp_rect
			(start -0.4318 0.9525)
			(end 0.4318 -0.9525)
			(stroke
				(width 0)
				(type default)
			)
			(fill no)
			(layer "F.Fab")
		)
		(pad "1" smd custom
			(at 0 -0.4445 270)
			(size 0.1524 0.1524)
			(layers "F.Cu" "F.Mask" "F.Paste")
			(net "P3V3")
			(options
				(clearance outline)
				(anchor circle)
			)
			(primitives
				(gr_poly
					(pts
						(arc
							(start 0.3048 -0.2032)
							(mid 0.275042 -0.275042)
							(end 0.2032 -0.3048)
						)
						(arc
							(start -0.2032 -0.3048)
							(mid -0.275042 -0.275042)
							(end -0.3048 -0.2032)
						)
						(arc
							(start -0.3048 0.2032)
							(mid -0.275042 0.275042)
							(end -0.2032 0.3048)
						)
						(arc
							(start 0.2032 0.3048)
							(mid 0.275042 0.275042)
							(end 0.3048 0.2032)
						)
					)
					(width 0)
					(fill yes)
				)
			)
		)
		(pad "2" smd custom
			(at 0 0.4445 270)
			(size 0.1524 0.1524)
			(layers "F.Cu" "F.Mask" "F.Paste")
			(net "GND")
			(options
				(clearance outline)
				(anchor circle)
			)
			(primitives
				(gr_poly
					(pts
						(arc
							(start 0.3048 -0.2032)
							(mid 0.275042 -0.275042)
							(end 0.2032 -0.3048)
						)
						(arc
							(start -0.2032 -0.3048)
							(mid -0.275042 -0.275042)
							(end -0.3048 -0.2032)
						)
						(arc
							(start -0.3048 0.2032)
							(mid -0.275042 0.275042)
							(end -0.2032 0.3048)
						)
						(arc
							(start 0.2032 0.3048)
							(mid 0.275042 0.275042)
							(end 0.3048 0.2032)
						)
					)
					(width 0)
					(fill yes)
				)
			)
		)
	)
	(footprint ""
		(layer "F.Cu")
		(at 7.6708 -378.4854 180)
		(property "Reference" "C9535"
			(at 0 0 180)
			(layer "F.SilkS")
			(hide yes)
			(effects
				(font
					(size 1.27 1.27)
				)
			)
		)
		(property "Value" "SCD01U50V2KX-1GP"
			(at 1.1811 -2.7051 180)
			(unlocked yes)
			(layer "F.Fab")
			(hide yes)
			(effects
				(font
					(size 1.016 1.016)
					(thickness 0.1524)
				)
			)
		)
		(property "Device Type" "C402H22"
			(at 1.1811 -4.2291 180)
			(unlocked yes)
			(layer "F.Fab")
			(hide yes)
			(effects
				(font
					(size 1.016 1.016)
					(thickness 0.1524)
				)
			)
		)
		(duplicate_pad_numbers_are_jumpers no)
		(fp_rect
			(start -0.4318 0.9525)
			(end 0.4318 -0.9525)
			(stroke
				(width 0)
				(type default)
			)
			(fill no)
			(layer "F.CrtYd")
		)
		(fp_rect
			(start -0.4318 0.9525)
			(end 0.4318 -0.9525)
			(stroke
				(width 0)
				(type default)
			)
			(fill no)
			(layer "F.Fab")
		)
		(pad "1" smd custom
			(at 0 -0.4445 180)
			(size 0.1524 0.1524)
			(layers "F.Cu" "F.Mask" "F.Paste")
			(net "PE_100M_CLK1_P")
			(options
				(clearance outline)
				(anchor circle)
			)
			(primitives
				(gr_poly
					(pts
						(arc
							(start 0.3048 -0.2032)
							(mid 0.275042 -0.275042)
							(end 0.2032 -0.3048)
						)
						(arc
							(start -0.2032 -0.3048)
							(mid -0.275042 -0.275042)
							(end -0.3048 -0.2032)
						)
						(arc
							(start -0.3048 0.2032)
							(mid -0.275042 0.275042)
							(end -0.2032 0.3048)
						)
						(arc
							(start 0.2032 0.3048)
							(mid 0.275042 0.275042)
							(end 0.3048 0.2032)
						)
					)
					(width 0)
					(fill yes)
				)
			)
		)
		(pad "2" smd custom
			(at 0 0.4445 180)
			(size 0.1524 0.1524)
			(layers "F.Cu" "F.Mask" "F.Paste")
			(net "PE_100M_CLK1_C_P")
			(options
				(clearance outline)
				(anchor circle)
			)
			(primitives
				(gr_poly
					(pts
						(arc
							(start 0.3048 -0.2032)
							(mid 0.275042 -0.275042)
							(end 0.2032 -0.3048)
						)
						(arc
							(start -0.2032 -0.3048)
							(mid -0.275042 -0.275042)
							(end -0.3048 -0.2032)
						)
						(arc
							(start -0.3048 0.2032)
							(mid -0.275042 0.275042)
							(end -0.2032 0.3048)
						)
						(arc
							(start 0.2032 0.3048)
							(mid 0.275042 0.275042)
							(end 0.3048 0.2032)
						)
					)
					(width 0)
					(fill yes)
				)
			)
		)
	)
	(footprint ""
		(layer "F.Cu")
		(at 29.845 -217.17 90)
		(property "Reference" "R414"
			(at 0 0 90)
			(layer "F.SilkS")
			(hide yes)
			(effects
				(font
					(size 1.27 1.27)
				)
			)
		)
		(property "Value" "0R2J-2-GP"
			(at 0.064008 -3.993896 90)
			(unlocked yes)
			(layer "F.Fab")
			(hide yes)
			(effects
				(font
					(size 1.016 1.016)
					(thickness 0.1524)
				)
			)
		)
		(property "Device Type" "R402H16"
			(at 0.064008 -5.517896 90)
			(unlocked yes)
			(layer "F.Fab")
			(hide yes)
			(effects
				(font
					(size 1.016 1.016)
					(thickness 0.1524)
				)
			)
		)
		(duplicate_pad_numbers_are_jumpers no)
		(fp_line
			(start 0.508 -0.9398)
			(end -0.508 -0.9398)
			(stroke
				(width 0.1524)
				(type default)
			)
			(layer "F.SilkS")
		)
		(fp_line
			(start -0.508 -0.9398)
			(end -0.508 0.9398)
			(stroke
				(width 0.1524)
				(type default)
			)
			(layer "F.SilkS")
		)
		(fp_rect
			(start -0.508 0.9398)
			(end 0.508 -0.9398)
			(stroke
				(width 0)
				(type default)
			)
			(fill no)
			(layer "F.CrtYd")
		)
		(fp_rect
			(start -0.508 0.9398)
			(end 0.508 -0.9398)
			(stroke
				(width 0)
				(type default)
			)
			(fill no)
			(layer "F.Fab")
		)
		(pad "1" smd custom
			(at 0 -0.4445 90)
			(size 0.1397 0.1397)
			(layers "F.Cu" "F.Mask" "F.Paste")
			(net "SDA_DR12_R")
			(options
				(clearance outline)
				(anchor circle)
			)
			(primitives
				(gr_poly
					(pts
						(arc
							(start -0.1778 -0.2794)
							(mid -0.249642 -0.249642)
							(end -0.2794 -0.1778)
						)
						(arc
							(start -0.2794 0.1778)
							(mid -0.249642 0.249642)
							(end -0.1778 0.2794)
						)
						(arc
							(start 0.1778 0.2794)
							(mid 0.249642 0.249642)
							(end 0.2794 0.1778)
						)
						(arc
							(start 0.2794 -0.1778)
							(mid 0.249642 -0.249642)
							(end 0.1778 -0.2794)
						)
					)
					(width 0)
					(fill yes)
				)
			)
		)
		(pad "2" smd custom
			(at 0 0.4445 90)
			(size 0.1397 0.1397)
			(layers "F.Cu" "F.Mask" "F.Paste")
			(net "SDA_DR12")
			(options
				(clearance outline)
				(anchor circle)
			)
			(primitives
				(gr_poly
					(pts
						(arc
							(start -0.1778 -0.2794)
							(mid -0.249642 -0.249642)
							(end -0.2794 -0.1778)
						)
						(arc
							(start -0.2794 0.1778)
							(mid -0.249642 0.249642)
							(end -0.1778 0.2794)
						)
						(arc
							(start 0.1778 0.2794)
							(mid 0.249642 0.249642)
							(end 0.2794 0.1778)
						)
						(arc
							(start 0.2794 -0.1778)
							(mid 0.249642 -0.249642)
							(end 0.1778 -0.2794)
						)
					)
					(width 0)
					(fill yes)
				)
			)
		)
	)
	(footprint ""
		(layer "F.Cu")
		(at 98.806 -317.246 -90)
		(property "Reference" "C9359"
			(at 0 0 270)
			(layer "F.SilkS")
			(hide yes)
			(effects
				(font
					(size 1.27 1.27)
				)
			)
		)
		(property "Value" "SC1KP50V2KX-1GP"
			(at 1.1811 -2.7051 270)
			(unlocked yes)
			(layer "F.Fab")
			(hide yes)
			(effects
				(font
					(size 1.016 1.016)
					(thickness 0.1524)
				)
			)
		)
		(property "Device Type" "C402H22"
			(at 1.1811 -4.2291 270)
			(unlocked yes)
			(layer "F.Fab")
			(hide yes)
			(effects
				(font
					(size 1.016 1.016)
					(thickness 0.1524)
				)
			)
		)
		(duplicate_pad_numbers_are_jumpers no)
		(fp_rect
			(start -0.4318 0.9525)
			(end 0.4318 -0.9525)
			(stroke
				(width 0)
				(type default)
			)
			(fill no)
			(layer "F.CrtYd")
		)
		(fp_rect
			(start -0.4318 0.9525)
			(end 0.4318 -0.9525)
			(stroke
				(width 0)
				(type default)
			)
			(fill no)
			(layer "F.Fab")
		)
		(pad "1" smd custom
			(at 0 -0.4445 270)
			(size 0.1524 0.1524)
			(layers "F.Cu" "F.Mask" "F.Paste")
			(net "SSD_PRSNT6")
			(options
				(clearance outline)
				(anchor circle)
			)
			(primitives
				(gr_poly
					(pts
						(arc
							(start 0.3048 -0.2032)
							(mid 0.275042 -0.275042)
							(end 0.2032 -0.3048)
						)
						(arc
							(start -0.2032 -0.3048)
							(mid -0.275042 -0.275042)
							(end -0.3048 -0.2032)
						)
						(arc
							(start -0.3048 0.2032)
							(mid -0.275042 0.275042)
							(end -0.2032 0.3048)
						)
						(arc
							(start 0.2032 0.3048)
							(mid 0.275042 0.275042)
							(end 0.3048 0.2032)
						)
					)
					(width 0)
					(fill yes)
				)
			)
		)
		(pad "2" smd custom
			(at 0 0.4445 270)
			(size 0.1524 0.1524)
			(layers "F.Cu" "F.Mask" "F.Paste")
			(net "GND")
			(options
				(clearance outline)
				(anchor circle)
			)
			(primitives
				(gr_poly
					(pts
						(arc
							(start 0.3048 -0.2032)
							(mid 0.275042 -0.275042)
							(end 0.2032 -0.3048)
						)
						(arc
							(start -0.2032 -0.3048)
							(mid -0.275042 -0.275042)
							(end -0.3048 -0.2032)
						)
						(arc
							(start -0.3048 0.2032)
							(mid -0.275042 0.275042)
							(end -0.2032 0.3048)
						)
						(arc
							(start 0.2032 0.3048)
							(mid 0.275042 0.275042)
							(end 0.3048 0.2032)
						)
					)
					(width 0)
					(fill yes)
				)
			)
		)
	)
	(footprint ""
		(layer "F.Cu")
		(at 247.904 -415.544)
		(property "Reference" "TP1"
			(at 0 0 0)
			(layer "F.SilkS")
			(hide yes)
			(effects
				(font
					(size 1.27 1.27)
				)
			)
		)
		(property "Value" "TPAD28-2-GP"
			(at -0.0127 -1.6637 0)
			(unlocked yes)
			(layer "F.Fab")
			(hide yes)
			(effects
				(font
					(size 1.016 1.016)
					(thickness 0.1524)
				)
			)
		)
		(property "Device Type" "TPAD28"
			(at -0.0127 -3.1877 0)
			(unlocked yes)
			(layer "F.Fab")
			(hide yes)
			(effects
				(font
					(size 1.016 1.016)
					(thickness 0.1524)
				)
			)
		)
		(duplicate_pad_numbers_are_jumpers no)
		(fp_poly
			(pts
				(arc
					(start 0.3556 0)
					(mid -0.3556 0)
					(end 0.3556 0)
				)
			)
			(stroke
				(width 0)
				(type default)
			)
			(fill no)
			(layer "F.CrtYd")
		)
		(fp_poly
			(pts
				(arc
					(start 0.6096 0)
					(mid -0.6096 0)
					(end 0.6096 0)
				)
			)
			(stroke
				(width 0)
				(type default)
			)
			(fill no)
			(layer "F.Fab")
		)
		(pad "1" smd circle
			(at 0 0)
			(size 0.7112 0.7112)
			(layers "F.Cu" "F.Mask" "F.Paste")
			(net "N70929042")
		)
	)
	(footprint ""
		(layer "F.Cu")
		(at 17.145 -492.887 -90)
		(property "Reference" "R143"
			(at 0 0 270)
			(layer "F.SilkS")
			(hide yes)
			(effects
				(font
					(size 1.27 1.27)
				)
			)
		)
		(property "Value" "4K7R2J-2-GP"
			(at 0.064008 -3.993896 270)
			(unlocked yes)
			(layer "F.Fab")
			(hide yes)
			(effects
				(font
					(size 1.016 1.016)
					(thickness 0.1524)
				)
			)
		)
		(property "Device Type" "R402H16"
			(at 0.064008 -5.517896 270)
			(unlocked yes)
			(layer "F.Fab")
			(hide yes)
			(effects
				(font
					(size 1.016 1.016)
					(thickness 0.1524)
				)
			)
		)
		(duplicate_pad_numbers_are_jumpers no)
		(fp_line
			(start -0.508 -0.9398)
			(end -0.508 0.9398)
			(stroke
				(width 0.1524)
				(type default)
			)
			(layer "F.SilkS")
		)
		(fp_line
			(start 0.508 -0.9398)
			(end -0.508 -0.9398)
			(stroke
				(width 0.1524)
				(type default)
			)
			(layer "F.SilkS")
		)
		(fp_rect
			(start -0.508 0.9398)
			(end 0.508 -0.9398)
			(stroke
				(width 0)
				(type default)
			)
			(fill no)
			(layer "F.CrtYd")
		)
		(fp_rect
			(start -0.508 0.9398)
			(end 0.508 -0.9398)
			(stroke
				(width 0)
				(type default)
			)
			(fill no)
			(layer "F.Fab")
		)
		(pad "1" smd custom
			(at 0 -0.4445 270)
			(size 0.1397 0.1397)
			(layers "F.Cu" "F.Mask" "F.Paste")
			(net "P12V")
			(options
				(clearance outline)
				(anchor circle)
			)
			(primitives
				(gr_poly
					(pts
						(arc
							(start -0.1778 -0.2794)
							(mid -0.249642 -0.249642)
							(end -0.2794 -0.1778)
						)
						(arc
							(start -0.2794 0.1778)
							(mid -0.249642 0.249642)
							(end -0.1778 0.2794)
						)
						(arc
							(start 0.1778 0.2794)
							(mid 0.249642 0.249642)
							(end 0.2794 0.1778)
						)
						(arc
							(start 0.2794 -0.1778)
							(mid 0.249642 -0.249642)
							(end 0.1778 -0.2794)
						)
					)
					(width 0)
					(fill yes)
				)
			)
		)
		(pad "2" smd custom
			(at 0 0.4445 270)
			(size 0.1397 0.1397)
			(layers "F.Cu" "F.Mask" "F.Paste")
			(net "SW_SSD5_R")
			(options
				(clearance outline)
				(anchor circle)
			)
			(primitives
				(gr_poly
					(pts
						(arc
							(start -0.1778 -0.2794)
							(mid -0.249642 -0.249642)
							(end -0.2794 -0.1778)
						)
						(arc
							(start -0.2794 0.1778)
							(mid -0.249642 0.249642)
							(end -0.1778 0.2794)
						)
						(arc
							(start 0.1778 0.2794)
							(mid 0.249642 0.249642)
							(end 0.2794 0.1778)
						)
						(arc
							(start 0.2794 -0.1778)
							(mid 0.249642 -0.249642)
							(end 0.1778 -0.2794)
						)
					)
					(width 0)
					(fill yes)
				)
			)
		)
	)
	(footprint ""
		(layer "F.Cu")
		(at 228.283516 -140.83411 180)
		(property "Reference" "SR1128"
			(at 0 0 180)
			(layer "F.SilkS")
			(hide yes)
			(effects
				(font
					(size 1.27 1.27)
				)
			)
		)
		(property "Value" "4K7R2J-2-GP"
			(at 0.064008 -3.993896 180)
			(unlocked yes)
			(layer "F.Fab")
			(hide yes)
			(effects
				(font
					(size 1.016 1.016)
					(thickness 0.1524)
				)
			)
		)
		(property "Device Type" "R402H16"
			(at 0.064008 -5.517896 180)
			(unlocked yes)
			(layer "F.Fab")
			(hide yes)
			(effects
				(font
					(size 1.016 1.016)
					(thickness 0.1524)
				)
			)
		)
		(duplicate_pad_numbers_are_jumpers no)
		(fp_line
			(start 0.508 -0.9398)
			(end -0.508 -0.9398)
			(stroke
				(width 0.1524)
				(type default)
			)
			(layer "F.SilkS")
		)
		(fp_line
			(start -0.508 -0.9398)
			(end -0.508 0.9398)
			(stroke
				(width 0.1524)
				(type default)
			)
			(layer "F.SilkS")
		)
		(fp_rect
			(start -0.508 0.9398)
			(end 0.508 -0.9398)
			(stroke
				(width 0)
				(type default)
			)
			(fill no)
			(layer "F.CrtYd")
		)
		(fp_rect
			(start -0.508 0.9398)
			(end 0.508 -0.9398)
			(stroke
				(width 0)
				(type default)
			)
			(fill no)
			(layer "F.Fab")
		)
		(pad "1" smd custom
			(at 0 -0.4445 180)
			(size 0.1397 0.1397)
			(layers "F.Cu" "F.Mask" "F.Paste")
			(net "P3V3")
			(options
				(clearance outline)
				(anchor circle)
			)
			(primitives
				(gr_poly
					(pts
						(arc
							(start -0.1778 -0.2794)
							(mid -0.249642 -0.249642)
							(end -0.2794 -0.1778)
						)
						(arc
							(start -0.2794 0.1778)
							(mid -0.249642 0.249642)
							(end -0.1778 0.2794)
						)
						(arc
							(start 0.1778 0.2794)
							(mid 0.249642 0.249642)
							(end 0.2794 0.1778)
						)
						(arc
							(start 0.2794 -0.1778)
							(mid 0.249642 -0.249642)
							(end 0.1778 -0.2794)
						)
					)
					(width 0)
					(fill yes)
				)
			)
		)
		(pad "2" smd custom
			(at 0 0.4445 180)
			(size 0.1397 0.1397)
			(layers "F.Cu" "F.Mask" "F.Paste")
			(net "SSD_ACT_DR3")
			(options
				(clearance outline)
				(anchor circle)
			)
			(primitives
				(gr_poly
					(pts
						(arc
							(start -0.1778 -0.2794)
							(mid -0.249642 -0.249642)
							(end -0.2794 -0.1778)
						)
						(arc
							(start -0.2794 0.1778)
							(mid -0.249642 0.249642)
							(end -0.1778 0.2794)
						)
						(arc
							(start 0.1778 0.2794)
							(mid 0.249642 0.249642)
							(end 0.2794 0.1778)
						)
						(arc
							(start 0.2794 -0.1778)
							(mid 0.249642 -0.249642)
							(end 0.1778 -0.2794)
						)
					)
					(width 0)
					(fill yes)
				)
			)
		)
	)
	(footprint ""
		(layer "F.Cu")
		(at 20.066 -64.38011 -90)
		(property "Reference" "R9873"
			(at 0 0 270)
			(layer "F.SilkS")
			(hide yes)
			(effects
				(font
					(size 1.27 1.27)
				)
			)
		)
		(property "Value" "0R2J-2-GP"
			(at 0.064008 -3.993896 270)
			(unlocked yes)
			(layer "F.Fab")
			(hide yes)
			(effects
				(font
					(size 1.016 1.016)
					(thickness 0.1524)
				)
			)
		)
		(property "Device Type" "R402H16"
			(at 0.064008 -5.517896 270)
			(unlocked yes)
			(layer "F.Fab")
			(hide yes)
			(effects
				(font
					(size 1.016 1.016)
					(thickness 0.1524)
				)
			)
		)
		(duplicate_pad_numbers_are_jumpers no)
		(fp_line
			(start -0.508 -0.9398)
			(end -0.508 0.9398)
			(stroke
				(width 0.1524)
				(type default)
			)
			(layer "F.SilkS")
		)
		(fp_line
			(start 0.508 -0.9398)
			(end -0.508 -0.9398)
			(stroke
				(width 0.1524)
				(type default)
			)
			(layer "F.SilkS")
		)
		(fp_rect
			(start -0.508 0.9398)
			(end 0.508 -0.9398)
			(stroke
				(width 0)
				(type default)
			)
			(fill no)
			(layer "F.CrtYd")
		)
		(fp_rect
			(start -0.508 0.9398)
			(end 0.508 -0.9398)
			(stroke
				(width 0)
				(type default)
			)
			(fill no)
			(layer "F.Fab")
		)
		(pad "1" smd custom
			(at 0 -0.4445 270)
			(size 0.1397 0.1397)
			(layers "F.Cu" "F.Mask" "F.Paste")
			(net "ATTN_LED_DR14_AND")
			(options
				(clearance outline)
				(anchor circle)
			)
			(primitives
				(gr_poly
					(pts
						(arc
							(start -0.1778 -0.2794)
							(mid -0.249642 -0.249642)
							(end -0.2794 -0.1778)
						)
						(arc
							(start -0.2794 0.1778)
							(mid -0.249642 0.249642)
							(end -0.1778 0.2794)
						)
						(arc
							(start 0.1778 0.2794)
							(mid 0.249642 0.249642)
							(end 0.2794 0.1778)
						)
						(arc
							(start 0.2794 -0.1778)
							(mid 0.249642 -0.249642)
							(end 0.1778 -0.2794)
						)
					)
					(width 0)
					(fill yes)
				)
			)
		)
		(pad "2" smd custom
			(at 0 0.4445 270)
			(size 0.1397 0.1397)
			(layers "F.Cu" "F.Mask" "F.Paste")
			(net "ATTN_LED_DR14_AND_R")
			(options
				(clearance outline)
				(anchor circle)
			)
			(primitives
				(gr_poly
					(pts
						(arc
							(start -0.1778 -0.2794)
							(mid -0.249642 -0.249642)
							(end -0.2794 -0.1778)
						)
						(arc
							(start -0.2794 0.1778)
							(mid -0.249642 0.249642)
							(end -0.1778 0.2794)
						)
						(arc
							(start 0.1778 0.2794)
							(mid 0.249642 0.249642)
							(end 0.2794 0.1778)
						)
						(arc
							(start 0.2794 -0.1778)
							(mid 0.249642 -0.249642)
							(end 0.1778 -0.2794)
						)
					)
					(width 0)
					(fill yes)
				)
			)
		)
	)
	(footprint ""
		(layer "F.Cu")
		(at 49.149 -144.526 -90)
		(property "Reference" "R9429"
			(at 0 0 270)
			(layer "F.SilkS")
			(hide yes)
			(effects
				(font
					(size 1.27 1.27)
				)
			)
		)
		(property "Value" "100R2J-2-GP"
			(at 0.064008 -3.993896 270)
			(unlocked yes)
			(layer "F.Fab")
			(hide yes)
			(effects
				(font
					(size 1.016 1.016)
					(thickness 0.1524)
				)
			)
		)
		(property "Device Type" "R402H14"
			(at 0.064008 -5.517896 270)
			(unlocked yes)
			(layer "F.Fab")
			(hide yes)
			(effects
				(font
					(size 1.016 1.016)
					(thickness 0.1524)
				)
			)
		)
		(duplicate_pad_numbers_are_jumpers no)
		(fp_line
			(start -0.508 -0.9398)
			(end -0.508 0.9398)
			(stroke
				(width 0.1524)
				(type default)
			)
			(layer "F.SilkS")
		)
		(fp_line
			(start 0.508 -0.9398)
			(end -0.508 -0.9398)
			(stroke
				(width 0.1524)
				(type default)
			)
			(layer "F.SilkS")
		)
		(fp_rect
			(start -0.508 0.9398)
			(end 0.508 -0.9398)
			(stroke
				(width 0)
				(type default)
			)
			(fill no)
			(layer "F.CrtYd")
		)
		(fp_rect
			(start -0.508 0.9398)
			(end 0.508 -0.9398)
			(stroke
				(width 0)
				(type default)
			)
			(fill no)
			(layer "F.Fab")
		)
		(pad "1" smd custom
			(at 0 -0.4445 270)
			(size 0.1397 0.1397)
			(layers "F.Cu" "F.Mask" "F.Paste")
			(net "P3V3")
			(options
				(clearance outline)
				(anchor circle)
			)
			(primitives
				(gr_poly
					(pts
						(arc
							(start -0.1778 -0.2794)
							(mid -0.249642 -0.249642)
							(end -0.2794 -0.1778)
						)
						(arc
							(start -0.2794 0.1778)
							(mid -0.249642 0.249642)
							(end -0.1778 0.2794)
						)
						(arc
							(start 0.1778 0.2794)
							(mid 0.249642 0.249642)
							(end 0.2794 0.1778)
						)
						(arc
							(start 0.2794 -0.1778)
							(mid 0.249642 -0.249642)
							(end 0.1778 -0.2794)
						)
					)
					(width 0)
					(fill yes)
				)
			)
		)
		(pad "2" smd custom
			(at 0 0.4445 270)
			(size 0.1397 0.1397)
			(layers "F.Cu" "F.Mask" "F.Paste")
			(net "DRV_ACT_8")
			(options
				(clearance outline)
				(anchor circle)
			)
			(primitives
				(gr_poly
					(pts
						(arc
							(start -0.1778 -0.2794)
							(mid -0.249642 -0.249642)
							(end -0.2794 -0.1778)
						)
						(arc
							(start -0.2794 0.1778)
							(mid -0.249642 0.249642)
							(end -0.1778 0.2794)
						)
						(arc
							(start 0.1778 0.2794)
							(mid 0.249642 0.249642)
							(end 0.2794 0.1778)
						)
						(arc
							(start 0.2794 -0.1778)
							(mid 0.249642 -0.249642)
							(end 0.1778 -0.2794)
						)
					)
					(width 0)
					(fill yes)
				)
			)
		)
	)
	(footprint ""
		(layer "F.Cu")
		(at 210.439 -44.704)
		(property "Reference" "R337"
			(at 0 0 0)
			(layer "F.SilkS")
			(hide yes)
			(effects
				(font
					(size 1.27 1.27)
				)
			)
		)
		(property "Value" "4K7R2F-GP"
			(at 0.064008 -3.993896 0)
			(unlocked yes)
			(layer "F.Fab")
			(hide yes)
			(effects
				(font
					(size 1.016 1.016)
					(thickness 0.1524)
				)
			)
		)
		(property "Device Type" "R402H16"
			(at 0.064008 -5.517896 0)
			(unlocked yes)
			(layer "F.Fab")
			(hide yes)
			(effects
				(font
					(size 1.016 1.016)
					(thickness 0.1524)
				)
			)
		)
		(duplicate_pad_numbers_are_jumpers no)
		(fp_line
			(start -0.508 -0.9398)
			(end -0.508 0.9398)
			(stroke
				(width 0.1524)
				(type default)
			)
			(layer "F.SilkS")
		)
		(fp_line
			(start 0.508 -0.9398)
			(end -0.508 -0.9398)
			(stroke
				(width 0.1524)
				(type default)
			)
			(layer "F.SilkS")
		)
		(fp_rect
			(start -0.508 0.9398)
			(end 0.508 -0.9398)
			(stroke
				(width 0)
				(type default)
			)
			(fill no)
			(layer "F.CrtYd")
		)
		(fp_rect
			(start -0.508 0.9398)
			(end 0.508 -0.9398)
			(stroke
				(width 0)
				(type default)
			)
			(fill no)
			(layer "F.Fab")
		)
		(pad "1" smd custom
			(at 0 -0.4445)
			(size 0.1397 0.1397)
			(layers "F.Cu" "F.Mask" "F.Paste")
			(net "I2C_B_TMP3_A1")
			(options
				(clearance outline)
				(anchor circle)
			)
			(primitives
				(gr_poly
					(pts
						(arc
							(start -0.1778 -0.2794)
							(mid -0.249642 -0.249642)
							(end -0.2794 -0.1778)
						)
						(arc
							(start -0.2794 0.1778)
							(mid -0.249642 0.249642)
							(end -0.1778 0.2794)
						)
						(arc
							(start 0.1778 0.2794)
							(mid 0.249642 0.249642)
							(end 0.2794 0.1778)
						)
						(arc
							(start 0.2794 -0.1778)
							(mid 0.249642 -0.249642)
							(end 0.1778 -0.2794)
						)
					)
					(width 0)
					(fill yes)
				)
			)
		)
		(pad "2" smd custom
			(at 0 0.4445)
			(size 0.1397 0.1397)
			(layers "F.Cu" "F.Mask" "F.Paste")
			(net "GND")
			(options
				(clearance outline)
				(anchor circle)
			)
			(primitives
				(gr_poly
					(pts
						(arc
							(start -0.1778 -0.2794)
							(mid -0.249642 -0.249642)
							(end -0.2794 -0.1778)
						)
						(arc
							(start -0.2794 0.1778)
							(mid -0.249642 0.249642)
							(end -0.1778 0.2794)
						)
						(arc
							(start 0.1778 0.2794)
							(mid 0.249642 0.249642)
							(end 0.2794 0.1778)
						)
						(arc
							(start 0.2794 -0.1778)
							(mid 0.249642 -0.249642)
							(end 0.1778 -0.2794)
						)
					)
					(width 0)
					(fill yes)
				)
			)
		)
	)
	(footprint ""
		(layer "F.Cu")
		(at 50.038 -10.795)
		(property "Reference" "Q22"
			(at 0 0 0)
			(layer "F.SilkS")
			(hide yes)
			(effects
				(font
					(size 1.27 1.27)
				)
			)
		)
		(property "Value" "2N7002A-7-GP"
			(at 0.127 -8.9662 0)
			(unlocked yes)
			(layer "F.Fab")
			(hide yes)
			(effects
				(font
					(size 1.016 1.016)
					(thickness 0.1524)
				)
			)
		)
		(property "Device Type" "SOT23DGS2D4H48"
			(at 0.127 -10.4902 0)
			(unlocked yes)
			(layer "F.Fab")
			(hide yes)
			(effects
				(font
					(size 1.016 1.016)
					(thickness 0.1524)
				)
			)
		)
		(duplicate_pad_numbers_are_jumpers no)
		(fp_line
			(start -1.651 -1.778)
			(end -1.651 1.778)
			(stroke
				(width 0.1524)
				(type default)
			)
			(layer "F.SilkS")
		)
		(fp_line
			(start -1.651 1.778)
			(end 1.651 1.778)
			(stroke
				(width 0.1524)
				(type default)
			)
			(layer "F.SilkS")
		)
		(fp_line
			(start 1.651 -1.778)
			(end -1.651 -1.778)
			(stroke
				(width 0.1524)
				(type default)
			)
			(layer "F.SilkS")
		)
		(fp_line
			(start 1.651 1.778)
			(end 1.651 -1.778)
			(stroke
				(width 0.1524)
				(type default)
			)
			(layer "F.SilkS")
		)
		(fp_poly
			(pts
				(xy -1.778 1.8796) (xy -1.778 -1.8796) (xy 1.778 -1.8796) (xy 1.778 1.8796)
			)
			(stroke
				(width 0)
				(type default)
			)
			(fill no)
			(layer "F.CrtYd")
		)
		(fp_poly
			(pts
				(xy -1.778 1.8796) (xy -1.778 -1.8796) (xy 1.778 -1.8796) (xy 1.778 1.8796)
			)
			(stroke
				(width 0)
				(type default)
			)
			(fill no)
			(layer "F.Fab")
		)
		(pad "D" smd custom
			(at 0 -0.9525)
			(size 0.1905 0.1905)
			(layers "F.Cu" "F.Mask" "F.Paste")
			(net "SW_SSD14_R")
			(options
				(clearance outline)
				(anchor circle)
			)
			(primitives
				(gr_poly
					(pts
						(arc
							(start -0.1778 0.5715)
							(mid -0.321484 0.511984)
							(end -0.381 0.3683)
						)
						(arc
							(start -0.381 -0.3683)
							(mid -0.321484 -0.511984)
							(end -0.1778 -0.5715)
						)
						(arc
							(start 0.1778 -0.5715)
							(mid 0.321484 -0.511984)
							(end 0.381 -0.3683)
						)
						(arc
							(start 0.381 0.3683)
							(mid 0.321484 0.511984)
							(end 0.1778 0.5715)
						)
					)
					(width 0)
					(fill yes)
				)
			)
		)
		(pad "G" smd custom
			(at -0.98425 0.9525)
			(size 0.1905 0.1905)
			(layers "F.Cu" "F.Mask" "F.Paste")
			(net "SSD14_PWREN")
			(options
				(clearance outline)
				(anchor circle)
			)
			(primitives
				(gr_poly
					(pts
						(arc
							(start -0.1778 0.5715)
							(mid -0.321484 0.511984)
							(end -0.381 0.3683)
						)
						(arc
							(start -0.381 -0.3683)
							(mid -0.321484 -0.511984)
							(end -0.1778 -0.5715)
						)
						(arc
							(start 0.1778 -0.5715)
							(mid 0.321484 -0.511984)
							(end 0.381 -0.3683)
						)
						(arc
							(start 0.381 0.3683)
							(mid 0.321484 0.511984)
							(end 0.1778 0.5715)
						)
					)
					(width 0)
					(fill yes)
				)
			)
		)
		(pad "S" smd custom
			(at 0.98425 0.9525)
			(size 0.1905 0.1905)
			(layers "F.Cu" "F.Mask" "F.Paste")
			(net "GND")
			(options
				(clearance outline)
				(anchor circle)
			)
			(primitives
				(gr_poly
					(pts
						(arc
							(start -0.1778 0.5715)
							(mid -0.321484 0.511984)
							(end -0.381 0.3683)
						)
						(arc
							(start -0.381 -0.3683)
							(mid -0.321484 -0.511984)
							(end -0.1778 -0.5715)
						)
						(arc
							(start 0.1778 -0.5715)
							(mid 0.321484 -0.511984)
							(end 0.381 -0.3683)
						)
						(arc
							(start 0.381 0.3683)
							(mid 0.321484 0.511984)
							(end 0.1778 0.5715)
						)
					)
					(width 0)
					(fill yes)
				)
			)
		)
	)
	(footprint ""
		(layer "F.Cu")
		(at 24.257 -464.82 -90)
		(property "Reference" "R117"
			(at 0 0 270)
			(layer "F.SilkS")
			(hide yes)
			(effects
				(font
					(size 1.27 1.27)
				)
			)
		)
		(property "Value" "330R2F-GP"
			(at 0.064008 -3.993896 270)
			(unlocked yes)
			(layer "F.Fab")
			(hide yes)
			(effects
				(font
					(size 1.016 1.016)
					(thickness 0.1524)
				)
			)
		)
		(property "Device Type" "R402H16"
			(at 0.064008 -5.517896 270)
			(unlocked yes)
			(layer "F.Fab")
			(hide yes)
			(effects
				(font
					(size 1.016 1.016)
					(thickness 0.1524)
				)
			)
		)
		(duplicate_pad_numbers_are_jumpers no)
		(fp_line
			(start -0.508 -0.9398)
			(end -0.508 0.9398)
			(stroke
				(width 0.1524)
				(type default)
			)
			(layer "F.SilkS")
		)
		(fp_line
			(start 0.508 -0.9398)
			(end -0.508 -0.9398)
			(stroke
				(width 0.1524)
				(type default)
			)
			(layer "F.SilkS")
		)
		(fp_rect
			(start -0.508 0.9398)
			(end 0.508 -0.9398)
			(stroke
				(width 0)
				(type default)
			)
			(fill no)
			(layer "F.CrtYd")
		)
		(fp_rect
			(start -0.508 0.9398)
			(end 0.508 -0.9398)
			(stroke
				(width 0)
				(type default)
			)
			(fill no)
			(layer "F.Fab")
		)
		(pad "1" smd custom
			(at 0 -0.4445 270)
			(size 0.1397 0.1397)
			(layers "F.Cu" "F.Mask" "F.Paste")
			(net "P3V3")
			(options
				(clearance outline)
				(anchor circle)
			)
			(primitives
				(gr_poly
					(pts
						(arc
							(start -0.1778 -0.2794)
							(mid -0.249642 -0.249642)
							(end -0.2794 -0.1778)
						)
						(arc
							(start -0.2794 0.1778)
							(mid -0.249642 0.249642)
							(end -0.1778 0.2794)
						)
						(arc
							(start 0.1778 0.2794)
							(mid 0.249642 0.249642)
							(end 0.2794 0.1778)
						)
						(arc
							(start 0.2794 -0.1778)
							(mid 0.249642 -0.249642)
							(end 0.1778 -0.2794)
						)
					)
					(width 0)
					(fill yes)
				)
			)
		)
		(pad "2" smd custom
			(at 0 0.4445 270)
			(size 0.1397 0.1397)
			(layers "F.Cu" "F.Mask" "F.Paste")
			(net "DRV_ATTN_10")
			(options
				(clearance outline)
				(anchor circle)
			)
			(primitives
				(gr_poly
					(pts
						(arc
							(start -0.1778 -0.2794)
							(mid -0.249642 -0.249642)
							(end -0.2794 -0.1778)
						)
						(arc
							(start -0.2794 0.1778)
							(mid -0.249642 0.249642)
							(end -0.1778 0.2794)
						)
						(arc
							(start 0.1778 0.2794)
							(mid 0.249642 0.249642)
							(end 0.2794 0.1778)
						)
						(arc
							(start 0.2794 -0.1778)
							(mid 0.249642 -0.249642)
							(end 0.1778 -0.2794)
						)
					)
					(width 0)
					(fill yes)
				)
			)
		)
	)
	(footprint ""
		(layer "F.Cu")
		(at 88.138 -115.062)
		(property "Reference" "R9615"
			(at 0 0 0)
			(layer "F.SilkS")
			(hide yes)
			(effects
				(font
					(size 1.27 1.27)
				)
			)
		)
		(property "Value" "10R2F-L-GP"
			(at 0.064008 -3.993896 0)
			(unlocked yes)
			(layer "F.Fab")
			(hide yes)
			(effects
				(font
					(size 1.016 1.016)
					(thickness 0.1524)
				)
			)
		)
		(property "Device Type" "R402H14"
			(at 0.064008 -5.517896 0)
			(unlocked yes)
			(layer "F.Fab")
			(hide yes)
			(effects
				(font
					(size 1.016 1.016)
					(thickness 0.1524)
				)
			)
		)
		(duplicate_pad_numbers_are_jumpers no)
		(fp_line
			(start -0.508 -0.9398)
			(end -0.508 0.9398)
			(stroke
				(width 0.1524)
				(type default)
			)
			(layer "F.SilkS")
		)
		(fp_line
			(start 0.508 -0.9398)
			(end -0.508 -0.9398)
			(stroke
				(width 0.1524)
				(type default)
			)
			(layer "F.SilkS")
		)
		(fp_rect
			(start -0.508 0.9398)
			(end 0.508 -0.9398)
			(stroke
				(width 0)
				(type default)
			)
			(fill no)
			(layer "F.CrtYd")
		)
		(fp_rect
			(start -0.508 0.9398)
			(end 0.508 -0.9398)
			(stroke
				(width 0)
				(type default)
			)
			(fill no)
			(layer "F.Fab")
		)
		(pad "1" smd custom
			(at 0 -0.4445)
			(size 0.1397 0.1397)
			(layers "F.Cu" "F.Mask" "F.Paste")
			(net "SSD13_CLK0_OE_N")
			(options
				(clearance outline)
				(anchor circle)
			)
			(primitives
				(gr_poly
					(pts
						(arc
							(start -0.1778 -0.2794)
							(mid -0.249642 -0.249642)
							(end -0.2794 -0.1778)
						)
						(arc
							(start -0.2794 0.1778)
							(mid -0.249642 0.249642)
							(end -0.1778 0.2794)
						)
						(arc
							(start 0.1778 0.2794)
							(mid 0.249642 0.249642)
							(end 0.2794 0.1778)
						)
						(arc
							(start 0.2794 -0.1778)
							(mid 0.249642 -0.249642)
							(end 0.1778 -0.2794)
						)
					)
					(width 0)
					(fill yes)
				)
			)
		)
		(pad "2" smd custom
			(at 0 0.4445)
			(size 0.1397 0.1397)
			(layers "F.Cu" "F.Mask" "F.Paste")
			(net "SSD13_CLK0_OE_R_N")
			(options
				(clearance outline)
				(anchor circle)
			)
			(primitives
				(gr_poly
					(pts
						(arc
							(start -0.1778 -0.2794)
							(mid -0.249642 -0.249642)
							(end -0.2794 -0.1778)
						)
						(arc
							(start -0.2794 0.1778)
							(mid -0.249642 0.249642)
							(end -0.1778 0.2794)
						)
						(arc
							(start 0.1778 0.2794)
							(mid 0.249642 0.249642)
							(end 0.2794 0.1778)
						)
						(arc
							(start 0.2794 -0.1778)
							(mid 0.249642 -0.249642)
							(end 0.1778 -0.2794)
						)
					)
					(width 0)
					(fill yes)
				)
			)
		)
	)
	(footprint ""
		(layer "F.Cu")
		(at 102.616 -437.134 90)
		(property "Reference" "R9055"
			(at 0 0 90)
			(layer "F.SilkS")
			(hide yes)
			(effects
				(font
					(size 1.27 1.27)
				)
			)
		)
		(property "Value" "27R2F-GP"
			(at 0.064008 -3.993896 90)
			(unlocked yes)
			(layer "F.Fab")
			(hide yes)
			(effects
				(font
					(size 1.016 1.016)
					(thickness 0.1524)
				)
			)
		)
		(property "Device Type" "R402H16"
			(at 0.064008 -5.517896 90)
			(unlocked yes)
			(layer "F.Fab")
			(hide yes)
			(effects
				(font
					(size 1.016 1.016)
					(thickness 0.1524)
				)
			)
		)
		(duplicate_pad_numbers_are_jumpers no)
		(fp_line
			(start 0.508 -0.9398)
			(end -0.508 -0.9398)
			(stroke
				(width 0.1524)
				(type default)
			)
			(layer "F.SilkS")
		)
		(fp_line
			(start -0.508 -0.9398)
			(end -0.508 0.9398)
			(stroke
				(width 0.1524)
				(type default)
			)
			(layer "F.SilkS")
		)
		(fp_rect
			(start -0.508 0.9398)
			(end 0.508 -0.9398)
			(stroke
				(width 0)
				(type default)
			)
			(fill no)
			(layer "F.CrtYd")
		)
		(fp_rect
			(start -0.508 0.9398)
			(end 0.508 -0.9398)
			(stroke
				(width 0)
				(type default)
			)
			(fill no)
			(layer "F.Fab")
		)
		(pad "1" smd custom
			(at 0 -0.4445 90)
			(size 0.1397 0.1397)
			(layers "F.Cu" "F.Mask" "F.Paste")
			(net "PE_CLK_100M_DR0_1_R_P")
			(options
				(clearance outline)
				(anchor circle)
			)
			(primitives
				(gr_poly
					(pts
						(arc
							(start -0.1778 -0.2794)
							(mid -0.249642 -0.249642)
							(end -0.2794 -0.1778)
						)
						(arc
							(start -0.2794 0.1778)
							(mid -0.249642 0.249642)
							(end -0.1778 0.2794)
						)
						(arc
							(start 0.1778 0.2794)
							(mid 0.249642 0.249642)
							(end 0.2794 0.1778)
						)
						(arc
							(start 0.2794 -0.1778)
							(mid 0.249642 -0.249642)
							(end 0.1778 -0.2794)
						)
					)
					(width 0)
					(fill yes)
				)
			)
		)
		(pad "2" smd custom
			(at 0 0.4445 90)
			(size 0.1397 0.1397)
			(layers "F.Cu" "F.Mask" "F.Paste")
			(net "PE_CLK100M_DR0_1_P")
			(options
				(clearance outline)
				(anchor circle)
			)
			(primitives
				(gr_poly
					(pts
						(arc
							(start -0.1778 -0.2794)
							(mid -0.249642 -0.249642)
							(end -0.2794 -0.1778)
						)
						(arc
							(start -0.2794 0.1778)
							(mid -0.249642 0.249642)
							(end -0.1778 0.2794)
						)
						(arc
							(start 0.1778 0.2794)
							(mid 0.249642 0.249642)
							(end 0.2794 0.1778)
						)
						(arc
							(start 0.2794 -0.1778)
							(mid 0.249642 -0.249642)
							(end 0.1778 -0.2794)
						)
					)
					(width 0)
					(fill yes)
				)
			)
		)
	)
	(footprint ""
		(layer "F.Cu")
		(at 226.949 -434.34 -90)
		(property "Reference" "PU2"
			(at 0 0 270)
			(layer "F.SilkS")
			(hide yes)
			(effects
				(font
					(size 1.27 1.27)
				)
			)
		)
		(property "Value" "TPS53312RGTR-GP"
			(at 4.9784 -6.9342 270)
			(unlocked yes)
			(layer "F.Fab")
			(hide yes)
			(effects
				(font
					(size 1.016 1.016)
					(thickness 0.1524)
				)
			)
		)
		(property "Device Type" "QFN16G3-G1D7H40"
			(at 4.9784 -8.4582 270)
			(unlocked yes)
			(layer "F.Fab")
			(hide yes)
			(effects
				(font
					(size 1.016 1.016)
					(thickness 0.1524)
				)
			)
		)
		(duplicate_pad_numbers_are_jumpers no)
		(fp_line
			(start -2.5146 2.5146)
			(end -1.2446 2.5146)
			(stroke
				(width 0.1524)
				(type default)
			)
			(layer "F.SilkS")
		)
		(fp_line
			(start 1.2446 2.5146)
			(end 2.5146 2.5146)
			(stroke
				(width 0.1524)
				(type default)
			)
			(layer "F.SilkS")
		)
		(fp_line
			(start 2.5146 2.5146)
			(end 2.5146 1.2446)
			(stroke
				(width 0.1524)
				(type default)
			)
			(layer "F.SilkS")
		)
		(fp_line
			(start -0.249936 2.262124)
			(end -0.249936 3.024124)
			(stroke
				(width 0.1524)
				(type default)
			)
			(layer "F.SilkS")
		)
		(fp_line
			(start -2.5146 1.2446)
			(end -2.5146 2.5146)
			(stroke
				(width 0.1524)
				(type default)
			)
			(layer "F.SilkS")
		)
		(fp_line
			(start 2.262124 -0.249936)
			(end 2.770124 -0.249936)
			(stroke
				(width 0.1524)
				(type default)
			)
			(layer "F.SilkS")
		)
		(fp_line
			(start -2.262124 -0.750062)
			(end -2.770124 -0.750062)
			(stroke
				(width 0.1524)
				(type default)
			)
			(layer "F.SilkS")
		)
		(fp_line
			(start -2.5146 -2.5146)
			(end -2.5146 -1.2446)
			(stroke
				(width 0.1524)
				(type default)
			)
			(layer "F.SilkS")
		)
		(fp_line
			(start -1.2446 -2.5146)
			(end -2.5146 -2.5146)
			(stroke
				(width 0.1524)
				(type default)
			)
			(layer "F.SilkS")
		)
		(fp_poly
			(pts
				(xy 2.5146 -2.5146) (xy 1.2446 -2.5146) (xy 2.5146 -1.2446)
			)
			(stroke
				(width 0)
				(type default)
			)
			(fill yes)
			(layer "F.SilkS")
		)
		(fp_rect
			(start -1.4986 1.4986)
			(end 1.4986 -1.4986)
			(stroke
				(width 0)
				(type default)
			)
			(fill no)
			(layer "F.CrtYd")
		)
		(fp_poly
			(pts
				(xy 2.5146 -1.4986) (xy -1.4986 -1.4986) (xy -1.4986 1.4986) (xy 1.4986 1.4986) (xy 1.4986 -1.4859)
				(xy 2.5146 -1.4859) (xy 2.5146 2.5146) (xy -2.5146 2.5146) (xy -2.5146 -2.5146) (xy 2.5146 -2.5146)
			)
			(stroke
				(width 0)
				(type default)
			)
			(fill no)
			(layer "F.CrtYd")
		)
		(fp_rect
			(start -2.5146 2.5146)
			(end 2.5146 -2.5146)
			(stroke
				(width 0)
				(type default)
			)
			(fill no)
			(layer "F.Fab")
		)
		(pad "1" smd rect
			(at 0.750062 -1.550924 270)
			(size 0.3048 0.9144)
			(layers "F.Cu" "F.Mask" "F.Paste")
			(net "P3V3_VFB")
		)
		(pad "2" smd rect
			(at 0.249936 -1.538224 270)
			(size 0.3048 0.9398)
			(layers "F.Cu" "F.Mask" "F.Paste")
			(net "P3V3_VRG5")
		)
		(pad "3" smd rect
			(at -0.249936 -1.538224 270)
			(size 0.3048 0.9398)
			(layers "F.Cu" "F.Mask" "F.Paste")
			(net "P3V3_SS")
		)
		(pad "4" smd rect
			(at -0.750062 -1.550924 270)
			(size 0.3048 0.9144)
			(layers "F.Cu" "F.Mask" "F.Paste")
			(net "AGND_P3V3")
		)
		(pad "5" smd rect
			(at -1.550924 -0.750062 270)
			(size 0.9144 0.3048)
			(layers "F.Cu" "F.Mask" "F.Paste")
			(net "TPS53312_P3V3_PG")
		)
		(pad "6" smd rect
			(at -1.538224 -0.249936 270)
			(size 0.9398 0.3048)
			(layers "F.Cu" "F.Mask" "F.Paste")
			(net "P3V3_EN_R")
		)
		(pad "7" smd rect
			(at -1.538224 0.249936 270)
			(size 0.9398 0.3048)
			(layers "F.Cu" "F.Mask" "F.Paste")
			(net "GND")
		)
		(pad "8" smd rect
			(at -1.550924 0.750062 270)
			(size 0.9144 0.3048)
			(layers "F.Cu" "F.Mask" "F.Paste")
			(net "GND")
		)
		(pad "9" smd rect
			(at -0.750062 1.550924 270)
			(size 0.3048 0.9144)
			(layers "F.Cu" "F.Mask" "F.Paste")
			(net "P3V3_SW")
		)
		(pad "10" smd rect
			(at -0.249936 1.538224 270)
			(size 0.3048 0.9398)
			(layers "F.Cu" "F.Mask" "F.Paste")
			(net "P3V3_SW")
		)
		(pad "11" smd rect
			(at 0.249936 1.538224 270)
			(size 0.3048 0.9398)
			(layers "F.Cu" "F.Mask" "F.Paste")
			(net "P3V3_SW")
		)
		(pad "12" smd rect
			(at 0.750062 1.550924 270)
			(size 0.3048 0.9144)
			(layers "F.Cu" "F.Mask" "F.Paste")
			(net "P3V3_VBST")
		)
		(pad "13" smd rect
			(at 1.550924 0.750062 270)
			(size 0.9144 0.3048)
			(layers "F.Cu" "F.Mask" "F.Paste")
			(net "P3V3_VIN")
		)
		(pad "14" smd rect
			(at 1.538224 0.249936 270)
			(size 0.9398 0.3048)
			(layers "F.Cu" "F.Mask" "F.Paste")
			(net "P3V3_VIN")
		)
		(pad "15" smd rect
			(at 1.538224 -0.249936 270)
			(size 0.9398 0.3048)
			(layers "F.Cu" "F.Mask" "F.Paste")
			(net "P3V3_VCC")
		)
		(pad "16" smd rect
			(at 1.550924 -0.750062 270)
			(size 0.9144 0.3048)
			(layers "F.Cu" "F.Mask" "F.Paste")
			(net "P3V3_VO")
		)
		(pad "17" smd rect
			(at 0 0 270)
			(size 1.6764 1.6764)
			(layers "F.Cu" "F.Mask" "F.Paste")
			(net "GND")
		)
	)
	(footprint ""
		(layer "F.Cu")
		(at 86.614 -102.743 180)
		(property "Reference" "C8933"
			(at 0 0 180)
			(layer "F.SilkS")
			(hide yes)
			(effects
				(font
					(size 1.27 1.27)
				)
			)
		)
		(property "Value" "SC1U10V2KX-7-GP"
			(at 1.1811 -2.7051 180)
			(unlocked yes)
			(layer "F.Fab")
			(hide yes)
			(effects
				(font
					(size 1.016 1.016)
					(thickness 0.1524)
				)
			)
		)
		(property "Device Type" "C402H22"
			(at 1.1811 -4.2291 180)
			(unlocked yes)
			(layer "F.Fab")
			(hide yes)
			(effects
				(font
					(size 1.016 1.016)
					(thickness 0.1524)
				)
			)
		)
		(duplicate_pad_numbers_are_jumpers no)
		(fp_rect
			(start -0.4318 0.9525)
			(end 0.4318 -0.9525)
			(stroke
				(width 0)
				(type default)
			)
			(fill no)
			(layer "F.CrtYd")
		)
		(fp_rect
			(start -0.4318 0.9525)
			(end 0.4318 -0.9525)
			(stroke
				(width 0)
				(type default)
			)
			(fill no)
			(layer "F.Fab")
		)
		(pad "1" smd custom
			(at 0 -0.4445 180)
			(size 0.1524 0.1524)
			(layers "F.Cu" "F.Mask" "F.Paste")
			(net "VDDR_4")
			(options
				(clearance outline)
				(anchor circle)
			)
			(primitives
				(gr_poly
					(pts
						(arc
							(start 0.3048 -0.2032)
							(mid 0.275042 -0.275042)
							(end 0.2032 -0.3048)
						)
						(arc
							(start -0.2032 -0.3048)
							(mid -0.275042 -0.275042)
							(end -0.3048 -0.2032)
						)
						(arc
							(start -0.3048 0.2032)
							(mid -0.275042 0.275042)
							(end -0.2032 0.3048)
						)
						(arc
							(start 0.2032 0.3048)
							(mid 0.275042 0.275042)
							(end 0.3048 0.2032)
						)
					)
					(width 0)
					(fill yes)
				)
			)
		)
		(pad "2" smd custom
			(at 0 0.4445 180)
			(size 0.1524 0.1524)
			(layers "F.Cu" "F.Mask" "F.Paste")
			(net "GND")
			(options
				(clearance outline)
				(anchor circle)
			)
			(primitives
				(gr_poly
					(pts
						(arc
							(start 0.3048 -0.2032)
							(mid 0.275042 -0.275042)
							(end 0.2032 -0.3048)
						)
						(arc
							(start -0.2032 -0.3048)
							(mid -0.275042 -0.275042)
							(end -0.3048 -0.2032)
						)
						(arc
							(start -0.3048 0.2032)
							(mid -0.275042 0.275042)
							(end -0.2032 0.3048)
						)
						(arc
							(start 0.2032 0.3048)
							(mid 0.275042 0.275042)
							(end 0.3048 0.2032)
						)
					)
					(width 0)
					(fill yes)
				)
			)
		)
	)
	(footprint ""
		(layer "F.Cu")
		(at 48.807116 -344.801952 180)
		(property "Reference" "Q58"
			(at 0 0 180)
			(layer "F.SilkS")
			(hide yes)
			(effects
				(font
					(size 1.27 1.27)
				)
			)
		)
		(property "Value" "2N7002A-7-GP"
			(at 0.127 -8.9662 180)
			(unlocked yes)
			(layer "F.Fab")
			(hide yes)
			(effects
				(font
					(size 1.016 1.016)
					(thickness 0.1524)
				)
			)
		)
		(property "Device Type" "SOT23DGS2D4H48"
			(at 0.127 -10.4902 180)
			(unlocked yes)
			(layer "F.Fab")
			(hide yes)
			(effects
				(font
					(size 1.016 1.016)
					(thickness 0.1524)
				)
			)
		)
		(duplicate_pad_numbers_are_jumpers no)
		(fp_line
			(start 1.651 1.778)
			(end 1.651 -1.778)
			(stroke
				(width 0.1524)
				(type default)
			)
			(layer "F.SilkS")
		)
		(fp_line
			(start 1.651 -1.778)
			(end -1.651 -1.778)
			(stroke
				(width 0.1524)
				(type default)
			)
			(layer "F.SilkS")
		)
		(fp_line
			(start -1.651 1.778)
			(end 1.651 1.778)
			(stroke
				(width 0.1524)
				(type default)
			)
			(layer "F.SilkS")
		)
		(fp_line
			(start -1.651 -1.778)
			(end -1.651 1.778)
			(stroke
				(width 0.1524)
				(type default)
			)
			(layer "F.SilkS")
		)
		(fp_poly
			(pts
				(xy -1.778 1.8796) (xy -1.778 -1.8796) (xy 1.778 -1.8796) (xy 1.778 1.8796)
			)
			(stroke
				(width 0)
				(type default)
			)
			(fill no)
			(layer "F.CrtYd")
		)
		(fp_poly
			(pts
				(xy -1.778 1.8796) (xy -1.778 -1.8796) (xy 1.778 -1.8796) (xy 1.778 1.8796)
			)
			(stroke
				(width 0)
				(type default)
			)
			(fill no)
			(layer "F.Fab")
		)
		(pad "D" smd custom
			(at 0 -0.9525 180)
			(size 0.1905 0.1905)
			(layers "F.Cu" "F.Mask" "F.Paste")
			(net "SSD_ACT_DR6_MOS_N")
			(options
				(clearance outline)
				(anchor circle)
			)
			(primitives
				(gr_poly
					(pts
						(arc
							(start -0.1778 0.5715)
							(mid -0.321484 0.511984)
							(end -0.381 0.3683)
						)
						(arc
							(start -0.381 -0.3683)
							(mid -0.321484 -0.511984)
							(end -0.1778 -0.5715)
						)
						(arc
							(start 0.1778 -0.5715)
							(mid 0.321484 -0.511984)
							(end 0.381 -0.3683)
						)
						(arc
							(start 0.381 0.3683)
							(mid 0.321484 0.511984)
							(end 0.1778 0.5715)
						)
					)
					(width 0)
					(fill yes)
				)
			)
		)
		(pad "G" smd custom
			(at -0.98425 0.9525 180)
			(size 0.1905 0.1905)
			(layers "F.Cu" "F.Mask" "F.Paste")
			(net "ATTN_LED_DR6_AND_R")
			(options
				(clearance outline)
				(anchor circle)
			)
			(primitives
				(gr_poly
					(pts
						(arc
							(start -0.1778 0.5715)
							(mid -0.321484 0.511984)
							(end -0.381 0.3683)
						)
						(arc
							(start -0.381 -0.3683)
							(mid -0.321484 -0.511984)
							(end -0.1778 -0.5715)
						)
						(arc
							(start 0.1778 -0.5715)
							(mid 0.321484 -0.511984)
							(end 0.381 -0.3683)
						)
						(arc
							(start 0.381 0.3683)
							(mid 0.321484 0.511984)
							(end 0.1778 0.5715)
						)
					)
					(width 0)
					(fill yes)
				)
			)
		)
		(pad "S" smd custom
			(at 0.98425 0.9525 180)
			(size 0.1905 0.1905)
			(layers "F.Cu" "F.Mask" "F.Paste")
			(net "SSD_ACT_DR6_R")
			(options
				(clearance outline)
				(anchor circle)
			)
			(primitives
				(gr_poly
					(pts
						(arc
							(start -0.1778 0.5715)
							(mid -0.321484 0.511984)
							(end -0.381 0.3683)
						)
						(arc
							(start -0.381 -0.3683)
							(mid -0.321484 -0.511984)
							(end -0.1778 -0.5715)
						)
						(arc
							(start 0.1778 -0.5715)
							(mid 0.321484 -0.511984)
							(end 0.381 -0.3683)
						)
						(arc
							(start 0.381 0.3683)
							(mid 0.321484 0.511984)
							(end 0.1778 0.5715)
						)
					)
					(width 0)
					(fill yes)
				)
			)
		)
	)
	(footprint ""
		(layer "F.Cu")
		(at 29.95803 -187.684918)
		(property "Reference" "SR1107"
			(at 0 0 0)
			(layer "F.SilkS")
			(hide yes)
			(effects
				(font
					(size 1.27 1.27)
				)
			)
		)
		(property "Value" "4K7R2F-GP"
			(at 0.064008 -3.993896 0)
			(unlocked yes)
			(layer "F.Fab")
			(hide yes)
			(effects
				(font
					(size 1.016 1.016)
					(thickness 0.1524)
				)
			)
		)
		(property "Device Type" "R402H16"
			(at 0.064008 -5.517896 0)
			(unlocked yes)
			(layer "F.Fab")
			(hide yes)
			(effects
				(font
					(size 1.016 1.016)
					(thickness 0.1524)
				)
			)
		)
		(duplicate_pad_numbers_are_jumpers no)
		(fp_line
			(start -0.508 -0.9398)
			(end -0.508 0.9398)
			(stroke
				(width 0.1524)
				(type default)
			)
			(layer "F.SilkS")
		)
		(fp_line
			(start 0.508 -0.9398)
			(end -0.508 -0.9398)
			(stroke
				(width 0.1524)
				(type default)
			)
			(layer "F.SilkS")
		)
		(fp_rect
			(start -0.508 0.9398)
			(end 0.508 -0.9398)
			(stroke
				(width 0)
				(type default)
			)
			(fill no)
			(layer "F.CrtYd")
		)
		(fp_rect
			(start -0.508 0.9398)
			(end 0.508 -0.9398)
			(stroke
				(width 0)
				(type default)
			)
			(fill no)
			(layer "F.Fab")
		)
		(pad "1" smd custom
			(at 0 -0.4445)
			(size 0.1397 0.1397)
			(layers "F.Cu" "F.Mask" "F.Paste")
			(net "P3V3")
			(options
				(clearance outline)
				(anchor circle)
			)
			(primitives
				(gr_poly
					(pts
						(arc
							(start -0.1778 -0.2794)
							(mid -0.249642 -0.249642)
							(end -0.2794 -0.1778)
						)
						(arc
							(start -0.2794 0.1778)
							(mid -0.249642 0.249642)
							(end -0.1778 0.2794)
						)
						(arc
							(start 0.1778 0.2794)
							(mid 0.249642 0.249642)
							(end 0.2794 0.1778)
						)
						(arc
							(start 0.2794 -0.1778)
							(mid 0.249642 -0.249642)
							(end 0.1778 -0.2794)
						)
					)
					(width 0)
					(fill yes)
				)
			)
		)
		(pad "2" smd custom
			(at 0 0.4445)
			(size 0.1397 0.1397)
			(layers "F.Cu" "F.Mask" "F.Paste")
			(net "DUALPORTEN#8")
			(options
				(clearance outline)
				(anchor circle)
			)
			(primitives
				(gr_poly
					(pts
						(arc
							(start -0.1778 -0.2794)
							(mid -0.249642 -0.249642)
							(end -0.2794 -0.1778)
						)
						(arc
							(start -0.2794 0.1778)
							(mid -0.249642 0.249642)
							(end -0.1778 0.2794)
						)
						(arc
							(start 0.1778 0.2794)
							(mid 0.249642 0.249642)
							(end 0.2794 0.1778)
						)
						(arc
							(start 0.2794 -0.1778)
							(mid 0.249642 -0.249642)
							(end 0.1778 -0.2794)
						)
					)
					(width 0)
					(fill yes)
				)
			)
		)
	)
	(footprint ""
		(layer "F.Cu")
		(at 81.788 -146.431 -90)
		(property "Reference" "R428"
			(at 0 0 270)
			(layer "F.SilkS")
			(hide yes)
			(effects
				(font
					(size 1.27 1.27)
				)
			)
		)
		(property "Value" "0R2J-2-GP"
			(at 0.064008 -3.993896 270)
			(unlocked yes)
			(layer "F.Fab")
			(hide yes)
			(effects
				(font
					(size 1.016 1.016)
					(thickness 0.1524)
				)
			)
		)
		(property "Device Type" "R402H16"
			(at 0.064008 -5.517896 270)
			(unlocked yes)
			(layer "F.Fab")
			(hide yes)
			(effects
				(font
					(size 1.016 1.016)
					(thickness 0.1524)
				)
			)
		)
		(duplicate_pad_numbers_are_jumpers no)
		(fp_line
			(start -0.508 -0.9398)
			(end -0.508 0.9398)
			(stroke
				(width 0.1524)
				(type default)
			)
			(layer "F.SilkS")
		)
		(fp_line
			(start 0.508 -0.9398)
			(end -0.508 -0.9398)
			(stroke
				(width 0.1524)
				(type default)
			)
			(layer "F.SilkS")
		)
		(fp_rect
			(start -0.508 0.9398)
			(end 0.508 -0.9398)
			(stroke
				(width 0)
				(type default)
			)
			(fill no)
			(layer "F.CrtYd")
		)
		(fp_rect
			(start -0.508 0.9398)
			(end 0.508 -0.9398)
			(stroke
				(width 0)
				(type default)
			)
			(fill no)
			(layer "F.Fab")
		)
		(pad "1" smd custom
			(at 0 -0.4445 270)
			(size 0.1397 0.1397)
			(layers "F.Cu" "F.Mask" "F.Paste")
			(net "BMC_I2C_SDA_BUF_8")
			(options
				(clearance outline)
				(anchor circle)
			)
			(primitives
				(gr_poly
					(pts
						(arc
							(start -0.1778 -0.2794)
							(mid -0.249642 -0.249642)
							(end -0.2794 -0.1778)
						)
						(arc
							(start -0.2794 0.1778)
							(mid -0.249642 0.249642)
							(end -0.1778 0.2794)
						)
						(arc
							(start 0.1778 0.2794)
							(mid 0.249642 0.249642)
							(end 0.2794 0.1778)
						)
						(arc
							(start 0.2794 -0.1778)
							(mid 0.249642 -0.249642)
							(end 0.1778 -0.2794)
						)
					)
					(width 0)
					(fill yes)
				)
			)
		)
		(pad "2" smd custom
			(at 0 0.4445 270)
			(size 0.1397 0.1397)
			(layers "F.Cu" "F.Mask" "F.Paste")
			(net "I2C8_SDA_R_SW_EU16")
			(options
				(clearance outline)
				(anchor circle)
			)
			(primitives
				(gr_poly
					(pts
						(arc
							(start -0.1778 -0.2794)
							(mid -0.249642 -0.249642)
							(end -0.2794 -0.1778)
						)
						(arc
							(start -0.2794 0.1778)
							(mid -0.249642 0.249642)
							(end -0.1778 0.2794)
						)
						(arc
							(start 0.1778 0.2794)
							(mid 0.249642 0.249642)
							(end 0.2794 0.1778)
						)
						(arc
							(start 0.2794 -0.1778)
							(mid 0.249642 -0.249642)
							(end 0.1778 -0.2794)
						)
					)
					(width 0)
					(fill yes)
				)
			)
		)
	)
	(footprint ""
		(layer "F.Cu")
		(at 18.50009 -464.90001)
		(property "Reference" "LED10"
			(at 0 0 0)
			(layer "F.SilkS")
			(hide yes)
			(effects
				(font
					(size 1.27 1.27)
				)
			)
		)
		(property "Value" "LED-RB-4-GP"
			(at 5.88899 1.80848 0)
			(unlocked yes)
			(layer "F.Fab")
			(hide yes)
			(effects
				(font
					(size 1.016 1.016)
					(thickness 0.1524)
				)
			)
		)
		(property "Device Type" "LED1613-4PH20"
			(at 5.88899 0.28448 0)
			(unlocked yes)
			(layer "F.Fab")
			(hide yes)
			(effects
				(font
					(size 1.016 1.016)
					(thickness 0.1524)
				)
			)
		)
		(duplicate_pad_numbers_are_jumpers no)
		(fp_line
			(start -1.4478 -0.9652)
			(end 1.4478 -0.9652)
			(stroke
				(width 0.1524)
				(type default)
			)
			(layer "F.SilkS")
		)
		(fp_line
			(start -1.4478 0.9652)
			(end -1.4478 -0.9652)
			(stroke
				(width 0.1524)
				(type default)
			)
			(layer "F.SilkS")
		)
		(fp_line
			(start -1.4478 0.9652)
			(end -1.4478 -0.9652)
			(stroke
				(width 0.508)
				(type default)
			)
			(layer "F.SilkS")
		)
		(fp_line
			(start 1.4478 -0.9652)
			(end 1.4478 0.9652)
			(stroke
				(width 0.1524)
				(type default)
			)
			(layer "F.SilkS")
		)
		(fp_line
			(start 1.4478 0.9652)
			(end -1.4478 0.9652)
			(stroke
				(width 0.1524)
				(type default)
			)
			(layer "F.SilkS")
		)
		(fp_rect
			(start -0.8001 0.6477)
			(end 0.8001 -0.6477)
			(stroke
				(width 0)
				(type default)
			)
			(fill no)
			(layer "F.CrtYd")
		)
		(fp_poly
			(pts
				(xy -1.7018 1.2192) (xy -1.7018 -0.06223) (xy -0.8001 -0.06223) (xy -0.8001 0.6477) (xy 0.8001 0.6477)
				(xy 0.8001 -0.6477) (xy -0.8001 -0.6477) (xy -0.8001 -0.0635) (xy -1.7018 -0.0635) (xy -1.7018 -1.2192)
				(xy 1.7018 -1.2192) (xy 1.7018 1.2192)
			)
			(stroke
				(width 0)
				(type default)
			)
			(fill no)
			(layer "F.CrtYd")
		)
		(fp_rect
			(start -1.7018 1.2192)
			(end 1.7018 -1.2192)
			(stroke
				(width 0)
				(type default)
			)
			(fill no)
			(layer "F.Fab")
		)
		(pad "1" smd rect
			(at -0.73025 0.4064)
			(size 0.9144 0.6096)
			(layers "F.Cu" "F.Mask" "F.Paste")
			(net "SSD_ACT_DR10_MOS_N")
		)
		(pad "2" smd rect
			(at -0.73025 -0.4064)
			(size 0.9144 0.6096)
			(layers "F.Cu" "F.Mask" "F.Paste")
			(net "ATTN_LED_DR10_MOS_N")
		)
		(pad "3" smd rect
			(at 0.73025 -0.4064)
			(size 0.9144 0.6096)
			(layers "F.Cu" "F.Mask" "F.Paste")
			(net "DRV_ATTN_10")
		)
		(pad "4" smd rect
			(at 0.73025 0.4064)
			(size 0.9144 0.6096)
			(layers "F.Cu" "F.Mask" "F.Paste")
			(net "DRV_ACT_10")
		)
	)
	(footprint ""
		(layer "F.Cu")
		(at 84.455 -97.79 90)
		(property "Reference" "R426"
			(at 0 0 90)
			(layer "F.SilkS")
			(hide yes)
			(effects
				(font
					(size 1.27 1.27)
				)
			)
		)
		(property "Value" "0R2J-2-GP"
			(at 0.064008 -3.993896 90)
			(unlocked yes)
			(layer "F.Fab")
			(hide yes)
			(effects
				(font
					(size 1.016 1.016)
					(thickness 0.1524)
				)
			)
		)
		(property "Device Type" "R402H16"
			(at 0.064008 -5.517896 90)
			(unlocked yes)
			(layer "F.Fab")
			(hide yes)
			(effects
				(font
					(size 1.016 1.016)
					(thickness 0.1524)
				)
			)
		)
		(duplicate_pad_numbers_are_jumpers no)
		(fp_line
			(start 0.508 -0.9398)
			(end -0.508 -0.9398)
			(stroke
				(width 0.1524)
				(type default)
			)
			(layer "F.SilkS")
		)
		(fp_line
			(start -0.508 -0.9398)
			(end -0.508 0.9398)
			(stroke
				(width 0.1524)
				(type default)
			)
			(layer "F.SilkS")
		)
		(fp_rect
			(start -0.508 0.9398)
			(end 0.508 -0.9398)
			(stroke
				(width 0)
				(type default)
			)
			(fill no)
			(layer "F.CrtYd")
		)
		(fp_rect
			(start -0.508 0.9398)
			(end 0.508 -0.9398)
			(stroke
				(width 0)
				(type default)
			)
			(fill no)
			(layer "F.Fab")
		)
		(pad "1" smd custom
			(at 0 -0.4445 90)
			(size 0.1397 0.1397)
			(layers "F.Cu" "F.Mask" "F.Paste")
			(net "BMC_I2C_SDA_BUF_8")
			(options
				(clearance outline)
				(anchor circle)
			)
			(primitives
				(gr_poly
					(pts
						(arc
							(start -0.1778 -0.2794)
							(mid -0.249642 -0.249642)
							(end -0.2794 -0.1778)
						)
						(arc
							(start -0.2794 0.1778)
							(mid -0.249642 0.249642)
							(end -0.1778 0.2794)
						)
						(arc
							(start 0.1778 0.2794)
							(mid 0.249642 0.249642)
							(end 0.2794 0.1778)
						)
						(arc
							(start 0.2794 -0.1778)
							(mid 0.249642 -0.249642)
							(end 0.1778 -0.2794)
						)
					)
					(width 0)
					(fill yes)
				)
			)
		)
		(pad "2" smd custom
			(at 0 0.4445 90)
			(size 0.1397 0.1397)
			(layers "F.Cu" "F.Mask" "F.Paste")
			(net "I2C_SDA_BUF_8_EU4_R")
			(options
				(clearance outline)
				(anchor circle)
			)
			(primitives
				(gr_poly
					(pts
						(arc
							(start -0.1778 -0.2794)
							(mid -0.249642 -0.249642)
							(end -0.2794 -0.1778)
						)
						(arc
							(start -0.2794 0.1778)
							(mid -0.249642 0.249642)
							(end -0.1778 0.2794)
						)
						(arc
							(start 0.1778 0.2794)
							(mid 0.249642 0.249642)
							(end 0.2794 0.1778)
						)
						(arc
							(start 0.2794 -0.1778)
							(mid 0.249642 -0.249642)
							(end 0.1778 -0.2794)
						)
					)
					(width 0)
					(fill yes)
				)
			)
		)
	)
	(footprint ""
		(layer "F.Cu")
		(at 8.8138 -467.5124 90)
		(property "Reference" "PC1168"
			(at 0 0 90)
			(layer "F.SilkS")
			(hide yes)
			(effects
				(font
					(size 1.27 1.27)
				)
			)
		)
		(property "Value" "SC22U25V6KX-GP-U"
			(at -2.860802 -5.279644 90)
			(unlocked yes)
			(layer "F.Fab")
			(hide yes)
			(effects
				(font
					(size 1.016 1.016)
					(thickness 0.1524)
				)
			)
		)
		(property "Device Type" "C1206-TO0D3H75"
			(at -2.860802 -6.803644 90)
			(unlocked yes)
			(layer "F.Fab")
			(hide yes)
			(effects
				(font
					(size 1.016 1.016)
					(thickness 0.1524)
				)
			)
		)
		(duplicate_pad_numbers_are_jumpers no)
		(fp_line
			(start 1.3081 -2.3749)
			(end 1.3081 2.3749)
			(stroke
				(width 0.1524)
				(type default)
			)
			(layer "F.SilkS")
		)
		(fp_line
			(start -1.3081 -2.3749)
			(end 1.3081 -2.3749)
			(stroke
				(width 0.1524)
				(type default)
			)
			(layer "F.SilkS")
		)
		(fp_line
			(start 1.3081 2.3749)
			(end -1.3081 2.3749)
			(stroke
				(width 0.1524)
				(type default)
			)
			(layer "F.SilkS")
		)
		(fp_line
			(start -1.3081 2.3749)
			(end -1.3081 -2.3749)
			(stroke
				(width 0.1524)
				(type default)
			)
			(layer "F.SilkS")
		)
		(fp_rect
			(start -0.8001 1.6002)
			(end 0.8001 -1.6002)
			(stroke
				(width 0)
				(type default)
			)
			(fill no)
			(layer "F.CrtYd")
		)
		(fp_poly
			(pts
				(xy -1.5621 2.4511) (xy -1.5621 1.6002) (xy 0.8001 1.6002) (xy 0.8001 -1.6002) (xy -0.8001 -1.6002)
				(xy -0.8001 1.5875) (xy -1.5621 1.5875) (xy -1.5621 -2.4511) (xy 1.5621 -2.4511) (xy 1.5621 2.4511)
			)
			(stroke
				(width 0)
				(type default)
			)
			(fill no)
			(layer "F.CrtYd")
		)
		(fp_rect
			(start -1.5621 2.4511)
			(end 1.5621 -2.4511)
			(stroke
				(width 0)
				(type default)
			)
			(fill no)
			(layer "F.Fab")
		)
		(pad "1" smd rect
			(at 0 -1.392936 90)
			(size 2.1082 1.4478)
			(layers "F.Cu" "F.Mask" "F.Paste")
			(net "P12V")
		)
		(pad "2" smd rect
			(at 0 1.392936 90)
			(size 2.1082 1.4478)
			(layers "F.Cu" "F.Mask" "F.Paste")
			(net "GND")
		)
	)
	(footprint ""
		(layer "F.Cu")
		(at 97.028 -26.162 180)
		(property "Reference" "R9757"
			(at 0 0 180)
			(layer "F.SilkS")
			(hide yes)
			(effects
				(font
					(size 1.27 1.27)
				)
			)
		)
		(property "Value" "0R2J-2-GP"
			(at 0.064008 -3.993896 180)
			(unlocked yes)
			(layer "F.Fab")
			(hide yes)
			(effects
				(font
					(size 1.016 1.016)
					(thickness 0.1524)
				)
			)
		)
		(property "Device Type" "R402H16"
			(at 0.064008 -5.517896 180)
			(unlocked yes)
			(layer "F.Fab")
			(hide yes)
			(effects
				(font
					(size 1.016 1.016)
					(thickness 0.1524)
				)
			)
		)
		(duplicate_pad_numbers_are_jumpers no)
		(fp_line
			(start 0.508 -0.9398)
			(end -0.508 -0.9398)
			(stroke
				(width 0.1524)
				(type default)
			)
			(layer "F.SilkS")
		)
		(fp_line
			(start -0.508 -0.9398)
			(end -0.508 0.9398)
			(stroke
				(width 0.1524)
				(type default)
			)
			(layer "F.SilkS")
		)
		(fp_rect
			(start -0.508 0.9398)
			(end 0.508 -0.9398)
			(stroke
				(width 0)
				(type default)
			)
			(fill no)
			(layer "F.CrtYd")
		)
		(fp_rect
			(start -0.508 0.9398)
			(end 0.508 -0.9398)
			(stroke
				(width 0)
				(type default)
			)
			(fill no)
			(layer "F.Fab")
		)
		(pad "1" smd custom
			(at 0 -0.4445 180)
			(size 0.1397 0.1397)
			(layers "F.Cu" "F.Mask" "F.Paste")
			(net "P3V3")
			(options
				(clearance outline)
				(anchor circle)
			)
			(primitives
				(gr_poly
					(pts
						(arc
							(start -0.1778 -0.2794)
							(mid -0.249642 -0.249642)
							(end -0.2794 -0.1778)
						)
						(arc
							(start -0.2794 0.1778)
							(mid -0.249642 0.249642)
							(end -0.1778 0.2794)
						)
						(arc
							(start 0.1778 0.2794)
							(mid 0.249642 0.249642)
							(end 0.2794 0.1778)
						)
						(arc
							(start 0.2794 -0.1778)
							(mid 0.249642 -0.249642)
							(end 0.1778 -0.2794)
						)
					)
					(width 0)
					(fill yes)
				)
			)
		)
		(pad "2" smd custom
			(at 0 0.4445 180)
			(size 0.1397 0.1397)
			(layers "F.Cu" "F.Mask" "F.Paste")
			(net "P3V3_SENSE")
			(options
				(clearance outline)
				(anchor circle)
			)
			(primitives
				(gr_poly
					(pts
						(arc
							(start -0.1778 -0.2794)
							(mid -0.249642 -0.249642)
							(end -0.2794 -0.1778)
						)
						(arc
							(start -0.2794 0.1778)
							(mid -0.249642 0.249642)
							(end -0.1778 0.2794)
						)
						(arc
							(start 0.1778 0.2794)
							(mid 0.249642 0.249642)
							(end 0.2794 0.1778)
						)
						(arc
							(start 0.2794 -0.1778)
							(mid 0.249642 -0.249642)
							(end 0.1778 -0.2794)
						)
					)
					(width 0)
					(fill yes)
				)
			)
		)
	)
	(footprint ""
		(layer "F.Cu")
		(at 97.028 -89.535 90)
		(property "Reference" "C9355"
			(at 0 0 90)
			(layer "F.SilkS")
			(hide yes)
			(effects
				(font
					(size 1.27 1.27)
				)
			)
		)
		(property "Value" "SC1KP50V2KX-1GP"
			(at 1.1811 -2.7051 90)
			(unlocked yes)
			(layer "F.Fab")
			(hide yes)
			(effects
				(font
					(size 1.016 1.016)
					(thickness 0.1524)
				)
			)
		)
		(property "Device Type" "C402H22"
			(at 1.1811 -4.2291 90)
			(unlocked yes)
			(layer "F.Fab")
			(hide yes)
			(effects
				(font
					(size 1.016 1.016)
					(thickness 0.1524)
				)
			)
		)
		(duplicate_pad_numbers_are_jumpers no)
		(fp_rect
			(start -0.4318 0.9525)
			(end 0.4318 -0.9525)
			(stroke
				(width 0)
				(type default)
			)
			(fill no)
			(layer "F.CrtYd")
		)
		(fp_rect
			(start -0.4318 0.9525)
			(end 0.4318 -0.9525)
			(stroke
				(width 0)
				(type default)
			)
			(fill no)
			(layer "F.Fab")
		)
		(pad "1" smd custom
			(at 0 -0.4445 90)
			(size 0.1524 0.1524)
			(layers "F.Cu" "F.Mask" "F.Paste")
			(net "SSD_PRSNT14")
			(options
				(clearance outline)
				(anchor circle)
			)
			(primitives
				(gr_poly
					(pts
						(arc
							(start 0.3048 -0.2032)
							(mid 0.275042 -0.275042)
							(end 0.2032 -0.3048)
						)
						(arc
							(start -0.2032 -0.3048)
							(mid -0.275042 -0.275042)
							(end -0.3048 -0.2032)
						)
						(arc
							(start -0.3048 0.2032)
							(mid -0.275042 0.275042)
							(end -0.2032 0.3048)
						)
						(arc
							(start 0.2032 0.3048)
							(mid 0.275042 0.275042)
							(end 0.3048 0.2032)
						)
					)
					(width 0)
					(fill yes)
				)
			)
		)
		(pad "2" smd custom
			(at 0 0.4445 90)
			(size 0.1524 0.1524)
			(layers "F.Cu" "F.Mask" "F.Paste")
			(net "GND")
			(options
				(clearance outline)
				(anchor circle)
			)
			(primitives
				(gr_poly
					(pts
						(arc
							(start 0.3048 -0.2032)
							(mid 0.275042 -0.275042)
							(end 0.2032 -0.3048)
						)
						(arc
							(start -0.2032 -0.3048)
							(mid -0.275042 -0.275042)
							(end -0.3048 -0.2032)
						)
						(arc
							(start -0.3048 0.2032)
							(mid -0.275042 0.275042)
							(end -0.2032 0.3048)
						)
						(arc
							(start 0.2032 0.3048)
							(mid 0.275042 0.275042)
							(end 0.3048 0.2032)
						)
					)
					(width 0)
					(fill yes)
				)
			)
		)
	)
	(footprint ""
		(layer "F.Cu")
		(at 50.546 -138.303 180)
		(property "Reference" "R344"
			(at 0 0 180)
			(layer "F.SilkS")
			(hide yes)
			(effects
				(font
					(size 1.27 1.27)
				)
			)
		)
		(property "Value" "4K7R2J-2-GP"
			(at 0.064008 -3.993896 180)
			(unlocked yes)
			(layer "F.Fab")
			(hide yes)
			(effects
				(font
					(size 1.016 1.016)
					(thickness 0.1524)
				)
			)
		)
		(property "Device Type" "R402H16"
			(at 0.064008 -5.517896 180)
			(unlocked yes)
			(layer "F.Fab")
			(hide yes)
			(effects
				(font
					(size 1.016 1.016)
					(thickness 0.1524)
				)
			)
		)
		(duplicate_pad_numbers_are_jumpers no)
		(fp_line
			(start 0.508 -0.9398)
			(end -0.508 -0.9398)
			(stroke
				(width 0.1524)
				(type default)
			)
			(layer "F.SilkS")
		)
		(fp_line
			(start -0.508 -0.9398)
			(end -0.508 0.9398)
			(stroke
				(width 0.1524)
				(type default)
			)
			(layer "F.SilkS")
		)
		(fp_rect
			(start -0.508 0.9398)
			(end 0.508 -0.9398)
			(stroke
				(width 0)
				(type default)
			)
			(fill no)
			(layer "F.CrtYd")
		)
		(fp_rect
			(start -0.508 0.9398)
			(end 0.508 -0.9398)
			(stroke
				(width 0)
				(type default)
			)
			(fill no)
			(layer "F.Fab")
		)
		(pad "1" smd custom
			(at 0 -0.4445 180)
			(size 0.1397 0.1397)
			(layers "F.Cu" "F.Mask" "F.Paste")
			(net "I2C_B_TMP1_A0")
			(options
				(clearance outline)
				(anchor circle)
			)
			(primitives
				(gr_poly
					(pts
						(arc
							(start -0.1778 -0.2794)
							(mid -0.249642 -0.249642)
							(end -0.2794 -0.1778)
						)
						(arc
							(start -0.2794 0.1778)
							(mid -0.249642 0.249642)
							(end -0.1778 0.2794)
						)
						(arc
							(start 0.1778 0.2794)
							(mid 0.249642 0.249642)
							(end 0.2794 0.1778)
						)
						(arc
							(start 0.2794 -0.1778)
							(mid 0.249642 -0.249642)
							(end 0.1778 -0.2794)
						)
					)
					(width 0)
					(fill yes)
				)
			)
		)
		(pad "2" smd custom
			(at 0 0.4445 180)
			(size 0.1397 0.1397)
			(layers "F.Cu" "F.Mask" "F.Paste")
			(net "GND")
			(options
				(clearance outline)
				(anchor circle)
			)
			(primitives
				(gr_poly
					(pts
						(arc
							(start -0.1778 -0.2794)
							(mid -0.249642 -0.249642)
							(end -0.2794 -0.1778)
						)
						(arc
							(start -0.2794 0.1778)
							(mid -0.249642 0.249642)
							(end -0.1778 0.2794)
						)
						(arc
							(start 0.1778 0.2794)
							(mid 0.249642 0.249642)
							(end 0.2794 0.1778)
						)
						(arc
							(start 0.2794 -0.1778)
							(mid 0.249642 -0.249642)
							(end 0.1778 -0.2794)
						)
					)
					(width 0)
					(fill yes)
				)
			)
		)
	)
	(footprint ""
		(layer "F.Cu")
		(at 91.313 -440.436 180)
		(property "Reference" "R9065"
			(at 0 0 180)
			(layer "F.SilkS")
			(hide yes)
			(effects
				(font
					(size 1.27 1.27)
				)
			)
		)
		(property "Value" "27R2F-GP"
			(at 0.064008 -3.993896 180)
			(unlocked yes)
			(layer "F.Fab")
			(hide yes)
			(effects
				(font
					(size 1.016 1.016)
					(thickness 0.1524)
				)
			)
		)
		(property "Device Type" "R402H16"
			(at 0.064008 -5.517896 180)
			(unlocked yes)
			(layer "F.Fab")
			(hide yes)
			(effects
				(font
					(size 1.016 1.016)
					(thickness 0.1524)
				)
			)
		)
		(duplicate_pad_numbers_are_jumpers no)
		(fp_line
			(start 0.508 -0.9398)
			(end -0.508 -0.9398)
			(stroke
				(width 0.1524)
				(type default)
			)
			(layer "F.SilkS")
		)
		(fp_line
			(start -0.508 -0.9398)
			(end -0.508 0.9398)
			(stroke
				(width 0.1524)
				(type default)
			)
			(layer "F.SilkS")
		)
		(fp_rect
			(start -0.508 0.9398)
			(end 0.508 -0.9398)
			(stroke
				(width 0)
				(type default)
			)
			(fill no)
			(layer "F.CrtYd")
		)
		(fp_rect
			(start -0.508 0.9398)
			(end 0.508 -0.9398)
			(stroke
				(width 0)
				(type default)
			)
			(fill no)
			(layer "F.Fab")
		)
		(pad "1" smd custom
			(at 0 -0.4445 180)
			(size 0.1397 0.1397)
			(layers "F.Cu" "F.Mask" "F.Paste")
			(net "PE_CLK_100M_DR5_2_R_P")
			(options
				(clearance outline)
				(anchor circle)
			)
			(primitives
				(gr_poly
					(pts
						(arc
							(start -0.1778 -0.2794)
							(mid -0.249642 -0.249642)
							(end -0.2794 -0.1778)
						)
						(arc
							(start -0.2794 0.1778)
							(mid -0.249642 0.249642)
							(end -0.1778 0.2794)
						)
						(arc
							(start 0.1778 0.2794)
							(mid 0.249642 0.249642)
							(end 0.2794 0.1778)
						)
						(arc
							(start 0.2794 -0.1778)
							(mid 0.249642 -0.249642)
							(end 0.1778 -0.2794)
						)
					)
					(width 0)
					(fill yes)
				)
			)
		)
		(pad "2" smd custom
			(at 0 0.4445 180)
			(size 0.1397 0.1397)
			(layers "F.Cu" "F.Mask" "F.Paste")
			(net "PE_CLK100M_DR5_2_P")
			(options
				(clearance outline)
				(anchor circle)
			)
			(primitives
				(gr_poly
					(pts
						(arc
							(start -0.1778 -0.2794)
							(mid -0.249642 -0.249642)
							(end -0.2794 -0.1778)
						)
						(arc
							(start -0.2794 0.1778)
							(mid -0.249642 0.249642)
							(end -0.1778 0.2794)
						)
						(arc
							(start 0.1778 0.2794)
							(mid 0.249642 0.249642)
							(end 0.2794 0.1778)
						)
						(arc
							(start 0.2794 -0.1778)
							(mid 0.249642 -0.249642)
							(end 0.1778 -0.2794)
						)
					)
					(width 0)
					(fill yes)
				)
			)
		)
	)
	(footprint ""
		(layer "F.Cu")
		(at 50.546 -134.493 180)
		(property "Reference" "R343"
			(at 0 0 180)
			(layer "F.SilkS")
			(hide yes)
			(effects
				(font
					(size 1.27 1.27)
				)
			)
		)
		(property "Value" "4K7R2J-2-GP"
			(at 0.064008 -3.993896 180)
			(unlocked yes)
			(layer "F.Fab")
			(hide yes)
			(effects
				(font
					(size 1.016 1.016)
					(thickness 0.1524)
				)
			)
		)
		(property "Device Type" "R402H16"
			(at 0.064008 -5.517896 180)
			(unlocked yes)
			(layer "F.Fab")
			(hide yes)
			(effects
				(font
					(size 1.016 1.016)
					(thickness 0.1524)
				)
			)
		)
		(duplicate_pad_numbers_are_jumpers no)
		(fp_line
			(start 0.508 -0.9398)
			(end -0.508 -0.9398)
			(stroke
				(width 0.1524)
				(type default)
			)
			(layer "F.SilkS")
		)
		(fp_line
			(start -0.508 -0.9398)
			(end -0.508 0.9398)
			(stroke
				(width 0.1524)
				(type default)
			)
			(layer "F.SilkS")
		)
		(fp_rect
			(start -0.508 0.9398)
			(end 0.508 -0.9398)
			(stroke
				(width 0)
				(type default)
			)
			(fill no)
			(layer "F.CrtYd")
		)
		(fp_rect
			(start -0.508 0.9398)
			(end 0.508 -0.9398)
			(stroke
				(width 0)
				(type default)
			)
			(fill no)
			(layer "F.Fab")
		)
		(pad "1" smd custom
			(at 0 -0.4445 180)
			(size 0.1397 0.1397)
			(layers "F.Cu" "F.Mask" "F.Paste")
			(net "I2C_B_TMP1_A2")
			(options
				(clearance outline)
				(anchor circle)
			)
			(primitives
				(gr_poly
					(pts
						(arc
							(start -0.1778 -0.2794)
							(mid -0.249642 -0.249642)
							(end -0.2794 -0.1778)
						)
						(arc
							(start -0.2794 0.1778)
							(mid -0.249642 0.249642)
							(end -0.1778 0.2794)
						)
						(arc
							(start 0.1778 0.2794)
							(mid 0.249642 0.249642)
							(end 0.2794 0.1778)
						)
						(arc
							(start 0.2794 -0.1778)
							(mid 0.249642 -0.249642)
							(end 0.1778 -0.2794)
						)
					)
					(width 0)
					(fill yes)
				)
			)
		)
		(pad "2" smd custom
			(at 0 0.4445 180)
			(size 0.1397 0.1397)
			(layers "F.Cu" "F.Mask" "F.Paste")
			(net "GND")
			(options
				(clearance outline)
				(anchor circle)
			)
			(primitives
				(gr_poly
					(pts
						(arc
							(start -0.1778 -0.2794)
							(mid -0.249642 -0.249642)
							(end -0.2794 -0.1778)
						)
						(arc
							(start -0.2794 0.1778)
							(mid -0.249642 0.249642)
							(end -0.1778 0.2794)
						)
						(arc
							(start 0.1778 0.2794)
							(mid 0.249642 0.249642)
							(end 0.2794 0.1778)
						)
						(arc
							(start 0.2794 -0.1778)
							(mid 0.249642 -0.249642)
							(end 0.1778 -0.2794)
						)
					)
					(width 0)
					(fill yes)
				)
			)
		)
	)
	(footprint ""
		(layer "F.Cu")
		(at 88.138 -445.262)
		(property "Reference" "R9599"
			(at 0 0 0)
			(layer "F.SilkS")
			(hide yes)
			(effects
				(font
					(size 1.27 1.27)
				)
			)
		)
		(property "Value" "10R2F-L-GP"
			(at 0.064008 -3.993896 0)
			(unlocked yes)
			(layer "F.Fab")
			(hide yes)
			(effects
				(font
					(size 1.016 1.016)
					(thickness 0.1524)
				)
			)
		)
		(property "Device Type" "R402H14"
			(at 0.064008 -5.517896 0)
			(unlocked yes)
			(layer "F.Fab")
			(hide yes)
			(effects
				(font
					(size 1.016 1.016)
					(thickness 0.1524)
				)
			)
		)
		(duplicate_pad_numbers_are_jumpers no)
		(fp_line
			(start -0.508 -0.9398)
			(end -0.508 0.9398)
			(stroke
				(width 0.1524)
				(type default)
			)
			(layer "F.SilkS")
		)
		(fp_line
			(start 0.508 -0.9398)
			(end -0.508 -0.9398)
			(stroke
				(width 0.1524)
				(type default)
			)
			(layer "F.SilkS")
		)
		(fp_rect
			(start -0.508 0.9398)
			(end 0.508 -0.9398)
			(stroke
				(width 0)
				(type default)
			)
			(fill no)
			(layer "F.CrtYd")
		)
		(fp_rect
			(start -0.508 0.9398)
			(end 0.508 -0.9398)
			(stroke
				(width 0)
				(type default)
			)
			(fill no)
			(layer "F.Fab")
		)
		(pad "1" smd custom
			(at 0 -0.4445)
			(size 0.1397 0.1397)
			(layers "F.Cu" "F.Mask" "F.Paste")
			(net "SSD5_CLK0_OE_N")
			(options
				(clearance outline)
				(anchor circle)
			)
			(primitives
				(gr_poly
					(pts
						(arc
							(start -0.1778 -0.2794)
							(mid -0.249642 -0.249642)
							(end -0.2794 -0.1778)
						)
						(arc
							(start -0.2794 0.1778)
							(mid -0.249642 0.249642)
							(end -0.1778 0.2794)
						)
						(arc
							(start 0.1778 0.2794)
							(mid 0.249642 0.249642)
							(end 0.2794 0.1778)
						)
						(arc
							(start 0.2794 -0.1778)
							(mid 0.249642 -0.249642)
							(end 0.1778 -0.2794)
						)
					)
					(width 0)
					(fill yes)
				)
			)
		)
		(pad "2" smd custom
			(at 0 0.4445)
			(size 0.1397 0.1397)
			(layers "F.Cu" "F.Mask" "F.Paste")
			(net "SSD5_CLK0_OE_R_N")
			(options
				(clearance outline)
				(anchor circle)
			)
			(primitives
				(gr_poly
					(pts
						(arc
							(start -0.1778 -0.2794)
							(mid -0.249642 -0.249642)
							(end -0.2794 -0.1778)
						)
						(arc
							(start -0.2794 0.1778)
							(mid -0.249642 0.249642)
							(end -0.1778 0.2794)
						)
						(arc
							(start 0.1778 0.2794)
							(mid 0.249642 0.249642)
							(end 0.2794 0.1778)
						)
						(arc
							(start 0.2794 -0.1778)
							(mid 0.249642 -0.249642)
							(end 0.1778 -0.2794)
						)
					)
					(width 0)
					(fill yes)
				)
			)
		)
	)
	(footprint ""
		(layer "F.Cu")
		(at 47.879 -349.885 -90)
		(property "Reference" "R9471"
			(at 0 0 270)
			(layer "F.SilkS")
			(hide yes)
			(effects
				(font
					(size 1.27 1.27)
				)
			)
		)
		(property "Value" "100R2J-2-GP"
			(at 0.064008 -3.993896 270)
			(unlocked yes)
			(layer "F.Fab")
			(hide yes)
			(effects
				(font
					(size 1.016 1.016)
					(thickness 0.1524)
				)
			)
		)
		(property "Device Type" "R402H14"
			(at 0.064008 -5.517896 270)
			(unlocked yes)
			(layer "F.Fab")
			(hide yes)
			(effects
				(font
					(size 1.016 1.016)
					(thickness 0.1524)
				)
			)
		)
		(duplicate_pad_numbers_are_jumpers no)
		(fp_line
			(start -0.508 -0.9398)
			(end -0.508 0.9398)
			(stroke
				(width 0.1524)
				(type default)
			)
			(layer "F.SilkS")
		)
		(fp_line
			(start 0.508 -0.9398)
			(end -0.508 -0.9398)
			(stroke
				(width 0.1524)
				(type default)
			)
			(layer "F.SilkS")
		)
		(fp_rect
			(start -0.508 0.9398)
			(end 0.508 -0.9398)
			(stroke
				(width 0)
				(type default)
			)
			(fill no)
			(layer "F.CrtYd")
		)
		(fp_rect
			(start -0.508 0.9398)
			(end 0.508 -0.9398)
			(stroke
				(width 0)
				(type default)
			)
			(fill no)
			(layer "F.Fab")
		)
		(pad "1" smd custom
			(at 0 -0.4445 270)
			(size 0.1397 0.1397)
			(layers "F.Cu" "F.Mask" "F.Paste")
			(net "P3V3")
			(options
				(clearance outline)
				(anchor circle)
			)
			(primitives
				(gr_poly
					(pts
						(arc
							(start -0.1778 -0.2794)
							(mid -0.249642 -0.249642)
							(end -0.2794 -0.1778)
						)
						(arc
							(start -0.2794 0.1778)
							(mid -0.249642 0.249642)
							(end -0.1778 0.2794)
						)
						(arc
							(start 0.1778 0.2794)
							(mid 0.249642 0.249642)
							(end 0.2794 0.1778)
						)
						(arc
							(start 0.2794 -0.1778)
							(mid 0.249642 -0.249642)
							(end 0.1778 -0.2794)
						)
					)
					(width 0)
					(fill yes)
				)
			)
		)
		(pad "2" smd custom
			(at 0 0.4445 270)
			(size 0.1397 0.1397)
			(layers "F.Cu" "F.Mask" "F.Paste")
			(net "DRV_ACT_6")
			(options
				(clearance outline)
				(anchor circle)
			)
			(primitives
				(gr_poly
					(pts
						(arc
							(start -0.1778 -0.2794)
							(mid -0.249642 -0.249642)
							(end -0.2794 -0.1778)
						)
						(arc
							(start -0.2794 0.1778)
							(mid -0.249642 0.249642)
							(end -0.1778 0.2794)
						)
						(arc
							(start 0.1778 0.2794)
							(mid 0.249642 0.249642)
							(end 0.2794 0.1778)
						)
						(arc
							(start 0.2794 -0.1778)
							(mid 0.249642 -0.249642)
							(end 0.1778 -0.2794)
						)
					)
					(width 0)
					(fill yes)
				)
			)
		)
	)
	(footprint ""
		(layer "F.Cu")
		(at 23.998174 -165.08349 -90)
		(property "Reference" "U210"
			(at 0 0 270)
			(layer "F.SilkS")
			(hide yes)
			(effects
				(font
					(size 1.27 1.27)
				)
			)
		)
		(property "Value" "SN74LVC1G08DCKR-GP"
			(at -2.3368 -8.6868 270)
			(unlocked yes)
			(layer "F.Fab")
			(hide yes)
			(effects
				(font
					(size 1.016 1.016)
					(thickness 0.1524)
				)
			)
		)
		(property "Device Type" "SC70-5H44"
			(at -2.3114 -10.414 270)
			(unlocked yes)
			(layer "F.Fab")
			(hide yes)
			(effects
				(font
					(size 1.016 1.016)
					(thickness 0.1524)
				)
			)
		)
		(duplicate_pad_numbers_are_jumpers no)
		(fp_line
			(start -1.27 1.7018)
			(end -1.27 -1.7018)
			(stroke
				(width 0.1524)
				(type default)
			)
			(layer "F.SilkS")
		)
		(fp_line
			(start 1.27 1.7018)
			(end -1.27 1.7018)
			(stroke
				(width 0.1524)
				(type default)
			)
			(layer "F.SilkS")
		)
		(fp_line
			(start -1.27 -1.7018)
			(end 1.27 -1.7018)
			(stroke
				(width 0.1524)
				(type default)
			)
			(layer "F.SilkS")
		)
		(fp_line
			(start 1.27 -1.7018)
			(end 1.27 1.7018)
			(stroke
				(width 0.1524)
				(type default)
			)
			(layer "F.SilkS")
		)
		(fp_line
			(start 0.6604 -1.8034)
			(end 1.3843 -1.8034)
			(stroke
				(width 0.3302)
				(type default)
			)
			(layer "F.SilkS")
		)
		(fp_line
			(start 1.3843 -1.8034)
			(end 1.3843 -1.1176)
			(stroke
				(width 0.3302)
				(type default)
			)
			(layer "F.SilkS")
		)
		(fp_rect
			(start -1.524 1.9558)
			(end 1.524 -1.9558)
			(stroke
				(width 0)
				(type default)
			)
			(fill no)
			(layer "F.CrtYd")
		)
		(fp_poly
			(pts
				(xy -1.524 -1.9558) (xy 1.524 -1.9558) (xy 1.524 1.9558) (xy -1.524 1.9558)
			)
			(stroke
				(width 0)
				(type default)
			)
			(fill no)
			(layer "F.Fab")
		)
		(pad "1" smd rect
			(at 0.65024 -0.8255 270)
			(size 0.4064 1.2192)
			(layers "F.Cu" "F.Mask" "F.Paste")
			(net "SSD13_CLK0_OE_MOS_N")
		)
		(pad "2" smd rect
			(at 0 -0.8255 270)
			(size 0.4064 1.2192)
			(layers "F.Cu" "F.Mask" "F.Paste")
			(net "ATTN_LED_DR13_N")
		)
		(pad "3" smd rect
			(at -0.65024 -0.8255 270)
			(size 0.4064 1.2192)
			(layers "F.Cu" "F.Mask" "F.Paste")
			(net "GND")
		)
		(pad "4" smd rect
			(at -0.65024 0.8255 270)
			(size 0.4064 1.2192)
			(layers "F.Cu" "F.Mask" "F.Paste")
			(net "ATTN_LED_DR13_AND")
		)
		(pad "5" smd rect
			(at 0.65024 0.8255 270)
			(size 0.4064 1.2192)
			(layers "F.Cu" "F.Mask" "F.Paste")
			(net "P3V3")
		)
	)
	(footprint ""
		(layer "F.Cu")
		(at 230.632 -346.198952 -90)
		(property "Reference" "R9789"
			(at 0 0 270)
			(layer "F.SilkS")
			(hide yes)
			(effects
				(font
					(size 1.27 1.27)
				)
			)
		)
		(property "Value" "0R2J-2-GP"
			(at 0.064008 -3.993896 270)
			(unlocked yes)
			(layer "F.Fab")
			(hide yes)
			(effects
				(font
					(size 1.016 1.016)
					(thickness 0.1524)
				)
			)
		)
		(property "Device Type" "R402H16"
			(at 0.064008 -5.517896 270)
			(unlocked yes)
			(layer "F.Fab")
			(hide yes)
			(effects
				(font
					(size 1.016 1.016)
					(thickness 0.1524)
				)
			)
		)
		(duplicate_pad_numbers_are_jumpers no)
		(fp_line
			(start -0.508 -0.9398)
			(end -0.508 0.9398)
			(stroke
				(width 0.1524)
				(type default)
			)
			(layer "F.SilkS")
		)
		(fp_line
			(start 0.508 -0.9398)
			(end -0.508 -0.9398)
			(stroke
				(width 0.1524)
				(type default)
			)
			(layer "F.SilkS")
		)
		(fp_rect
			(start -0.508 0.9398)
			(end 0.508 -0.9398)
			(stroke
				(width 0)
				(type default)
			)
			(fill no)
			(layer "F.CrtYd")
		)
		(fp_rect
			(start -0.508 0.9398)
			(end 0.508 -0.9398)
			(stroke
				(width 0)
				(type default)
			)
			(fill no)
			(layer "F.Fab")
		)
		(pad "1" smd custom
			(at 0 -0.4445 270)
			(size 0.1397 0.1397)
			(layers "F.Cu" "F.Mask" "F.Paste")
			(net "SSD_ACT_DR1_R")
			(options
				(clearance outline)
				(anchor circle)
			)
			(primitives
				(gr_poly
					(pts
						(arc
							(start -0.1778 -0.2794)
							(mid -0.249642 -0.249642)
							(end -0.2794 -0.1778)
						)
						(arc
							(start -0.2794 0.1778)
							(mid -0.249642 0.249642)
							(end -0.1778 0.2794)
						)
						(arc
							(start 0.1778 0.2794)
							(mid 0.249642 0.249642)
							(end 0.2794 0.1778)
						)
						(arc
							(start 0.2794 -0.1778)
							(mid 0.249642 -0.249642)
							(end 0.1778 -0.2794)
						)
					)
					(width 0)
					(fill yes)
				)
			)
		)
		(pad "2" smd custom
			(at 0 0.4445 270)
			(size 0.1397 0.1397)
			(layers "F.Cu" "F.Mask" "F.Paste")
			(net "SSD_ACT_DR1")
			(options
				(clearance outline)
				(anchor circle)
			)
			(primitives
				(gr_poly
					(pts
						(arc
							(start -0.1778 -0.2794)
							(mid -0.249642 -0.249642)
							(end -0.2794 -0.1778)
						)
						(arc
							(start -0.2794 0.1778)
							(mid -0.249642 0.249642)
							(end -0.1778 0.2794)
						)
						(arc
							(start 0.1778 0.2794)
							(mid 0.249642 0.249642)
							(end 0.2794 0.1778)
						)
						(arc
							(start 0.2794 -0.1778)
							(mid 0.249642 -0.249642)
							(end 0.1778 -0.2794)
						)
					)
					(width 0)
					(fill yes)
				)
			)
		)
	)
	(footprint ""
		(layer "F.Cu")
		(at 13.843 -493.776)
		(property "Reference" "D23"
			(at 0 0 0)
			(layer "F.SilkS")
			(hide yes)
			(effects
				(font
					(size 1.27 1.27)
				)
			)
		)
		(property "Value" "RB551V30-1-GP"
			(at 0 -6.7818 0)
			(unlocked yes)
			(layer "F.Fab")
			(hide yes)
			(effects
				(font
					(size 1.016 1.016)
					(thickness 0.1524)
				)
			)
		)
		(property "Device Type" "SOD323AKH44"
			(at 0 -8.6868 0)
			(unlocked yes)
			(layer "F.Fab")
			(hide yes)
			(effects
				(font
					(size 1.016 1.016)
					(thickness 0.1524)
				)
			)
		)
		(duplicate_pad_numbers_are_jumpers no)
		(fp_line
			(start -0.889 -1.9304)
			(end 0.889 -1.9304)
			(stroke
				(width 0.1524)
				(type default)
			)
			(layer "F.SilkS")
		)
		(fp_line
			(start -0.889 2.159)
			(end -0.889 -1.9304)
			(stroke
				(width 0.1524)
				(type default)
			)
			(layer "F.SilkS")
		)
		(fp_line
			(start 0.762 2.0574)
			(end -0.762 2.0574)
			(stroke
				(width 0.508)
				(type default)
			)
			(layer "F.SilkS")
		)
		(fp_line
			(start 0.889 -1.9304)
			(end 0.889 2.159)
			(stroke
				(width 0.1524)
				(type default)
			)
			(layer "F.SilkS")
		)
		(fp_line
			(start 0.889 2.159)
			(end -0.889 2.159)
			(stroke
				(width 0.1524)
				(type default)
			)
			(layer "F.SilkS")
		)
		(fp_rect
			(start -1.016 2.3114)
			(end 1.016 -2.0066)
			(stroke
				(width 0)
				(type default)
			)
			(fill no)
			(layer "F.CrtYd")
		)
		(fp_poly
			(pts
				(xy -1.016 -2.0066) (xy 1.016 -2.0066) (xy 1.016 2.3114) (xy -1.016 2.3114)
			)
			(stroke
				(width 0)
				(type default)
			)
			(fill no)
			(layer "F.Fab")
		)
		(pad "A" smd rect
			(at 0 -1.143)
			(size 0.5588 1.016)
			(layers "F.Cu" "F.Mask" "F.Paste")
			(net "SW_SSD5_R")
		)
		(pad "K" smd rect
			(at 0 1.143)
			(size 0.5588 1.016)
			(layers "F.Cu" "F.Mask" "F.Paste")
			(net "SW_SSD5_N")
		)
	)
	(footprint ""
		(layer "F.Cu")
		(at 27.178 -419.735 180)
		(property "Reference" "PC1180"
			(at 0 0 180)
			(layer "F.SilkS")
			(hide yes)
			(effects
				(font
					(size 1.27 1.27)
				)
			)
		)
		(property "Value" "SC22U25V6KX-GP-U"
			(at -2.860802 -5.279644 180)
			(unlocked yes)
			(layer "F.Fab")
			(hide yes)
			(effects
				(font
					(size 1.016 1.016)
					(thickness 0.1524)
				)
			)
		)
		(property "Device Type" "C1206-TO0D3H75"
			(at -2.860802 -6.803644 180)
			(unlocked yes)
			(layer "F.Fab")
			(hide yes)
			(effects
				(font
					(size 1.016 1.016)
					(thickness 0.1524)
				)
			)
		)
		(duplicate_pad_numbers_are_jumpers no)
		(fp_line
			(start 1.3081 2.3749)
			(end -1.3081 2.3749)
			(stroke
				(width 0.1524)
				(type default)
			)
			(layer "F.SilkS")
		)
		(fp_line
			(start 1.3081 -2.3749)
			(end 1.3081 2.3749)
			(stroke
				(width 0.1524)
				(type default)
			)
			(layer "F.SilkS")
		)
		(fp_line
			(start -1.3081 2.3749)
			(end -1.3081 -2.3749)
			(stroke
				(width 0.1524)
				(type default)
			)
			(layer "F.SilkS")
		)
		(fp_line
			(start -1.3081 -2.3749)
			(end 1.3081 -2.3749)
			(stroke
				(width 0.1524)
				(type default)
			)
			(layer "F.SilkS")
		)
		(fp_rect
			(start -0.8001 1.6002)
			(end 0.8001 -1.6002)
			(stroke
				(width 0)
				(type default)
			)
			(fill no)
			(layer "F.CrtYd")
		)
		(fp_poly
			(pts
				(xy -1.5621 2.4511) (xy -1.5621 1.6002) (xy 0.8001 1.6002) (xy 0.8001 -1.6002) (xy -0.8001 -1.6002)
				(xy -0.8001 1.5875) (xy -1.5621 1.5875) (xy -1.5621 -2.4511) (xy 1.5621 -2.4511) (xy 1.5621 2.4511)
			)
			(stroke
				(width 0)
				(type default)
			)
			(fill no)
			(layer "F.CrtYd")
		)
		(fp_rect
			(start -1.5621 2.4511)
			(end 1.5621 -2.4511)
			(stroke
				(width 0)
				(type default)
			)
			(fill no)
			(layer "F.Fab")
		)
		(pad "1" smd rect
			(at 0 -1.392936 180)
			(size 2.1082 1.4478)
			(layers "F.Cu" "F.Mask" "F.Paste")
			(net "P12V_SSD10")
		)
		(pad "2" smd rect
			(at 0 1.392936 180)
			(size 2.1082 1.4478)
			(layers "F.Cu" "F.Mask" "F.Paste")
			(net "GND")
		)
	)
	(footprint ""
		(layer "F.Cu")
		(at 16.129 -164.332158)
		(property "Reference" "Q93"
			(at 0 0 0)
			(layer "F.SilkS")
			(hide yes)
			(effects
				(font
					(size 1.27 1.27)
				)
			)
		)
		(property "Value" "2N7002A-7-GP"
			(at 0.127 -8.9662 0)
			(unlocked yes)
			(layer "F.Fab")
			(hide yes)
			(effects
				(font
					(size 1.016 1.016)
					(thickness 0.1524)
				)
			)
		)
		(property "Device Type" "SOT23DGS2D4H48"
			(at 0.127 -10.4902 0)
			(unlocked yes)
			(layer "F.Fab")
			(hide yes)
			(effects
				(font
					(size 1.016 1.016)
					(thickness 0.1524)
				)
			)
		)
		(duplicate_pad_numbers_are_jumpers no)
		(fp_line
			(start -1.651 -1.778)
			(end -1.651 1.778)
			(stroke
				(width 0.1524)
				(type default)
			)
			(layer "F.SilkS")
		)
		(fp_line
			(start -1.651 1.778)
			(end 1.651 1.778)
			(stroke
				(width 0.1524)
				(type default)
			)
			(layer "F.SilkS")
		)
		(fp_line
			(start 1.651 -1.778)
			(end -1.651 -1.778)
			(stroke
				(width 0.1524)
				(type default)
			)
			(layer "F.SilkS")
		)
		(fp_line
			(start 1.651 1.778)
			(end 1.651 -1.778)
			(stroke
				(width 0.1524)
				(type default)
			)
			(layer "F.SilkS")
		)
		(fp_poly
			(pts
				(xy -1.778 1.8796) (xy -1.778 -1.8796) (xy 1.778 -1.8796) (xy 1.778 1.8796)
			)
			(stroke
				(width 0)
				(type default)
			)
			(fill no)
			(layer "F.CrtYd")
		)
		(fp_poly
			(pts
				(xy -1.778 1.8796) (xy -1.778 -1.8796) (xy 1.778 -1.8796) (xy 1.778 1.8796)
			)
			(stroke
				(width 0)
				(type default)
			)
			(fill no)
			(layer "F.Fab")
		)
		(pad "D" smd custom
			(at 0 -0.9525)
			(size 0.1905 0.1905)
			(layers "F.Cu" "F.Mask" "F.Paste")
			(net "SSD_ACT_DR13_MOS_N")
			(options
				(clearance outline)
				(anchor circle)
			)
			(primitives
				(gr_poly
					(pts
						(arc
							(start -0.1778 0.5715)
							(mid -0.321484 0.511984)
							(end -0.381 0.3683)
						)
						(arc
							(start -0.381 -0.3683)
							(mid -0.321484 -0.511984)
							(end -0.1778 -0.5715)
						)
						(arc
							(start 0.1778 -0.5715)
							(mid 0.321484 -0.511984)
							(end 0.381 -0.3683)
						)
						(arc
							(start 0.381 0.3683)
							(mid 0.321484 0.511984)
							(end 0.1778 0.5715)
						)
					)
					(width 0)
					(fill yes)
				)
			)
		)
		(pad "G" smd custom
			(at -0.98425 0.9525)
			(size 0.1905 0.1905)
			(layers "F.Cu" "F.Mask" "F.Paste")
			(net "ATTN_LED_DR13_AND_R")
			(options
				(clearance outline)
				(anchor circle)
			)
			(primitives
				(gr_poly
					(pts
						(arc
							(start -0.1778 0.5715)
							(mid -0.321484 0.511984)
							(end -0.381 0.3683)
						)
						(arc
							(start -0.381 -0.3683)
							(mid -0.321484 -0.511984)
							(end -0.1778 -0.5715)
						)
						(arc
							(start 0.1778 -0.5715)
							(mid 0.321484 -0.511984)
							(end 0.381 -0.3683)
						)
						(arc
							(start 0.381 0.3683)
							(mid 0.321484 0.511984)
							(end 0.1778 0.5715)
						)
					)
					(width 0)
					(fill yes)
				)
			)
		)
		(pad "S" smd custom
			(at 0.98425 0.9525)
			(size 0.1905 0.1905)
			(layers "F.Cu" "F.Mask" "F.Paste")
			(net "SSD_ACT_DR13_R")
			(options
				(clearance outline)
				(anchor circle)
			)
			(primitives
				(gr_poly
					(pts
						(arc
							(start -0.1778 0.5715)
							(mid -0.321484 0.511984)
							(end -0.381 0.3683)
						)
						(arc
							(start -0.381 -0.3683)
							(mid -0.321484 -0.511984)
							(end -0.1778 -0.5715)
						)
						(arc
							(start 0.1778 -0.5715)
							(mid 0.321484 -0.511984)
							(end 0.381 -0.3683)
						)
						(arc
							(start 0.381 0.3683)
							(mid 0.321484 0.511984)
							(end 0.1778 0.5715)
						)
					)
					(width 0)
					(fill yes)
				)
			)
		)
	)
	(footprint ""
		(layer "F.Cu")
		(at 224.964752 -346.7608 90)
		(property "Reference" "R9788"
			(at 0 0 90)
			(layer "F.SilkS")
			(hide yes)
			(effects
				(font
					(size 1.27 1.27)
				)
			)
		)
		(property "Value" "0R2J-2-GP"
			(at 0.064008 -3.993896 90)
			(unlocked yes)
			(layer "F.Fab")
			(hide yes)
			(effects
				(font
					(size 1.016 1.016)
					(thickness 0.1524)
				)
			)
		)
		(property "Device Type" "R402H16"
			(at 0.064008 -5.517896 90)
			(unlocked yes)
			(layer "F.Fab")
			(hide yes)
			(effects
				(font
					(size 1.016 1.016)
					(thickness 0.1524)
				)
			)
		)
		(duplicate_pad_numbers_are_jumpers no)
		(fp_line
			(start 0.508 -0.9398)
			(end -0.508 -0.9398)
			(stroke
				(width 0.1524)
				(type default)
			)
			(layer "F.SilkS")
		)
		(fp_line
			(start -0.508 -0.9398)
			(end -0.508 0.9398)
			(stroke
				(width 0.1524)
				(type default)
			)
			(layer "F.SilkS")
		)
		(fp_rect
			(start -0.508 0.9398)
			(end 0.508 -0.9398)
			(stroke
				(width 0)
				(type default)
			)
			(fill no)
			(layer "F.CrtYd")
		)
		(fp_rect
			(start -0.508 0.9398)
			(end 0.508 -0.9398)
			(stroke
				(width 0)
				(type default)
			)
			(fill no)
			(layer "F.Fab")
		)
		(pad "1" smd custom
			(at 0 -0.4445 90)
			(size 0.1397 0.1397)
			(layers "F.Cu" "F.Mask" "F.Paste")
			(net "ATTN_LED_DR1_R")
			(options
				(clearance outline)
				(anchor circle)
			)
			(primitives
				(gr_poly
					(pts
						(arc
							(start -0.1778 -0.2794)
							(mid -0.249642 -0.249642)
							(end -0.2794 -0.1778)
						)
						(arc
							(start -0.2794 0.1778)
							(mid -0.249642 0.249642)
							(end -0.1778 0.2794)
						)
						(arc
							(start 0.1778 0.2794)
							(mid 0.249642 0.249642)
							(end 0.2794 0.1778)
						)
						(arc
							(start 0.2794 -0.1778)
							(mid 0.249642 -0.249642)
							(end 0.1778 -0.2794)
						)
					)
					(width 0)
					(fill yes)
				)
			)
		)
		(pad "2" smd custom
			(at 0 0.4445 90)
			(size 0.1397 0.1397)
			(layers "F.Cu" "F.Mask" "F.Paste")
			(net "ATTN_LED_DR1_N")
			(options
				(clearance outline)
				(anchor circle)
			)
			(primitives
				(gr_poly
					(pts
						(arc
							(start -0.1778 -0.2794)
							(mid -0.249642 -0.249642)
							(end -0.2794 -0.1778)
						)
						(arc
							(start -0.2794 0.1778)
							(mid -0.249642 0.249642)
							(end -0.1778 0.2794)
						)
						(arc
							(start 0.1778 0.2794)
							(mid 0.249642 0.249642)
							(end 0.2794 0.1778)
						)
						(arc
							(start 0.2794 -0.1778)
							(mid 0.249642 -0.249642)
							(end 0.1778 -0.2794)
						)
					)
					(width 0)
					(fill yes)
				)
			)
		)
	)
	(footprint ""
		(layer "F.Cu")
		(at 88.011 -416.814 -90)
		(property "Reference" "R123"
			(at 0 0 270)
			(layer "F.SilkS")
			(hide yes)
			(effects
				(font
					(size 1.27 1.27)
				)
			)
		)
		(property "Value" "4K7R2J-2-GP"
			(at 0.064008 -3.993896 270)
			(unlocked yes)
			(layer "F.Fab")
			(hide yes)
			(effects
				(font
					(size 1.016 1.016)
					(thickness 0.1524)
				)
			)
		)
		(property "Device Type" "R402H16"
			(at 0.064008 -5.517896 270)
			(unlocked yes)
			(layer "F.Fab")
			(hide yes)
			(effects
				(font
					(size 1.016 1.016)
					(thickness 0.1524)
				)
			)
		)
		(duplicate_pad_numbers_are_jumpers no)
		(fp_line
			(start -0.508 -0.9398)
			(end -0.508 0.9398)
			(stroke
				(width 0.1524)
				(type default)
			)
			(layer "F.SilkS")
		)
		(fp_line
			(start 0.508 -0.9398)
			(end -0.508 -0.9398)
			(stroke
				(width 0.1524)
				(type default)
			)
			(layer "F.SilkS")
		)
		(fp_rect
			(start -0.508 0.9398)
			(end 0.508 -0.9398)
			(stroke
				(width 0)
				(type default)
			)
			(fill no)
			(layer "F.CrtYd")
		)
		(fp_rect
			(start -0.508 0.9398)
			(end 0.508 -0.9398)
			(stroke
				(width 0)
				(type default)
			)
			(fill no)
			(layer "F.Fab")
		)
		(pad "1" smd custom
			(at 0 -0.4445 270)
			(size 0.1397 0.1397)
			(layers "F.Cu" "F.Mask" "F.Paste")
			(net "P3V3")
			(options
				(clearance outline)
				(anchor circle)
			)
			(primitives
				(gr_poly
					(pts
						(arc
							(start -0.1778 -0.2794)
							(mid -0.249642 -0.249642)
							(end -0.2794 -0.1778)
						)
						(arc
							(start -0.2794 0.1778)
							(mid -0.249642 0.249642)
							(end -0.1778 0.2794)
						)
						(arc
							(start 0.1778 0.2794)
							(mid 0.249642 0.249642)
							(end 0.2794 0.1778)
						)
						(arc
							(start 0.2794 -0.1778)
							(mid 0.249642 -0.249642)
							(end 0.1778 -0.2794)
						)
					)
					(width 0)
					(fill yes)
				)
			)
		)
		(pad "2" smd custom
			(at 0 0.4445 270)
			(size 0.1397 0.1397)
			(layers "F.Cu" "F.Mask" "F.Paste")
			(net "SSD_PRSNT_NET10")
			(options
				(clearance outline)
				(anchor circle)
			)
			(primitives
				(gr_poly
					(pts
						(arc
							(start -0.1778 -0.2794)
							(mid -0.249642 -0.249642)
							(end -0.2794 -0.1778)
						)
						(arc
							(start -0.2794 0.1778)
							(mid -0.249642 0.249642)
							(end -0.1778 0.2794)
						)
						(arc
							(start 0.1778 0.2794)
							(mid 0.249642 0.249642)
							(end 0.2794 0.1778)
						)
						(arc
							(start 0.2794 -0.1778)
							(mid 0.249642 -0.249642)
							(end 0.1778 -0.2794)
						)
					)
					(width 0)
					(fill yes)
				)
			)
		)
	)
	(footprint ""
		(layer "F.Cu")
		(at 79.121 -437.4134 90)
		(property "Reference" "FB6"
			(at 0 0 90)
			(layer "F.SilkS")
			(hide yes)
			(effects
				(font
					(size 1.27 1.27)
				)
			)
		)
		(property "Value" "BLM21PG331SN1D-2-GP"
			(at 0 -4.2418 90)
			(unlocked yes)
			(layer "F.Fab")
			(hide yes)
			(effects
				(font
					(size 1.016 1.016)
					(thickness 0.1524)
				)
			)
		)
		(property "Device Type" "L805H42"
			(at 0 -5.7912 90)
			(unlocked yes)
			(layer "F.Fab")
			(hide yes)
			(effects
				(font
					(size 1.016 1.016)
					(thickness 0.1524)
				)
			)
		)
		(duplicate_pad_numbers_are_jumpers no)
		(fp_line
			(start 0.889 -1.7018)
			(end 0.889 1.7018)
			(stroke
				(width 0.1524)
				(type default)
			)
			(layer "F.SilkS")
		)
		(fp_line
			(start -0.889 -1.7018)
			(end 0.889 -1.7018)
			(stroke
				(width 0.1524)
				(type default)
			)
			(layer "F.SilkS")
		)
		(fp_line
			(start 0.889 1.7018)
			(end -0.889 1.7018)
			(stroke
				(width 0.1524)
				(type default)
			)
			(layer "F.SilkS")
		)
		(fp_line
			(start -0.889 1.7018)
			(end -0.889 -1.7018)
			(stroke
				(width 0.1524)
				(type default)
			)
			(layer "F.SilkS")
		)
		(fp_rect
			(start -0.9652 1.778)
			(end 0.9652 -1.778)
			(stroke
				(width 0)
				(type default)
			)
			(fill no)
			(layer "F.CrtYd")
		)
		(fp_rect
			(start -0.9652 1.778)
			(end 0.9652 -1.778)
			(stroke
				(width 0)
				(type default)
			)
			(fill no)
			(layer "F.Fab")
		)
		(pad "1" smd rect
			(at 0 -0.9652 90)
			(size 1.397 1.143)
			(layers "F.Cu" "F.Mask" "F.Paste")
			(net "P3V3")
		)
		(pad "2" smd rect
			(at 0 0.9652 90)
			(size 1.397 1.143)
			(layers "F.Cu" "F.Mask" "F.Paste")
			(net "VDD_DIFF_1")
		)
	)
	(footprint ""
		(layer "F.Cu")
		(at 13.208 -478.155 180)
		(property "Reference" "R411"
			(at 0 0 180)
			(layer "F.SilkS")
			(hide yes)
			(effects
				(font
					(size 1.27 1.27)
				)
			)
		)
		(property "Value" "100R2J-2-GP"
			(at 0.064008 -3.993896 180)
			(unlocked yes)
			(layer "F.Fab")
			(hide yes)
			(effects
				(font
					(size 1.016 1.016)
					(thickness 0.1524)
				)
			)
		)
		(property "Device Type" "R402H14"
			(at 0.064008 -5.517896 180)
			(unlocked yes)
			(layer "F.Fab")
			(hide yes)
			(effects
				(font
					(size 1.016 1.016)
					(thickness 0.1524)
				)
			)
		)
		(duplicate_pad_numbers_are_jumpers no)
		(fp_line
			(start 0.508 -0.9398)
			(end -0.508 -0.9398)
			(stroke
				(width 0.1524)
				(type default)
			)
			(layer "F.SilkS")
		)
		(fp_line
			(start -0.508 -0.9398)
			(end -0.508 0.9398)
			(stroke
				(width 0.1524)
				(type default)
			)
			(layer "F.SilkS")
		)
		(fp_rect
			(start -0.508 0.9398)
			(end 0.508 -0.9398)
			(stroke
				(width 0)
				(type default)
			)
			(fill no)
			(layer "F.CrtYd")
		)
		(fp_rect
			(start -0.508 0.9398)
			(end 0.508 -0.9398)
			(stroke
				(width 0)
				(type default)
			)
			(fill no)
			(layer "F.Fab")
		)
		(pad "1" smd custom
			(at 0 -0.4445 180)
			(size 0.1397 0.1397)
			(layers "F.Cu" "F.Mask" "F.Paste")
			(net "DPB_HW_REVISION")
			(options
				(clearance outline)
				(anchor circle)
			)
			(primitives
				(gr_poly
					(pts
						(arc
							(start -0.1778 -0.2794)
							(mid -0.249642 -0.249642)
							(end -0.2794 -0.1778)
						)
						(arc
							(start -0.2794 0.1778)
							(mid -0.249642 0.249642)
							(end -0.1778 0.2794)
						)
						(arc
							(start 0.1778 0.2794)
							(mid 0.249642 0.249642)
							(end 0.2794 0.1778)
						)
						(arc
							(start 0.2794 -0.1778)
							(mid 0.249642 -0.249642)
							(end 0.1778 -0.2794)
						)
					)
					(width 0)
					(fill yes)
				)
			)
		)
		(pad "2" smd custom
			(at 0 0.4445 180)
			(size 0.1397 0.1397)
			(layers "F.Cu" "F.Mask" "F.Paste")
			(net "GND")
			(options
				(clearance outline)
				(anchor circle)
			)
			(primitives
				(gr_poly
					(pts
						(arc
							(start -0.1778 -0.2794)
							(mid -0.249642 -0.249642)
							(end -0.2794 -0.1778)
						)
						(arc
							(start -0.2794 0.1778)
							(mid -0.249642 0.249642)
							(end -0.1778 0.2794)
						)
						(arc
							(start 0.1778 0.2794)
							(mid 0.249642 0.249642)
							(end 0.2794 0.1778)
						)
						(arc
							(start 0.2794 -0.1778)
							(mid 0.249642 -0.249642)
							(end 0.1778 -0.2794)
						)
					)
					(width 0)
					(fill yes)
				)
			)
		)
	)
	(footprint ""
		(layer "F.Cu")
		(at 23.1648 -87.122)
		(property "Reference" "R560"
			(at 0 0 0)
			(layer "F.SilkS")
			(hide yes)
			(effects
				(font
					(size 1.27 1.27)
				)
			)
		)
		(property "Value" "200KR2F-L-GP"
			(at 0.064008 -3.993896 0)
			(unlocked yes)
			(layer "F.Fab")
			(hide yes)
			(effects
				(font
					(size 1.016 1.016)
					(thickness 0.1524)
				)
			)
		)
		(property "Device Type" "R402H16"
			(at 0.064008 -5.517896 0)
			(unlocked yes)
			(layer "F.Fab")
			(hide yes)
			(effects
				(font
					(size 1.016 1.016)
					(thickness 0.1524)
				)
			)
		)
		(duplicate_pad_numbers_are_jumpers no)
		(fp_line
			(start -0.508 -0.9398)
			(end -0.508 0.9398)
			(stroke
				(width 0.1524)
				(type default)
			)
			(layer "F.SilkS")
		)
		(fp_line
			(start 0.508 -0.9398)
			(end -0.508 -0.9398)
			(stroke
				(width 0.1524)
				(type default)
			)
			(layer "F.SilkS")
		)
		(fp_rect
			(start -0.508 0.9398)
			(end 0.508 -0.9398)
			(stroke
				(width 0)
				(type default)
			)
			(fill no)
			(layer "F.CrtYd")
		)
		(fp_rect
			(start -0.508 0.9398)
			(end 0.508 -0.9398)
			(stroke
				(width 0)
				(type default)
			)
			(fill no)
			(layer "F.Fab")
		)
		(pad "1" smd custom
			(at 0 -0.4445)
			(size 0.1397 0.1397)
			(layers "F.Cu" "F.Mask" "F.Paste")
			(net "SW_SSD9_R")
			(options
				(clearance outline)
				(anchor circle)
			)
			(primitives
				(gr_poly
					(pts
						(arc
							(start -0.1778 -0.2794)
							(mid -0.249642 -0.249642)
							(end -0.2794 -0.1778)
						)
						(arc
							(start -0.2794 0.1778)
							(mid -0.249642 0.249642)
							(end -0.1778 0.2794)
						)
						(arc
							(start 0.1778 0.2794)
							(mid 0.249642 0.249642)
							(end 0.2794 0.1778)
						)
						(arc
							(start 0.2794 -0.1778)
							(mid 0.249642 -0.249642)
							(end 0.1778 -0.2794)
						)
					)
					(width 0)
					(fill yes)
				)
			)
		)
		(pad "2" smd custom
			(at 0 0.4445)
			(size 0.1397 0.1397)
			(layers "F.Cu" "F.Mask" "F.Paste")
			(net "SW_SSD9_N")
			(options
				(clearance outline)
				(anchor circle)
			)
			(primitives
				(gr_poly
					(pts
						(arc
							(start -0.1778 -0.2794)
							(mid -0.249642 -0.249642)
							(end -0.2794 -0.1778)
						)
						(arc
							(start -0.2794 0.1778)
							(mid -0.249642 0.249642)
							(end -0.1778 0.2794)
						)
						(arc
							(start 0.1778 0.2794)
							(mid 0.249642 0.249642)
							(end 0.2794 0.1778)
						)
						(arc
							(start 0.2794 -0.1778)
							(mid 0.249642 -0.249642)
							(end 0.1778 -0.2794)
						)
					)
					(width 0)
					(fill yes)
				)
			)
		)
	)
	(footprint ""
		(layer "F.Cu")
		(at 43.282108 -346.706952 180)
		(property "Reference" "SR1134"
			(at 0 0 180)
			(layer "F.SilkS")
			(hide yes)
			(effects
				(font
					(size 1.27 1.27)
				)
			)
		)
		(property "Value" "4K7R2J-2-GP"
			(at 0.064008 -3.993896 180)
			(unlocked yes)
			(layer "F.Fab")
			(hide yes)
			(effects
				(font
					(size 1.016 1.016)
					(thickness 0.1524)
				)
			)
		)
		(property "Device Type" "R402H16"
			(at 0.064008 -5.517896 180)
			(unlocked yes)
			(layer "F.Fab")
			(hide yes)
			(effects
				(font
					(size 1.016 1.016)
					(thickness 0.1524)
				)
			)
		)
		(duplicate_pad_numbers_are_jumpers no)
		(fp_line
			(start 0.508 -0.9398)
			(end -0.508 -0.9398)
			(stroke
				(width 0.1524)
				(type default)
			)
			(layer "F.SilkS")
		)
		(fp_line
			(start -0.508 -0.9398)
			(end -0.508 0.9398)
			(stroke
				(width 0.1524)
				(type default)
			)
			(layer "F.SilkS")
		)
		(fp_rect
			(start -0.508 0.9398)
			(end 0.508 -0.9398)
			(stroke
				(width 0)
				(type default)
			)
			(fill no)
			(layer "F.CrtYd")
		)
		(fp_rect
			(start -0.508 0.9398)
			(end 0.508 -0.9398)
			(stroke
				(width 0)
				(type default)
			)
			(fill no)
			(layer "F.Fab")
		)
		(pad "1" smd custom
			(at 0 -0.4445 180)
			(size 0.1397 0.1397)
			(layers "F.Cu" "F.Mask" "F.Paste")
			(net "P3V3")
			(options
				(clearance outline)
				(anchor circle)
			)
			(primitives
				(gr_poly
					(pts
						(arc
							(start -0.1778 -0.2794)
							(mid -0.249642 -0.249642)
							(end -0.2794 -0.1778)
						)
						(arc
							(start -0.2794 0.1778)
							(mid -0.249642 0.249642)
							(end -0.1778 0.2794)
						)
						(arc
							(start 0.1778 0.2794)
							(mid 0.249642 0.249642)
							(end 0.2794 0.1778)
						)
						(arc
							(start 0.2794 -0.1778)
							(mid 0.249642 -0.249642)
							(end 0.1778 -0.2794)
						)
					)
					(width 0)
					(fill yes)
				)
			)
		)
		(pad "2" smd custom
			(at 0 0.4445 180)
			(size 0.1397 0.1397)
			(layers "F.Cu" "F.Mask" "F.Paste")
			(net "SSD_ACT_DR6")
			(options
				(clearance outline)
				(anchor circle)
			)
			(primitives
				(gr_poly
					(pts
						(arc
							(start -0.1778 -0.2794)
							(mid -0.249642 -0.249642)
							(end -0.2794 -0.1778)
						)
						(arc
							(start -0.2794 0.1778)
							(mid -0.249642 0.249642)
							(end -0.1778 0.2794)
						)
						(arc
							(start 0.1778 0.2794)
							(mid 0.249642 0.249642)
							(end 0.2794 0.1778)
						)
						(arc
							(start 0.2794 -0.1778)
							(mid 0.249642 -0.249642)
							(end 0.1778 -0.2794)
						)
					)
					(width 0)
					(fill yes)
				)
			)
		)
	)
	(footprint ""
		(layer "F.Cu")
		(at 68.49999 -378.499878)
		(property "Reference" "H3"
			(at 0 0 0)
			(layer "F.SilkS")
			(hide yes)
			(effects
				(font
					(size 1.27 1.27)
				)
			)
		)
		(property "Value" "HOLE315R140-GP"
			(at 0 -7.5692 0)
			(unlocked yes)
			(layer "F.Fab")
			(hide yes)
			(effects
				(font
					(size 1.016 1.016)
					(thickness 0.1524)
				)
			)
		)
		(property "Device Type" "HOLE315R140"
			(at 0 -9.0932 0)
			(unlocked yes)
			(layer "F.Fab")
			(hide yes)
			(effects
				(font
					(size 1.016 1.016)
					(thickness 0.1524)
				)
			)
		)
		(duplicate_pad_numbers_are_jumpers no)
		(fp_poly
			(pts
				(arc
					(start 4.3053 0)
					(mid -4.3053 0)
					(end 4.3053 0)
				)
			)
			(stroke
				(width 0)
				(type default)
			)
			(fill no)
			(layer "F.CrtYd")
		)
		(fp_poly
			(pts
				(arc
					(start 4.3053 0)
					(mid -4.3053 0)
					(end 4.3053 0)
				)
			)
			(stroke
				(width 0)
				(type default)
			)
			(fill no)
			(layer "F.Fab")
		)
		(pad "1" thru_hole circle
			(at 0.00127 0.00127)
			(size 8.001 8.001)
			(drill 3.556)
			(layers "*.Cu" "*.Mask")
			(remove_unused_layers no)
			(net "GND")
			(clearance -1.7145)
			(thermal_gap 0.3048)
			(padstack
				(mode front_inner_back)
				(layer "Inner"
					(shape circle)
					(size 3.9624 3.9624)
					(clearance 0.3048)
				)
				(layer "B.Cu"
					(shape circle)
					(size 8.001 8.001)
					(clearance -1.7145)
				)
			)
		)
	)
	(footprint ""
		(layer "F.Cu")
		(at 102.616 -438.15 90)
		(property "Reference" "R9056"
			(at 0 0 90)
			(layer "F.SilkS")
			(hide yes)
			(effects
				(font
					(size 1.27 1.27)
				)
			)
		)
		(property "Value" "27R2F-GP"
			(at 0.064008 -3.993896 90)
			(unlocked yes)
			(layer "F.Fab")
			(hide yes)
			(effects
				(font
					(size 1.016 1.016)
					(thickness 0.1524)
				)
			)
		)
		(property "Device Type" "R402H16"
			(at 0.064008 -5.517896 90)
			(unlocked yes)
			(layer "F.Fab")
			(hide yes)
			(effects
				(font
					(size 1.016 1.016)
					(thickness 0.1524)
				)
			)
		)
		(duplicate_pad_numbers_are_jumpers no)
		(fp_line
			(start 0.508 -0.9398)
			(end -0.508 -0.9398)
			(stroke
				(width 0.1524)
				(type default)
			)
			(layer "F.SilkS")
		)
		(fp_line
			(start -0.508 -0.9398)
			(end -0.508 0.9398)
			(stroke
				(width 0.1524)
				(type default)
			)
			(layer "F.SilkS")
		)
		(fp_rect
			(start -0.508 0.9398)
			(end 0.508 -0.9398)
			(stroke
				(width 0)
				(type default)
			)
			(fill no)
			(layer "F.CrtYd")
		)
		(fp_rect
			(start -0.508 0.9398)
			(end 0.508 -0.9398)
			(stroke
				(width 0)
				(type default)
			)
			(fill no)
			(layer "F.Fab")
		)
		(pad "1" smd custom
			(at 0 -0.4445 90)
			(size 0.1397 0.1397)
			(layers "F.Cu" "F.Mask" "F.Paste")
			(net "PE_CLK_100M_DR0_1_R_N")
			(options
				(clearance outline)
				(anchor circle)
			)
			(primitives
				(gr_poly
					(pts
						(arc
							(start -0.1778 -0.2794)
							(mid -0.249642 -0.249642)
							(end -0.2794 -0.1778)
						)
						(arc
							(start -0.2794 0.1778)
							(mid -0.249642 0.249642)
							(end -0.1778 0.2794)
						)
						(arc
							(start 0.1778 0.2794)
							(mid 0.249642 0.249642)
							(end 0.2794 0.1778)
						)
						(arc
							(start 0.2794 -0.1778)
							(mid 0.249642 -0.249642)
							(end 0.1778 -0.2794)
						)
					)
					(width 0)
					(fill yes)
				)
			)
		)
		(pad "2" smd custom
			(at 0 0.4445 90)
			(size 0.1397 0.1397)
			(layers "F.Cu" "F.Mask" "F.Paste")
			(net "PE_CLK100M_DR0_1_N")
			(options
				(clearance outline)
				(anchor circle)
			)
			(primitives
				(gr_poly
					(pts
						(arc
							(start -0.1778 -0.2794)
							(mid -0.249642 -0.249642)
							(end -0.2794 -0.1778)
						)
						(arc
							(start -0.2794 0.1778)
							(mid -0.249642 0.249642)
							(end -0.1778 0.2794)
						)
						(arc
							(start 0.1778 0.2794)
							(mid 0.249642 0.249642)
							(end 0.2794 0.1778)
						)
						(arc
							(start 0.2794 -0.1778)
							(mid 0.249642 -0.249642)
							(end 0.1778 -0.2794)
						)
					)
					(width 0)
					(fill yes)
				)
			)
		)
	)
	(footprint ""
		(layer "F.Cu")
		(at 81.661 -359.029 -90)
		(property "Reference" "SR993"
			(at 0 0 270)
			(layer "F.SilkS")
			(hide yes)
			(effects
				(font
					(size 1.27 1.27)
				)
			)
		)
		(property "Value" "2KR2F-3-GP"
			(at 0.064008 -3.993896 270)
			(unlocked yes)
			(layer "F.Fab")
			(hide yes)
			(effects
				(font
					(size 1.016 1.016)
					(thickness 0.1524)
				)
			)
		)
		(property "Device Type" "R402H16"
			(at 0.064008 -5.517896 270)
			(unlocked yes)
			(layer "F.Fab")
			(hide yes)
			(effects
				(font
					(size 1.016 1.016)
					(thickness 0.1524)
				)
			)
		)
		(duplicate_pad_numbers_are_jumpers no)
		(fp_line
			(start -0.508 -0.9398)
			(end -0.508 0.9398)
			(stroke
				(width 0.1524)
				(type default)
			)
			(layer "F.SilkS")
		)
		(fp_line
			(start 0.508 -0.9398)
			(end -0.508 -0.9398)
			(stroke
				(width 0.1524)
				(type default)
			)
			(layer "F.SilkS")
		)
		(fp_rect
			(start -0.508 0.9398)
			(end 0.508 -0.9398)
			(stroke
				(width 0)
				(type default)
			)
			(fill no)
			(layer "F.CrtYd")
		)
		(fp_rect
			(start -0.508 0.9398)
			(end 0.508 -0.9398)
			(stroke
				(width 0)
				(type default)
			)
			(fill no)
			(layer "F.Fab")
		)
		(pad "1" smd custom
			(at 0 -0.4445 270)
			(size 0.1397 0.1397)
			(layers "F.Cu" "F.Mask" "F.Paste")
			(net "P3V3")
			(options
				(clearance outline)
				(anchor circle)
			)
			(primitives
				(gr_poly
					(pts
						(arc
							(start -0.1778 -0.2794)
							(mid -0.249642 -0.249642)
							(end -0.2794 -0.1778)
						)
						(arc
							(start -0.2794 0.1778)
							(mid -0.249642 0.249642)
							(end -0.1778 0.2794)
						)
						(arc
							(start 0.1778 0.2794)
							(mid 0.249642 0.249642)
							(end 0.2794 0.1778)
						)
						(arc
							(start 0.2794 -0.1778)
							(mid 0.249642 -0.249642)
							(end 0.1778 -0.2794)
						)
					)
					(width 0)
					(fill yes)
				)
			)
		)
		(pad "2" smd custom
			(at 0 0.4445 270)
			(size 0.1397 0.1397)
			(layers "F.Cu" "F.Mask" "F.Paste")
			(net "SCL_DR2")
			(options
				(clearance outline)
				(anchor circle)
			)
			(primitives
				(gr_poly
					(pts
						(arc
							(start -0.1778 -0.2794)
							(mid -0.249642 -0.249642)
							(end -0.2794 -0.1778)
						)
						(arc
							(start -0.2794 0.1778)
							(mid -0.249642 0.249642)
							(end -0.1778 0.2794)
						)
						(arc
							(start 0.1778 0.2794)
							(mid 0.249642 0.249642)
							(end 0.2794 0.1778)
						)
						(arc
							(start 0.2794 -0.1778)
							(mid 0.249642 -0.249642)
							(end 0.1778 -0.2794)
						)
					)
					(width 0)
					(fill yes)
				)
			)
		)
	)
	(footprint ""
		(layer "F.Cu")
		(at 96.774 -320.167 90)
		(property "Reference" "R9502"
			(at 0 0 90)
			(layer "F.SilkS")
			(hide yes)
			(effects
				(font
					(size 1.27 1.27)
				)
			)
		)
		(property "Value" "4K7R2J-2-GP"
			(at 0.064008 -3.993896 90)
			(unlocked yes)
			(layer "F.Fab")
			(hide yes)
			(effects
				(font
					(size 1.016 1.016)
					(thickness 0.1524)
				)
			)
		)
		(property "Device Type" "R402H16"
			(at 0.064008 -5.517896 90)
			(unlocked yes)
			(layer "F.Fab")
			(hide yes)
			(effects
				(font
					(size 1.016 1.016)
					(thickness 0.1524)
				)
			)
		)
		(duplicate_pad_numbers_are_jumpers no)
		(fp_line
			(start 0.508 -0.9398)
			(end -0.508 -0.9398)
			(stroke
				(width 0.1524)
				(type default)
			)
			(layer "F.SilkS")
		)
		(fp_line
			(start -0.508 -0.9398)
			(end -0.508 0.9398)
			(stroke
				(width 0.1524)
				(type default)
			)
			(layer "F.SilkS")
		)
		(fp_rect
			(start -0.508 0.9398)
			(end 0.508 -0.9398)
			(stroke
				(width 0)
				(type default)
			)
			(fill no)
			(layer "F.CrtYd")
		)
		(fp_rect
			(start -0.508 0.9398)
			(end 0.508 -0.9398)
			(stroke
				(width 0)
				(type default)
			)
			(fill no)
			(layer "F.Fab")
		)
		(pad "1" smd custom
			(at 0 -0.4445 90)
			(size 0.1397 0.1397)
			(layers "F.Cu" "F.Mask" "F.Paste")
			(net "P3V3")
			(options
				(clearance outline)
				(anchor circle)
			)
			(primitives
				(gr_poly
					(pts
						(arc
							(start -0.1778 -0.2794)
							(mid -0.249642 -0.249642)
							(end -0.2794 -0.1778)
						)
						(arc
							(start -0.2794 0.1778)
							(mid -0.249642 0.249642)
							(end -0.1778 0.2794)
						)
						(arc
							(start 0.1778 0.2794)
							(mid 0.249642 0.249642)
							(end 0.2794 0.1778)
						)
						(arc
							(start 0.2794 -0.1778)
							(mid 0.249642 -0.249642)
							(end 0.1778 -0.2794)
						)
					)
					(width 0)
					(fill yes)
				)
			)
		)
		(pad "2" smd custom
			(at 0 0.4445 90)
			(size 0.1397 0.1397)
			(layers "F.Cu" "F.Mask" "F.Paste")
			(net "SSD6_CLK0_OE_N")
			(options
				(clearance outline)
				(anchor circle)
			)
			(primitives
				(gr_poly
					(pts
						(arc
							(start -0.1778 -0.2794)
							(mid -0.249642 -0.249642)
							(end -0.2794 -0.1778)
						)
						(arc
							(start -0.2794 0.1778)
							(mid -0.249642 0.249642)
							(end -0.1778 0.2794)
						)
						(arc
							(start 0.1778 0.2794)
							(mid 0.249642 0.249642)
							(end 0.2794 0.1778)
						)
						(arc
							(start 0.2794 -0.1778)
							(mid 0.249642 -0.249642)
							(end 0.1778 -0.2794)
						)
					)
					(width 0)
					(fill yes)
				)
			)
		)
	)
	(footprint ""
		(layer "F.Cu")
		(at 37.0332 -189.0014)
		(property "Reference" "PC1218"
			(at 0 0 0)
			(layer "F.SilkS")
			(hide yes)
			(effects
				(font
					(size 1.27 1.27)
				)
			)
		)
		(property "Value" "SCD01U50V2KX-1GP"
			(at 1.1811 -2.7051 0)
			(unlocked yes)
			(layer "F.Fab")
			(hide yes)
			(effects
				(font
					(size 1.016 1.016)
					(thickness 0.1524)
				)
			)
		)
		(property "Device Type" "C402H22"
			(at 1.1811 -4.2291 0)
			(unlocked yes)
			(layer "F.Fab")
			(hide yes)
			(effects
				(font
					(size 1.016 1.016)
					(thickness 0.1524)
				)
			)
		)
		(duplicate_pad_numbers_are_jumpers no)
		(fp_rect
			(start -0.4318 0.9525)
			(end 0.4318 -0.9525)
			(stroke
				(width 0)
				(type default)
			)
			(fill no)
			(layer "F.CrtYd")
		)
		(fp_rect
			(start -0.4318 0.9525)
			(end 0.4318 -0.9525)
			(stroke
				(width 0)
				(type default)
			)
			(fill no)
			(layer "F.Fab")
		)
		(pad "1" smd custom
			(at 0 -0.4445)
			(size 0.1524 0.1524)
			(layers "F.Cu" "F.Mask" "F.Paste")
			(net "P12V_SSD8")
			(options
				(clearance outline)
				(anchor circle)
			)
			(primitives
				(gr_poly
					(pts
						(arc
							(start 0.3048 -0.2032)
							(mid 0.275042 -0.275042)
							(end 0.2032 -0.3048)
						)
						(arc
							(start -0.2032 -0.3048)
							(mid -0.275042 -0.275042)
							(end -0.3048 -0.2032)
						)
						(arc
							(start -0.3048 0.2032)
							(mid -0.275042 0.275042)
							(end -0.2032 0.3048)
						)
						(arc
							(start 0.2032 0.3048)
							(mid 0.275042 0.275042)
							(end 0.3048 0.2032)
						)
					)
					(width 0)
					(fill yes)
				)
			)
		)
		(pad "2" smd custom
			(at 0 0.4445)
			(size 0.1524 0.1524)
			(layers "F.Cu" "F.Mask" "F.Paste")
			(net "GND")
			(options
				(clearance outline)
				(anchor circle)
			)
			(primitives
				(gr_poly
					(pts
						(arc
							(start 0.3048 -0.2032)
							(mid 0.275042 -0.275042)
							(end 0.2032 -0.3048)
						)
						(arc
							(start -0.2032 -0.3048)
							(mid -0.275042 -0.275042)
							(end -0.3048 -0.2032)
						)
						(arc
							(start -0.3048 0.2032)
							(mid -0.275042 0.275042)
							(end -0.2032 0.3048)
						)
						(arc
							(start 0.2032 0.3048)
							(mid 0.275042 0.275042)
							(end 0.3048 0.2032)
						)
					)
					(width 0)
					(fill yes)
				)
			)
		)
	)
	(footprint ""
		(layer "F.Cu")
		(at 215.7984 -495.2238 -90)
		(property "Reference" "SR1092"
			(at 0 0 270)
			(layer "F.SilkS")
			(hide yes)
			(effects
				(font
					(size 1.27 1.27)
				)
			)
		)
		(property "Value" "4K7R2F-GP"
			(at 0.064008 -3.993896 270)
			(unlocked yes)
			(layer "F.Fab")
			(hide yes)
			(effects
				(font
					(size 1.016 1.016)
					(thickness 0.1524)
				)
			)
		)
		(property "Device Type" "R402H16"
			(at 0.064008 -5.517896 270)
			(unlocked yes)
			(layer "F.Fab")
			(hide yes)
			(effects
				(font
					(size 1.016 1.016)
					(thickness 0.1524)
				)
			)
		)
		(duplicate_pad_numbers_are_jumpers no)
		(fp_line
			(start -0.508 -0.9398)
			(end -0.508 0.9398)
			(stroke
				(width 0.1524)
				(type default)
			)
			(layer "F.SilkS")
		)
		(fp_line
			(start 0.508 -0.9398)
			(end -0.508 -0.9398)
			(stroke
				(width 0.1524)
				(type default)
			)
			(layer "F.SilkS")
		)
		(fp_rect
			(start -0.508 0.9398)
			(end 0.508 -0.9398)
			(stroke
				(width 0)
				(type default)
			)
			(fill no)
			(layer "F.CrtYd")
		)
		(fp_rect
			(start -0.508 0.9398)
			(end 0.508 -0.9398)
			(stroke
				(width 0)
				(type default)
			)
			(fill no)
			(layer "F.Fab")
		)
		(pad "1" smd custom
			(at 0 -0.4445 270)
			(size 0.1397 0.1397)
			(layers "F.Cu" "F.Mask" "F.Paste")
			(net "DUALPORTEN#0")
			(options
				(clearance outline)
				(anchor circle)
			)
			(primitives
				(gr_poly
					(pts
						(arc
							(start -0.1778 -0.2794)
							(mid -0.249642 -0.249642)
							(end -0.2794 -0.1778)
						)
						(arc
							(start -0.2794 0.1778)
							(mid -0.249642 0.249642)
							(end -0.1778 0.2794)
						)
						(arc
							(start 0.1778 0.2794)
							(mid 0.249642 0.249642)
							(end 0.2794 0.1778)
						)
						(arc
							(start 0.2794 -0.1778)
							(mid 0.249642 -0.249642)
							(end 0.1778 -0.2794)
						)
					)
					(width 0)
					(fill yes)
				)
			)
		)
		(pad "2" smd custom
			(at 0 0.4445 270)
			(size 0.1397 0.1397)
			(layers "F.Cu" "F.Mask" "F.Paste")
			(net "GND")
			(options
				(clearance outline)
				(anchor circle)
			)
			(primitives
				(gr_poly
					(pts
						(arc
							(start -0.1778 -0.2794)
							(mid -0.249642 -0.249642)
							(end -0.2794 -0.1778)
						)
						(arc
							(start -0.2794 0.1778)
							(mid -0.249642 0.249642)
							(end -0.1778 0.2794)
						)
						(arc
							(start 0.1778 0.2794)
							(mid 0.249642 0.249642)
							(end 0.2794 0.1778)
						)
						(arc
							(start 0.2794 -0.1778)
							(mid 0.249642 -0.249642)
							(end 0.1778 -0.2794)
						)
					)
					(width 0)
					(fill yes)
				)
			)
		)
	)
	(footprint ""
		(layer "F.Cu")
		(at 234.061 -41.771062 -90)
		(property "Reference" "R9407"
			(at 0 0 270)
			(layer "F.SilkS")
			(hide yes)
			(effects
				(font
					(size 1.27 1.27)
				)
			)
		)
		(property "Value" "330R2F-GP"
			(at 0.064008 -3.993896 270)
			(unlocked yes)
			(layer "F.Fab")
			(hide yes)
			(effects
				(font
					(size 1.016 1.016)
					(thickness 0.1524)
				)
			)
		)
		(property "Device Type" "R402H16"
			(at 0.064008 -5.517896 270)
			(unlocked yes)
			(layer "F.Fab")
			(hide yes)
			(effects
				(font
					(size 1.016 1.016)
					(thickness 0.1524)
				)
			)
		)
		(duplicate_pad_numbers_are_jumpers no)
		(fp_line
			(start -0.508 -0.9398)
			(end -0.508 0.9398)
			(stroke
				(width 0.1524)
				(type default)
			)
			(layer "F.SilkS")
		)
		(fp_line
			(start 0.508 -0.9398)
			(end -0.508 -0.9398)
			(stroke
				(width 0.1524)
				(type default)
			)
			(layer "F.SilkS")
		)
		(fp_rect
			(start -0.508 0.9398)
			(end 0.508 -0.9398)
			(stroke
				(width 0)
				(type default)
			)
			(fill no)
			(layer "F.CrtYd")
		)
		(fp_rect
			(start -0.508 0.9398)
			(end 0.508 -0.9398)
			(stroke
				(width 0)
				(type default)
			)
			(fill no)
			(layer "F.Fab")
		)
		(pad "1" smd custom
			(at 0 -0.4445 270)
			(size 0.1397 0.1397)
			(layers "F.Cu" "F.Mask" "F.Paste")
			(net "P3V3")
			(options
				(clearance outline)
				(anchor circle)
			)
			(primitives
				(gr_poly
					(pts
						(arc
							(start -0.1778 -0.2794)
							(mid -0.249642 -0.249642)
							(end -0.2794 -0.1778)
						)
						(arc
							(start -0.2794 0.1778)
							(mid -0.249642 0.249642)
							(end -0.1778 0.2794)
						)
						(arc
							(start 0.1778 0.2794)
							(mid 0.249642 0.249642)
							(end 0.2794 0.1778)
						)
						(arc
							(start 0.2794 -0.1778)
							(mid 0.249642 -0.249642)
							(end 0.1778 -0.2794)
						)
					)
					(width 0)
					(fill yes)
				)
			)
		)
		(pad "2" smd custom
			(at 0 0.4445 270)
			(size 0.1397 0.1397)
			(layers "F.Cu" "F.Mask" "F.Paste")
			(net "DRV_ATTN_4")
			(options
				(clearance outline)
				(anchor circle)
			)
			(primitives
				(gr_poly
					(pts
						(arc
							(start -0.1778 -0.2794)
							(mid -0.249642 -0.249642)
							(end -0.2794 -0.1778)
						)
						(arc
							(start -0.2794 0.1778)
							(mid -0.249642 0.249642)
							(end -0.1778 0.2794)
						)
						(arc
							(start 0.1778 0.2794)
							(mid 0.249642 0.249642)
							(end 0.2794 0.1778)
						)
						(arc
							(start 0.2794 -0.1778)
							(mid 0.249642 -0.249642)
							(end 0.1778 -0.2794)
						)
					)
					(width 0)
					(fill yes)
				)
			)
		)
	)
	(footprint ""
		(layer "F.Cu")
		(at 98.679 -88.138 180)
		(property "Reference" "R9617"
			(at 0 0 180)
			(layer "F.SilkS")
			(hide yes)
			(effects
				(font
					(size 1.27 1.27)
				)
			)
		)
		(property "Value" "10R2F-L-GP"
			(at 0.064008 -3.993896 180)
			(unlocked yes)
			(layer "F.Fab")
			(hide yes)
			(effects
				(font
					(size 1.016 1.016)
					(thickness 0.1524)
				)
			)
		)
		(property "Device Type" "R402H14"
			(at 0.064008 -5.517896 180)
			(unlocked yes)
			(layer "F.Fab")
			(hide yes)
			(effects
				(font
					(size 1.016 1.016)
					(thickness 0.1524)
				)
			)
		)
		(duplicate_pad_numbers_are_jumpers no)
		(fp_line
			(start 0.508 -0.9398)
			(end -0.508 -0.9398)
			(stroke
				(width 0.1524)
				(type default)
			)
			(layer "F.SilkS")
		)
		(fp_line
			(start -0.508 -0.9398)
			(end -0.508 0.9398)
			(stroke
				(width 0.1524)
				(type default)
			)
			(layer "F.SilkS")
		)
		(fp_rect
			(start -0.508 0.9398)
			(end 0.508 -0.9398)
			(stroke
				(width 0)
				(type default)
			)
			(fill no)
			(layer "F.CrtYd")
		)
		(fp_rect
			(start -0.508 0.9398)
			(end 0.508 -0.9398)
			(stroke
				(width 0)
				(type default)
			)
			(fill no)
			(layer "F.Fab")
		)
		(pad "1" smd custom
			(at 0 -0.4445 180)
			(size 0.1397 0.1397)
			(layers "F.Cu" "F.Mask" "F.Paste")
			(net "SSD14_CLK0_OE_N")
			(options
				(clearance outline)
				(anchor circle)
			)
			(primitives
				(gr_poly
					(pts
						(arc
							(start -0.1778 -0.2794)
							(mid -0.249642 -0.249642)
							(end -0.2794 -0.1778)
						)
						(arc
							(start -0.2794 0.1778)
							(mid -0.249642 0.249642)
							(end -0.1778 0.2794)
						)
						(arc
							(start 0.1778 0.2794)
							(mid 0.249642 0.249642)
							(end 0.2794 0.1778)
						)
						(arc
							(start 0.2794 -0.1778)
							(mid 0.249642 -0.249642)
							(end 0.1778 -0.2794)
						)
					)
					(width 0)
					(fill yes)
				)
			)
		)
		(pad "2" smd custom
			(at 0 0.4445 180)
			(size 0.1397 0.1397)
			(layers "F.Cu" "F.Mask" "F.Paste")
			(net "SSD14_CLK0_OE_R_N")
			(options
				(clearance outline)
				(anchor circle)
			)
			(primitives
				(gr_poly
					(pts
						(arc
							(start -0.1778 -0.2794)
							(mid -0.249642 -0.249642)
							(end -0.2794 -0.1778)
						)
						(arc
							(start -0.2794 0.1778)
							(mid -0.249642 0.249642)
							(end -0.1778 0.2794)
						)
						(arc
							(start 0.1778 0.2794)
							(mid 0.249642 0.249642)
							(end 0.2794 0.1778)
						)
						(arc
							(start 0.2794 -0.1778)
							(mid 0.249642 -0.249642)
							(end 0.1778 -0.2794)
						)
					)
					(width 0)
					(fill yes)
				)
			)
		)
	)
	(footprint ""
		(layer "F.Cu")
		(at 70.739 -146.558 90)
		(property "Reference" "SR969"
			(at 0 0 90)
			(layer "F.SilkS")
			(hide yes)
			(effects
				(font
					(size 1.27 1.27)
				)
			)
		)
		(property "Value" "2KR2F-3-GP"
			(at 0.064008 -3.993896 90)
			(unlocked yes)
			(layer "F.Fab")
			(hide yes)
			(effects
				(font
					(size 1.016 1.016)
					(thickness 0.1524)
				)
			)
		)
		(property "Device Type" "R402H16"
			(at 0.064008 -5.517896 90)
			(unlocked yes)
			(layer "F.Fab")
			(hide yes)
			(effects
				(font
					(size 1.016 1.016)
					(thickness 0.1524)
				)
			)
		)
		(duplicate_pad_numbers_are_jumpers no)
		(fp_line
			(start 0.508 -0.9398)
			(end -0.508 -0.9398)
			(stroke
				(width 0.1524)
				(type default)
			)
			(layer "F.SilkS")
		)
		(fp_line
			(start -0.508 -0.9398)
			(end -0.508 0.9398)
			(stroke
				(width 0.1524)
				(type default)
			)
			(layer "F.SilkS")
		)
		(fp_rect
			(start -0.508 0.9398)
			(end 0.508 -0.9398)
			(stroke
				(width 0)
				(type default)
			)
			(fill no)
			(layer "F.CrtYd")
		)
		(fp_rect
			(start -0.508 0.9398)
			(end 0.508 -0.9398)
			(stroke
				(width 0)
				(type default)
			)
			(fill no)
			(layer "F.Fab")
		)
		(pad "1" smd custom
			(at 0 -0.4445 90)
			(size 0.1397 0.1397)
			(layers "F.Cu" "F.Mask" "F.Paste")
			(net "P3V3")
			(options
				(clearance outline)
				(anchor circle)
			)
			(primitives
				(gr_poly
					(pts
						(arc
							(start -0.1778 -0.2794)
							(mid -0.249642 -0.249642)
							(end -0.2794 -0.1778)
						)
						(arc
							(start -0.2794 0.1778)
							(mid -0.249642 0.249642)
							(end -0.1778 0.2794)
						)
						(arc
							(start 0.1778 0.2794)
							(mid 0.249642 0.249642)
							(end 0.2794 0.1778)
						)
						(arc
							(start 0.2794 -0.1778)
							(mid 0.249642 -0.249642)
							(end 0.1778 -0.2794)
						)
					)
					(width 0)
					(fill yes)
				)
			)
		)
		(pad "2" smd custom
			(at 0 0.4445 90)
			(size 0.1397 0.1397)
			(layers "F.Cu" "F.Mask" "F.Paste")
			(net "SCL_DR13")
			(options
				(clearance outline)
				(anchor circle)
			)
			(primitives
				(gr_poly
					(pts
						(arc
							(start -0.1778 -0.2794)
							(mid -0.249642 -0.249642)
							(end -0.2794 -0.1778)
						)
						(arc
							(start -0.2794 0.1778)
							(mid -0.249642 0.249642)
							(end -0.1778 0.2794)
						)
						(arc
							(start 0.1778 0.2794)
							(mid 0.249642 0.249642)
							(end 0.2794 0.1778)
						)
						(arc
							(start 0.2794 -0.1778)
							(mid 0.249642 -0.249642)
							(end 0.1778 -0.2794)
						)
					)
					(width 0)
					(fill yes)
				)
			)
		)
	)
	(footprint ""
		(layer "F.Cu")
		(at 32.131 -287.528 -90)
		(property "Reference" "R401"
			(at 0 0 270)
			(layer "F.SilkS")
			(hide yes)
			(effects
				(font
					(size 1.27 1.27)
				)
			)
		)
		(property "Value" "0R2J-2-GP"
			(at 0.064008 -3.993896 270)
			(unlocked yes)
			(layer "F.Fab")
			(hide yes)
			(effects
				(font
					(size 1.016 1.016)
					(thickness 0.1524)
				)
			)
		)
		(property "Device Type" "R402H16"
			(at 0.064008 -5.517896 270)
			(unlocked yes)
			(layer "F.Fab")
			(hide yes)
			(effects
				(font
					(size 1.016 1.016)
					(thickness 0.1524)
				)
			)
		)
		(duplicate_pad_numbers_are_jumpers no)
		(fp_line
			(start -0.508 -0.9398)
			(end -0.508 0.9398)
			(stroke
				(width 0.1524)
				(type default)
			)
			(layer "F.SilkS")
		)
		(fp_line
			(start 0.508 -0.9398)
			(end -0.508 -0.9398)
			(stroke
				(width 0.1524)
				(type default)
			)
			(layer "F.SilkS")
		)
		(fp_rect
			(start -0.508 0.9398)
			(end 0.508 -0.9398)
			(stroke
				(width 0)
				(type default)
			)
			(fill no)
			(layer "F.CrtYd")
		)
		(fp_rect
			(start -0.508 0.9398)
			(end 0.508 -0.9398)
			(stroke
				(width 0)
				(type default)
			)
			(fill no)
			(layer "F.Fab")
		)
		(pad "1" smd custom
			(at 0 -0.4445 270)
			(size 0.1397 0.1397)
			(layers "F.Cu" "F.Mask" "F.Paste")
			(net "SCL_DR7_R")
			(options
				(clearance outline)
				(anchor circle)
			)
			(primitives
				(gr_poly
					(pts
						(arc
							(start -0.1778 -0.2794)
							(mid -0.249642 -0.249642)
							(end -0.2794 -0.1778)
						)
						(arc
							(start -0.2794 0.1778)
							(mid -0.249642 0.249642)
							(end -0.1778 0.2794)
						)
						(arc
							(start 0.1778 0.2794)
							(mid 0.249642 0.249642)
							(end 0.2794 0.1778)
						)
						(arc
							(start 0.2794 -0.1778)
							(mid 0.249642 -0.249642)
							(end 0.1778 -0.2794)
						)
					)
					(width 0)
					(fill yes)
				)
			)
		)
		(pad "2" smd custom
			(at 0 0.4445 270)
			(size 0.1397 0.1397)
			(layers "F.Cu" "F.Mask" "F.Paste")
			(net "SCL_DR7")
			(options
				(clearance outline)
				(anchor circle)
			)
			(primitives
				(gr_poly
					(pts
						(arc
							(start -0.1778 -0.2794)
							(mid -0.249642 -0.249642)
							(end -0.2794 -0.1778)
						)
						(arc
							(start -0.2794 0.1778)
							(mid -0.249642 0.249642)
							(end -0.1778 0.2794)
						)
						(arc
							(start 0.1778 0.2794)
							(mid 0.249642 0.249642)
							(end 0.2794 0.1778)
						)
						(arc
							(start 0.2794 -0.1778)
							(mid 0.249642 -0.249642)
							(end 0.1778 -0.2794)
						)
					)
					(width 0)
					(fill yes)
				)
			)
		)
	)
	(footprint ""
		(layer "F.Cu")
		(at 29.845 -114.173 90)
		(property "Reference" "R416"
			(at 0 0 90)
			(layer "F.SilkS")
			(hide yes)
			(effects
				(font
					(size 1.27 1.27)
				)
			)
		)
		(property "Value" "0R2J-2-GP"
			(at 0.064008 -3.993896 90)
			(unlocked yes)
			(layer "F.Fab")
			(hide yes)
			(effects
				(font
					(size 1.016 1.016)
					(thickness 0.1524)
				)
			)
		)
		(property "Device Type" "R402H16"
			(at 0.064008 -5.517896 90)
			(unlocked yes)
			(layer "F.Fab")
			(hide yes)
			(effects
				(font
					(size 1.016 1.016)
					(thickness 0.1524)
				)
			)
		)
		(duplicate_pad_numbers_are_jumpers no)
		(fp_line
			(start 0.508 -0.9398)
			(end -0.508 -0.9398)
			(stroke
				(width 0.1524)
				(type default)
			)
			(layer "F.SilkS")
		)
		(fp_line
			(start -0.508 -0.9398)
			(end -0.508 0.9398)
			(stroke
				(width 0.1524)
				(type default)
			)
			(layer "F.SilkS")
		)
		(fp_rect
			(start -0.508 0.9398)
			(end 0.508 -0.9398)
			(stroke
				(width 0)
				(type default)
			)
			(fill no)
			(layer "F.CrtYd")
		)
		(fp_rect
			(start -0.508 0.9398)
			(end 0.508 -0.9398)
			(stroke
				(width 0)
				(type default)
			)
			(fill no)
			(layer "F.Fab")
		)
		(pad "1" smd custom
			(at 0 -0.4445 90)
			(size 0.1397 0.1397)
			(layers "F.Cu" "F.Mask" "F.Paste")
			(net "SDA_DR13_R")
			(options
				(clearance outline)
				(anchor circle)
			)
			(primitives
				(gr_poly
					(pts
						(arc
							(start -0.1778 -0.2794)
							(mid -0.249642 -0.249642)
							(end -0.2794 -0.1778)
						)
						(arc
							(start -0.2794 0.1778)
							(mid -0.249642 0.249642)
							(end -0.1778 0.2794)
						)
						(arc
							(start 0.1778 0.2794)
							(mid 0.249642 0.249642)
							(end 0.2794 0.1778)
						)
						(arc
							(start 0.2794 -0.1778)
							(mid 0.249642 -0.249642)
							(end 0.1778 -0.2794)
						)
					)
					(width 0)
					(fill yes)
				)
			)
		)
		(pad "2" smd custom
			(at 0 0.4445 90)
			(size 0.1397 0.1397)
			(layers "F.Cu" "F.Mask" "F.Paste")
			(net "SDA_DR13")
			(options
				(clearance outline)
				(anchor circle)
			)
			(primitives
				(gr_poly
					(pts
						(arc
							(start -0.1778 -0.2794)
							(mid -0.249642 -0.249642)
							(end -0.2794 -0.1778)
						)
						(arc
							(start -0.2794 0.1778)
							(mid -0.249642 0.249642)
							(end -0.1778 0.2794)
						)
						(arc
							(start 0.1778 0.2794)
							(mid 0.249642 0.249642)
							(end 0.2794 0.1778)
						)
						(arc
							(start 0.2794 -0.1778)
							(mid 0.249642 -0.249642)
							(end 0.1778 -0.2794)
						)
					)
					(width 0)
					(fill yes)
				)
			)
		)
	)
	(footprint ""
		(layer "F.Cu")
		(at 55.753 -241.040158 180)
		(property "Reference" "Q65"
			(at 0 0 180)
			(layer "F.SilkS")
			(hide yes)
			(effects
				(font
					(size 1.27 1.27)
				)
			)
		)
		(property "Value" "2N7002A-7-GP"
			(at 0.127 -8.9662 180)
			(unlocked yes)
			(layer "F.Fab")
			(hide yes)
			(effects
				(font
					(size 1.016 1.016)
					(thickness 0.1524)
				)
			)
		)
		(property "Device Type" "SOT23DGS2D4H48"
			(at 0.127 -10.4902 180)
			(unlocked yes)
			(layer "F.Fab")
			(hide yes)
			(effects
				(font
					(size 1.016 1.016)
					(thickness 0.1524)
				)
			)
		)
		(duplicate_pad_numbers_are_jumpers no)
		(fp_line
			(start 1.651 1.778)
			(end 1.651 -1.778)
			(stroke
				(width 0.1524)
				(type default)
			)
			(layer "F.SilkS")
		)
		(fp_line
			(start 1.651 -1.778)
			(end -1.651 -1.778)
			(stroke
				(width 0.1524)
				(type default)
			)
			(layer "F.SilkS")
		)
		(fp_line
			(start -1.651 1.778)
			(end 1.651 1.778)
			(stroke
				(width 0.1524)
				(type default)
			)
			(layer "F.SilkS")
		)
		(fp_line
			(start -1.651 -1.778)
			(end -1.651 1.778)
			(stroke
				(width 0.1524)
				(type default)
			)
			(layer "F.SilkS")
		)
		(fp_poly
			(pts
				(xy -1.778 1.8796) (xy -1.778 -1.8796) (xy 1.778 -1.8796) (xy 1.778 1.8796)
			)
			(stroke
				(width 0)
				(type default)
			)
			(fill no)
			(layer "F.CrtYd")
		)
		(fp_poly
			(pts
				(xy -1.778 1.8796) (xy -1.778 -1.8796) (xy 1.778 -1.8796) (xy 1.778 1.8796)
			)
			(stroke
				(width 0)
				(type default)
			)
			(fill no)
			(layer "F.Fab")
		)
		(pad "D" smd custom
			(at 0 -0.9525 180)
			(size 0.1905 0.1905)
			(layers "F.Cu" "F.Mask" "F.Paste")
			(net "ATTN_LED_DR7_MOS_N")
			(options
				(clearance outline)
				(anchor circle)
			)
			(primitives
				(gr_poly
					(pts
						(arc
							(start -0.1778 0.5715)
							(mid -0.321484 0.511984)
							(end -0.381 0.3683)
						)
						(arc
							(start -0.381 -0.3683)
							(mid -0.321484 -0.511984)
							(end -0.1778 -0.5715)
						)
						(arc
							(start 0.1778 -0.5715)
							(mid 0.321484 -0.511984)
							(end 0.381 -0.3683)
						)
						(arc
							(start 0.381 0.3683)
							(mid 0.321484 0.511984)
							(end 0.1778 0.5715)
						)
					)
					(width 0)
					(fill yes)
				)
			)
		)
		(pad "G" smd custom
			(at -0.98425 0.9525 180)
			(size 0.1905 0.1905)
			(layers "F.Cu" "F.Mask" "F.Paste")
			(net "SSD7_CLK0_OE_MOS_N")
			(options
				(clearance outline)
				(anchor circle)
			)
			(primitives
				(gr_poly
					(pts
						(arc
							(start -0.1778 0.5715)
							(mid -0.321484 0.511984)
							(end -0.381 0.3683)
						)
						(arc
							(start -0.381 -0.3683)
							(mid -0.321484 -0.511984)
							(end -0.1778 -0.5715)
						)
						(arc
							(start 0.1778 -0.5715)
							(mid 0.321484 -0.511984)
							(end 0.381 -0.3683)
						)
						(arc
							(start 0.381 0.3683)
							(mid 0.321484 0.511984)
							(end 0.1778 0.5715)
						)
					)
					(width 0)
					(fill yes)
				)
			)
		)
		(pad "S" smd custom
			(at 0.98425 0.9525 180)
			(size 0.1905 0.1905)
			(layers "F.Cu" "F.Mask" "F.Paste")
			(net "ATTN_LED_DR7_R")
			(options
				(clearance outline)
				(anchor circle)
			)
			(primitives
				(gr_poly
					(pts
						(arc
							(start -0.1778 0.5715)
							(mid -0.321484 0.511984)
							(end -0.381 0.3683)
						)
						(arc
							(start -0.381 -0.3683)
							(mid -0.321484 -0.511984)
							(end -0.1778 -0.5715)
						)
						(arc
							(start 0.1778 -0.5715)
							(mid 0.321484 -0.511984)
							(end 0.381 -0.3683)
						)
						(arc
							(start 0.381 0.3683)
							(mid 0.321484 0.511984)
							(end 0.1778 0.5715)
						)
					)
					(width 0)
					(fill yes)
				)
			)
		)
	)
	(footprint ""
		(layer "F.Cu")
		(at 46.609 -134.874 -90)
		(property "Reference" "R320"
			(at 0 0 270)
			(layer "F.SilkS")
			(hide yes)
			(effects
				(font
					(size 1.27 1.27)
				)
			)
		)
		(property "Value" "0R2J-2-GP"
			(at 0.064008 -3.993896 270)
			(unlocked yes)
			(layer "F.Fab")
			(hide yes)
			(effects
				(font
					(size 1.016 1.016)
					(thickness 0.1524)
				)
			)
		)
		(property "Device Type" "R402H16"
			(at 0.064008 -5.517896 270)
			(unlocked yes)
			(layer "F.Fab")
			(hide yes)
			(effects
				(font
					(size 1.016 1.016)
					(thickness 0.1524)
				)
			)
		)
		(duplicate_pad_numbers_are_jumpers no)
		(fp_line
			(start -0.508 -0.9398)
			(end -0.508 0.9398)
			(stroke
				(width 0.1524)
				(type default)
			)
			(layer "F.SilkS")
		)
		(fp_line
			(start 0.508 -0.9398)
			(end -0.508 -0.9398)
			(stroke
				(width 0.1524)
				(type default)
			)
			(layer "F.SilkS")
		)
		(fp_rect
			(start -0.508 0.9398)
			(end 0.508 -0.9398)
			(stroke
				(width 0)
				(type default)
			)
			(fill no)
			(layer "F.CrtYd")
		)
		(fp_rect
			(start -0.508 0.9398)
			(end 0.508 -0.9398)
			(stroke
				(width 0)
				(type default)
			)
			(fill no)
			(layer "F.Fab")
		)
		(pad "1" smd custom
			(at 0 -0.4445 270)
			(size 0.1397 0.1397)
			(layers "F.Cu" "F.Mask" "F.Paste")
			(net "I2C_B_SDA")
			(options
				(clearance outline)
				(anchor circle)
			)
			(primitives
				(gr_poly
					(pts
						(arc
							(start -0.1778 -0.2794)
							(mid -0.249642 -0.249642)
							(end -0.2794 -0.1778)
						)
						(arc
							(start -0.2794 0.1778)
							(mid -0.249642 0.249642)
							(end -0.1778 0.2794)
						)
						(arc
							(start 0.1778 0.2794)
							(mid 0.249642 0.249642)
							(end 0.2794 0.1778)
						)
						(arc
							(start 0.2794 -0.1778)
							(mid 0.249642 -0.249642)
							(end 0.1778 -0.2794)
						)
					)
					(width 0)
					(fill yes)
				)
			)
		)
		(pad "2" smd custom
			(at 0 0.4445 270)
			(size 0.1397 0.1397)
			(layers "F.Cu" "F.Mask" "F.Paste")
			(net "TMP1_SDA")
			(options
				(clearance outline)
				(anchor circle)
			)
			(primitives
				(gr_poly
					(pts
						(arc
							(start -0.1778 -0.2794)
							(mid -0.249642 -0.249642)
							(end -0.2794 -0.1778)
						)
						(arc
							(start -0.2794 0.1778)
							(mid -0.249642 0.249642)
							(end -0.1778 0.2794)
						)
						(arc
							(start 0.1778 0.2794)
							(mid 0.249642 0.249642)
							(end 0.2794 0.1778)
						)
						(arc
							(start 0.2794 -0.1778)
							(mid 0.249642 -0.249642)
							(end 0.1778 -0.2794)
						)
					)
					(width 0)
					(fill yes)
				)
			)
		)
	)
	(footprint ""
		(layer "F.Cu")
		(at 24.8158 -88.646 -90)
		(property "Reference" "R147"
			(at 0 0 270)
			(layer "F.SilkS")
			(hide yes)
			(effects
				(font
					(size 1.27 1.27)
				)
			)
		)
		(property "Value" "4K7R2J-2-GP"
			(at 0.064008 -3.993896 270)
			(unlocked yes)
			(layer "F.Fab")
			(hide yes)
			(effects
				(font
					(size 1.016 1.016)
					(thickness 0.1524)
				)
			)
		)
		(property "Device Type" "R402H16"
			(at 0.064008 -5.517896 270)
			(unlocked yes)
			(layer "F.Fab")
			(hide yes)
			(effects
				(font
					(size 1.016 1.016)
					(thickness 0.1524)
				)
			)
		)
		(duplicate_pad_numbers_are_jumpers no)
		(fp_line
			(start -0.508 -0.9398)
			(end -0.508 0.9398)
			(stroke
				(width 0.1524)
				(type default)
			)
			(layer "F.SilkS")
		)
		(fp_line
			(start 0.508 -0.9398)
			(end -0.508 -0.9398)
			(stroke
				(width 0.1524)
				(type default)
			)
			(layer "F.SilkS")
		)
		(fp_rect
			(start -0.508 0.9398)
			(end 0.508 -0.9398)
			(stroke
				(width 0)
				(type default)
			)
			(fill no)
			(layer "F.CrtYd")
		)
		(fp_rect
			(start -0.508 0.9398)
			(end 0.508 -0.9398)
			(stroke
				(width 0)
				(type default)
			)
			(fill no)
			(layer "F.Fab")
		)
		(pad "1" smd custom
			(at 0 -0.4445 270)
			(size 0.1397 0.1397)
			(layers "F.Cu" "F.Mask" "F.Paste")
			(net "P12V")
			(options
				(clearance outline)
				(anchor circle)
			)
			(primitives
				(gr_poly
					(pts
						(arc
							(start -0.1778 -0.2794)
							(mid -0.249642 -0.249642)
							(end -0.2794 -0.1778)
						)
						(arc
							(start -0.2794 0.1778)
							(mid -0.249642 0.249642)
							(end -0.1778 0.2794)
						)
						(arc
							(start 0.1778 0.2794)
							(mid 0.249642 0.249642)
							(end 0.2794 0.1778)
						)
						(arc
							(start 0.2794 -0.1778)
							(mid 0.249642 -0.249642)
							(end 0.1778 -0.2794)
						)
					)
					(width 0)
					(fill yes)
				)
			)
		)
		(pad "2" smd custom
			(at 0 0.4445 270)
			(size 0.1397 0.1397)
			(layers "F.Cu" "F.Mask" "F.Paste")
			(net "SW_SSD9_R")
			(options
				(clearance outline)
				(anchor circle)
			)
			(primitives
				(gr_poly
					(pts
						(arc
							(start -0.1778 -0.2794)
							(mid -0.249642 -0.249642)
							(end -0.2794 -0.1778)
						)
						(arc
							(start -0.2794 0.1778)
							(mid -0.249642 0.249642)
							(end -0.1778 0.2794)
						)
						(arc
							(start 0.1778 0.2794)
							(mid 0.249642 0.249642)
							(end 0.2794 0.1778)
						)
						(arc
							(start 0.2794 -0.1778)
							(mid 0.249642 -0.249642)
							(end 0.1778 -0.2794)
						)
					)
					(width 0)
					(fill yes)
				)
			)
		)
	)
	(footprint ""
		(layer "F.Cu")
		(at 78.994 -310.896 90)
		(property "Reference" "FB7"
			(at 0 0 90)
			(layer "F.SilkS")
			(hide yes)
			(effects
				(font
					(size 1.27 1.27)
				)
			)
		)
		(property "Value" "BLM21PG331SN1D-2-GP"
			(at 0 -4.2418 90)
			(unlocked yes)
			(layer "F.Fab")
			(hide yes)
			(effects
				(font
					(size 1.016 1.016)
					(thickness 0.1524)
				)
			)
		)
		(property "Device Type" "L805H42"
			(at 0 -5.7912 90)
			(unlocked yes)
			(layer "F.Fab")
			(hide yes)
			(effects
				(font
					(size 1.016 1.016)
					(thickness 0.1524)
				)
			)
		)
		(duplicate_pad_numbers_are_jumpers no)
		(fp_line
			(start 0.889 -1.7018)
			(end 0.889 1.7018)
			(stroke
				(width 0.1524)
				(type default)
			)
			(layer "F.SilkS")
		)
		(fp_line
			(start -0.889 -1.7018)
			(end 0.889 -1.7018)
			(stroke
				(width 0.1524)
				(type default)
			)
			(layer "F.SilkS")
		)
		(fp_line
			(start 0.889 1.7018)
			(end -0.889 1.7018)
			(stroke
				(width 0.1524)
				(type default)
			)
			(layer "F.SilkS")
		)
		(fp_line
			(start -0.889 1.7018)
			(end -0.889 -1.7018)
			(stroke
				(width 0.1524)
				(type default)
			)
			(layer "F.SilkS")
		)
		(fp_rect
			(start -0.9652 1.778)
			(end 0.9652 -1.778)
			(stroke
				(width 0)
				(type default)
			)
			(fill no)
			(layer "F.CrtYd")
		)
		(fp_rect
			(start -0.9652 1.778)
			(end 0.9652 -1.778)
			(stroke
				(width 0)
				(type default)
			)
			(fill no)
			(layer "F.Fab")
		)
		(pad "1" smd rect
			(at 0 -0.9652 90)
			(size 1.397 1.143)
			(layers "F.Cu" "F.Mask" "F.Paste")
			(net "P3V3")
		)
		(pad "2" smd rect
			(at 0 0.9652 90)
			(size 1.397 1.143)
			(layers "F.Cu" "F.Mask" "F.Paste")
			(net "VDD_DIFF_2")
		)
	)
	(footprint ""
		(layer "F.Cu")
		(at 95.885 -26.162)
		(property "Reference" "R9758"
			(at 0 0 0)
			(layer "F.SilkS")
			(hide yes)
			(effects
				(font
					(size 1.27 1.27)
				)
			)
		)
		(property "Value" "1KR2J-1-GP"
			(at 0.064008 -3.993896 0)
			(unlocked yes)
			(layer "F.Fab")
			(hide yes)
			(effects
				(font
					(size 1.016 1.016)
					(thickness 0.1524)
				)
			)
		)
		(property "Device Type" "R402H16"
			(at 0.064008 -5.517896 0)
			(unlocked yes)
			(layer "F.Fab")
			(hide yes)
			(effects
				(font
					(size 1.016 1.016)
					(thickness 0.1524)
				)
			)
		)
		(duplicate_pad_numbers_are_jumpers no)
		(fp_line
			(start -0.508 -0.9398)
			(end -0.508 0.9398)
			(stroke
				(width 0.1524)
				(type default)
			)
			(layer "F.SilkS")
		)
		(fp_line
			(start 0.508 -0.9398)
			(end -0.508 -0.9398)
			(stroke
				(width 0.1524)
				(type default)
			)
			(layer "F.SilkS")
		)
		(fp_rect
			(start -0.508 0.9398)
			(end 0.508 -0.9398)
			(stroke
				(width 0)
				(type default)
			)
			(fill no)
			(layer "F.CrtYd")
		)
		(fp_rect
			(start -0.508 0.9398)
			(end 0.508 -0.9398)
			(stroke
				(width 0)
				(type default)
			)
			(fill no)
			(layer "F.Fab")
		)
		(pad "1" smd custom
			(at 0 -0.4445)
			(size 0.1397 0.1397)
			(layers "F.Cu" "F.Mask" "F.Paste")
			(net "P3V3_SENSE")
			(options
				(clearance outline)
				(anchor circle)
			)
			(primitives
				(gr_poly
					(pts
						(arc
							(start -0.1778 -0.2794)
							(mid -0.249642 -0.249642)
							(end -0.2794 -0.1778)
						)
						(arc
							(start -0.2794 0.1778)
							(mid -0.249642 0.249642)
							(end -0.1778 0.2794)
						)
						(arc
							(start 0.1778 0.2794)
							(mid 0.249642 0.249642)
							(end 0.2794 0.1778)
						)
						(arc
							(start 0.2794 -0.1778)
							(mid 0.249642 -0.249642)
							(end 0.1778 -0.2794)
						)
					)
					(width 0)
					(fill yes)
				)
			)
		)
		(pad "2" smd custom
			(at 0 0.4445)
			(size 0.1397 0.1397)
			(layers "F.Cu" "F.Mask" "F.Paste")
			(net "GND")
			(options
				(clearance outline)
				(anchor circle)
			)
			(primitives
				(gr_poly
					(pts
						(arc
							(start -0.1778 -0.2794)
							(mid -0.249642 -0.249642)
							(end -0.2794 -0.1778)
						)
						(arc
							(start -0.2794 0.1778)
							(mid -0.249642 0.249642)
							(end -0.1778 0.2794)
						)
						(arc
							(start 0.1778 0.2794)
							(mid 0.249642 0.249642)
							(end 0.2794 0.1778)
						)
						(arc
							(start 0.2794 -0.1778)
							(mid 0.249642 -0.249642)
							(end 0.1778 -0.2794)
						)
					)
					(width 0)
					(fill yes)
				)
			)
		)
	)
	(footprint ""
		(layer "F.Cu")
		(at 210.185 -432.816)
		(property "Reference" "PC1285"
			(at 0 0 0)
			(layer "F.SilkS")
			(hide yes)
			(effects
				(font
					(size 1.27 1.27)
				)
			)
		)
		(property "Value" "SC47U10V5MX-GP-U"
			(at -0.0762 -2.9972 0)
			(unlocked yes)
			(layer "F.Fab")
			(hide yes)
			(effects
				(font
					(size 1.016 1.016)
					(thickness 0.1524)
				)
			)
		)
		(property "Device Type" "C805H62"
			(at -0.0762 -4.5212 0)
			(unlocked yes)
			(layer "F.Fab")
			(hide yes)
			(effects
				(font
					(size 1.016 1.016)
					(thickness 0.1524)
				)
			)
		)
		(duplicate_pad_numbers_are_jumpers no)
		(fp_line
			(start 0.635 0)
			(end -0.635 0)
			(stroke
				(width 0.508)
				(type default)
			)
			(layer "F.SilkS")
		)
		(fp_rect
			(start -0.6223 1.0033)
			(end 0.6223 -1.0033)
			(stroke
				(width 0)
				(type default)
			)
			(fill no)
			(layer "F.CrtYd")
		)
		(fp_poly
			(pts
				(xy -0.9652 1.778) (xy -0.9652 -1.778) (xy 0.9652 -1.778) (xy 0.9652 0.39116) (xy 0.6223 0.39116)
				(xy 0.6223 -1.0033) (xy -0.6223 -1.0033) (xy -0.6223 1.0033) (xy 0.6223 1.0033) (xy 0.6223 0.3937)
				(xy 0.9652 0.3937) (xy 0.9652 1.778)
			)
			(stroke
				(width 0)
				(type default)
			)
			(fill no)
			(layer "F.CrtYd")
		)
		(fp_rect
			(start -0.9652 1.778)
			(end 0.9652 -1.778)
			(stroke
				(width 0)
				(type default)
			)
			(fill no)
			(layer "F.Fab")
		)
		(pad "1" smd rect
			(at 0 -0.9652)
			(size 1.397 1.143)
			(layers "F.Cu" "F.Mask" "F.Paste")
			(net "P3V3_OUT")
		)
		(pad "2" smd rect
			(at 0 0.9652)
			(size 1.397 1.143)
			(layers "F.Cu" "F.Mask" "F.Paste")
			(net "GND")
		)
	)
	(footprint ""
		(layer "F.Cu")
		(at 42.974768 -454.835768 -90)
		(property "Reference" "R9937"
			(at 0 0 270)
			(layer "F.SilkS")
			(hide yes)
			(effects
				(font
					(size 1.27 1.27)
				)
			)
		)
		(property "Value" "4K7R2J-2-GP"
			(at 0.064008 -3.993896 270)
			(unlocked yes)
			(layer "F.Fab")
			(hide yes)
			(effects
				(font
					(size 1.016 1.016)
					(thickness 0.1524)
				)
			)
		)
		(property "Device Type" "R402H16"
			(at 0.064008 -5.517896 270)
			(unlocked yes)
			(layer "F.Fab")
			(hide yes)
			(effects
				(font
					(size 1.016 1.016)
					(thickness 0.1524)
				)
			)
		)
		(duplicate_pad_numbers_are_jumpers no)
		(fp_line
			(start -0.508 -0.9398)
			(end -0.508 0.9398)
			(stroke
				(width 0.1524)
				(type default)
			)
			(layer "F.SilkS")
		)
		(fp_line
			(start 0.508 -0.9398)
			(end -0.508 -0.9398)
			(stroke
				(width 0.1524)
				(type default)
			)
			(layer "F.SilkS")
		)
		(fp_rect
			(start -0.508 0.9398)
			(end 0.508 -0.9398)
			(stroke
				(width 0)
				(type default)
			)
			(fill no)
			(layer "F.CrtYd")
		)
		(fp_rect
			(start -0.508 0.9398)
			(end 0.508 -0.9398)
			(stroke
				(width 0)
				(type default)
			)
			(fill no)
			(layer "F.Fab")
		)
		(pad "1" smd custom
			(at 0 -0.4445 270)
			(size 0.1397 0.1397)
			(layers "F.Cu" "F.Mask" "F.Paste")
			(net "P3V3")
			(options
				(clearance outline)
				(anchor circle)
			)
			(primitives
				(gr_poly
					(pts
						(arc
							(start -0.1778 -0.2794)
							(mid -0.249642 -0.249642)
							(end -0.2794 -0.1778)
						)
						(arc
							(start -0.2794 0.1778)
							(mid -0.249642 0.249642)
							(end -0.1778 0.2794)
						)
						(arc
							(start 0.1778 0.2794)
							(mid 0.249642 0.249642)
							(end 0.2794 0.1778)
						)
						(arc
							(start 0.2794 -0.1778)
							(mid 0.249642 -0.249642)
							(end 0.1778 -0.2794)
						)
					)
					(width 0)
					(fill yes)
				)
			)
		)
		(pad "2" smd custom
			(at 0 0.4445 270)
			(size 0.1397 0.1397)
			(layers "F.Cu" "F.Mask" "F.Paste")
			(net "ATTN_LED_DR5_MOS_N")
			(options
				(clearance outline)
				(anchor circle)
			)
			(primitives
				(gr_poly
					(pts
						(arc
							(start -0.1778 -0.2794)
							(mid -0.249642 -0.249642)
							(end -0.2794 -0.1778)
						)
						(arc
							(start -0.2794 0.1778)
							(mid -0.249642 0.249642)
							(end -0.1778 0.2794)
						)
						(arc
							(start 0.1778 0.2794)
							(mid 0.249642 0.249642)
							(end 0.2794 0.1778)
						)
						(arc
							(start 0.2794 -0.1778)
							(mid 0.249642 -0.249642)
							(end 0.1778 -0.2794)
						)
					)
					(width 0)
					(fill yes)
				)
			)
		)
	)
	(footprint ""
		(layer "F.Cu")
		(at 99.06 -89.535 90)
		(property "Reference" "C9374"
			(at 0 0 90)
			(layer "F.SilkS")
			(hide yes)
			(effects
				(font
					(size 1.27 1.27)
				)
			)
		)
		(property "Value" "SC1KP50V2KX-1GP"
			(at 1.1811 -2.7051 90)
			(unlocked yes)
			(layer "F.Fab")
			(hide yes)
			(effects
				(font
					(size 1.016 1.016)
					(thickness 0.1524)
				)
			)
		)
		(property "Device Type" "C402H22"
			(at 1.1811 -4.2291 90)
			(unlocked yes)
			(layer "F.Fab")
			(hide yes)
			(effects
				(font
					(size 1.016 1.016)
					(thickness 0.1524)
				)
			)
		)
		(duplicate_pad_numbers_are_jumpers no)
		(fp_rect
			(start -0.4318 0.9525)
			(end 0.4318 -0.9525)
			(stroke
				(width 0)
				(type default)
			)
			(fill no)
			(layer "F.CrtYd")
		)
		(fp_rect
			(start -0.4318 0.9525)
			(end 0.4318 -0.9525)
			(stroke
				(width 0)
				(type default)
			)
			(fill no)
			(layer "F.Fab")
		)
		(pad "1" smd custom
			(at 0 -0.4445 90)
			(size 0.1524 0.1524)
			(layers "F.Cu" "F.Mask" "F.Paste")
			(net "SSD14_CLK0_OE_R_N")
			(options
				(clearance outline)
				(anchor circle)
			)
			(primitives
				(gr_poly
					(pts
						(arc
							(start 0.3048 -0.2032)
							(mid 0.275042 -0.275042)
							(end 0.2032 -0.3048)
						)
						(arc
							(start -0.2032 -0.3048)
							(mid -0.275042 -0.275042)
							(end -0.3048 -0.2032)
						)
						(arc
							(start -0.3048 0.2032)
							(mid -0.275042 0.275042)
							(end -0.2032 0.3048)
						)
						(arc
							(start 0.2032 0.3048)
							(mid 0.275042 0.275042)
							(end 0.3048 0.2032)
						)
					)
					(width 0)
					(fill yes)
				)
			)
		)
		(pad "2" smd custom
			(at 0 0.4445 90)
			(size 0.1524 0.1524)
			(layers "F.Cu" "F.Mask" "F.Paste")
			(net "GND")
			(options
				(clearance outline)
				(anchor circle)
			)
			(primitives
				(gr_poly
					(pts
						(arc
							(start 0.3048 -0.2032)
							(mid 0.275042 -0.275042)
							(end 0.2032 -0.3048)
						)
						(arc
							(start -0.2032 -0.3048)
							(mid -0.275042 -0.275042)
							(end -0.3048 -0.2032)
						)
						(arc
							(start -0.3048 0.2032)
							(mid -0.275042 0.275042)
							(end -0.2032 0.3048)
						)
						(arc
							(start 0.2032 0.3048)
							(mid 0.275042 0.275042)
							(end 0.3048 0.2032)
						)
					)
					(width 0)
					(fill yes)
				)
			)
		)
	)
	(footprint ""
		(layer "F.Cu")
		(at 102.616 -307.721 90)
		(property "Reference" "R9075"
			(at 0 0 90)
			(layer "F.SilkS")
			(hide yes)
			(effects
				(font
					(size 1.27 1.27)
				)
			)
		)
		(property "Value" "27R2F-GP"
			(at 0.064008 -3.993896 90)
			(unlocked yes)
			(layer "F.Fab")
			(hide yes)
			(effects
				(font
					(size 1.016 1.016)
					(thickness 0.1524)
				)
			)
		)
		(property "Device Type" "R402H16"
			(at 0.064008 -5.517896 90)
			(unlocked yes)
			(layer "F.Fab")
			(hide yes)
			(effects
				(font
					(size 1.016 1.016)
					(thickness 0.1524)
				)
			)
		)
		(duplicate_pad_numbers_are_jumpers no)
		(fp_line
			(start 0.508 -0.9398)
			(end -0.508 -0.9398)
			(stroke
				(width 0.1524)
				(type default)
			)
			(layer "F.SilkS")
		)
		(fp_line
			(start -0.508 -0.9398)
			(end -0.508 0.9398)
			(stroke
				(width 0.1524)
				(type default)
			)
			(layer "F.SilkS")
		)
		(fp_rect
			(start -0.508 0.9398)
			(end 0.508 -0.9398)
			(stroke
				(width 0)
				(type default)
			)
			(fill no)
			(layer "F.CrtYd")
		)
		(fp_rect
			(start -0.508 0.9398)
			(end 0.508 -0.9398)
			(stroke
				(width 0)
				(type default)
			)
			(fill no)
			(layer "F.Fab")
		)
		(pad "1" smd custom
			(at 0 -0.4445 90)
			(size 0.1397 0.1397)
			(layers "F.Cu" "F.Mask" "F.Paste")
			(net "PE_CLK_100M_DR1_2_R_N")
			(options
				(clearance outline)
				(anchor circle)
			)
			(primitives
				(gr_poly
					(pts
						(arc
							(start -0.1778 -0.2794)
							(mid -0.249642 -0.249642)
							(end -0.2794 -0.1778)
						)
						(arc
							(start -0.2794 0.1778)
							(mid -0.249642 0.249642)
							(end -0.1778 0.2794)
						)
						(arc
							(start 0.1778 0.2794)
							(mid 0.249642 0.249642)
							(end 0.2794 0.1778)
						)
						(arc
							(start 0.2794 -0.1778)
							(mid 0.249642 -0.249642)
							(end 0.1778 -0.2794)
						)
					)
					(width 0)
					(fill yes)
				)
			)
		)
		(pad "2" smd custom
			(at 0 0.4445 90)
			(size 0.1397 0.1397)
			(layers "F.Cu" "F.Mask" "F.Paste")
			(net "PE_CLK100M_DR1_2_N")
			(options
				(clearance outline)
				(anchor circle)
			)
			(primitives
				(gr_poly
					(pts
						(arc
							(start -0.1778 -0.2794)
							(mid -0.249642 -0.249642)
							(end -0.2794 -0.1778)
						)
						(arc
							(start -0.2794 0.1778)
							(mid -0.249642 0.249642)
							(end -0.1778 0.2794)
						)
						(arc
							(start 0.1778 0.2794)
							(mid 0.249642 0.249642)
							(end 0.2794 0.1778)
						)
						(arc
							(start 0.2794 -0.1778)
							(mid 0.249642 -0.249642)
							(end 0.1778 -0.2794)
						)
					)
					(width 0)
					(fill yes)
				)
			)
		)
	)
	(footprint ""
		(layer "F.Cu")
		(at 40.4876 -210.4644 180)
		(property "Reference" "D30"
			(at 0 0 180)
			(layer "F.SilkS")
			(hide yes)
			(effects
				(font
					(size 1.27 1.27)
				)
			)
		)
		(property "Value" "RB551V30-1-GP"
			(at 0 -6.7818 180)
			(unlocked yes)
			(layer "F.Fab")
			(hide yes)
			(effects
				(font
					(size 1.016 1.016)
					(thickness 0.1524)
				)
			)
		)
		(property "Device Type" "SOD323AKH44"
			(at 0 -8.6868 180)
			(unlocked yes)
			(layer "F.Fab")
			(hide yes)
			(effects
				(font
					(size 1.016 1.016)
					(thickness 0.1524)
				)
			)
		)
		(duplicate_pad_numbers_are_jumpers no)
		(fp_line
			(start 0.889 2.159)
			(end -0.889 2.159)
			(stroke
				(width 0.1524)
				(type default)
			)
			(layer "F.SilkS")
		)
		(fp_line
			(start 0.889 -1.9304)
			(end 0.889 2.159)
			(stroke
				(width 0.1524)
				(type default)
			)
			(layer "F.SilkS")
		)
		(fp_line
			(start 0.762 2.0574)
			(end -0.762 2.0574)
			(stroke
				(width 0.508)
				(type default)
			)
			(layer "F.SilkS")
		)
		(fp_line
			(start -0.889 2.159)
			(end -0.889 -1.9304)
			(stroke
				(width 0.1524)
				(type default)
			)
			(layer "F.SilkS")
		)
		(fp_line
			(start -0.889 -1.9304)
			(end 0.889 -1.9304)
			(stroke
				(width 0.1524)
				(type default)
			)
			(layer "F.SilkS")
		)
		(fp_rect
			(start -1.016 2.3114)
			(end 1.016 -2.0066)
			(stroke
				(width 0)
				(type default)
			)
			(fill no)
			(layer "F.CrtYd")
		)
		(fp_poly
			(pts
				(xy -1.016 -2.0066) (xy 1.016 -2.0066) (xy 1.016 2.3114) (xy -1.016 2.3114)
			)
			(stroke
				(width 0)
				(type default)
			)
			(fill no)
			(layer "F.Fab")
		)
		(pad "A" smd rect
			(at 0 -1.143 180)
			(size 0.5588 1.016)
			(layers "F.Cu" "F.Mask" "F.Paste")
			(net "SW_SSD12_R")
		)
		(pad "K" smd rect
			(at 0 1.143 180)
			(size 0.5588 1.016)
			(layers "F.Cu" "F.Mask" "F.Paste")
			(net "SW_SSD12_N")
		)
	)
	(footprint ""
		(layer "F.Cu")
		(at 68.961 -454.66 180)
		(property "Reference" "R350"
			(at 0 0 180)
			(layer "F.SilkS")
			(hide yes)
			(effects
				(font
					(size 1.27 1.27)
				)
			)
		)
		(property "Value" "4K7R2J-2-GP"
			(at 0.064008 -3.993896 180)
			(unlocked yes)
			(layer "F.Fab")
			(hide yes)
			(effects
				(font
					(size 1.016 1.016)
					(thickness 0.1524)
				)
			)
		)
		(property "Device Type" "R402H16"
			(at 0.064008 -5.517896 180)
			(unlocked yes)
			(layer "F.Fab")
			(hide yes)
			(effects
				(font
					(size 1.016 1.016)
					(thickness 0.1524)
				)
			)
		)
		(duplicate_pad_numbers_are_jumpers no)
		(fp_line
			(start 0.508 -0.9398)
			(end -0.508 -0.9398)
			(stroke
				(width 0.1524)
				(type default)
			)
			(layer "F.SilkS")
		)
		(fp_line
			(start -0.508 -0.9398)
			(end -0.508 0.9398)
			(stroke
				(width 0.1524)
				(type default)
			)
			(layer "F.SilkS")
		)
		(fp_rect
			(start -0.508 0.9398)
			(end 0.508 -0.9398)
			(stroke
				(width 0)
				(type default)
			)
			(fill no)
			(layer "F.CrtYd")
		)
		(fp_rect
			(start -0.508 0.9398)
			(end 0.508 -0.9398)
			(stroke
				(width 0)
				(type default)
			)
			(fill no)
			(layer "F.Fab")
		)
		(pad "1" smd custom
			(at 0 -0.4445 180)
			(size 0.1397 0.1397)
			(layers "F.Cu" "F.Mask" "F.Paste")
			(net "EEPROM_A2")
			(options
				(clearance outline)
				(anchor circle)
			)
			(primitives
				(gr_poly
					(pts
						(arc
							(start -0.1778 -0.2794)
							(mid -0.249642 -0.249642)
							(end -0.2794 -0.1778)
						)
						(arc
							(start -0.2794 0.1778)
							(mid -0.249642 0.249642)
							(end -0.1778 0.2794)
						)
						(arc
							(start 0.1778 0.2794)
							(mid 0.249642 0.249642)
							(end 0.2794 0.1778)
						)
						(arc
							(start 0.2794 -0.1778)
							(mid 0.249642 -0.249642)
							(end 0.1778 -0.2794)
						)
					)
					(width 0)
					(fill yes)
				)
			)
		)
		(pad "2" smd custom
			(at 0 0.4445 180)
			(size 0.1397 0.1397)
			(layers "F.Cu" "F.Mask" "F.Paste")
			(net "GND")
			(options
				(clearance outline)
				(anchor circle)
			)
			(primitives
				(gr_poly
					(pts
						(arc
							(start -0.1778 -0.2794)
							(mid -0.249642 -0.249642)
							(end -0.2794 -0.1778)
						)
						(arc
							(start -0.2794 0.1778)
							(mid -0.249642 0.249642)
							(end -0.1778 0.2794)
						)
						(arc
							(start 0.1778 0.2794)
							(mid 0.249642 0.249642)
							(end 0.2794 0.1778)
						)
						(arc
							(start 0.2794 -0.1778)
							(mid 0.249642 -0.249642)
							(end 0.1778 -0.2794)
						)
					)
					(width 0)
					(fill yes)
				)
			)
		)
	)
	(footprint ""
		(layer "F.Cu")
		(at 221.742 -36.83 -90)
		(property "Reference" "Q49"
			(at 0 0 270)
			(layer "F.SilkS")
			(hide yes)
			(effects
				(font
					(size 1.27 1.27)
				)
			)
		)
		(property "Value" "2N7002A-7-GP"
			(at 0.127 -8.9662 270)
			(unlocked yes)
			(layer "F.Fab")
			(hide yes)
			(effects
				(font
					(size 1.016 1.016)
					(thickness 0.1524)
				)
			)
		)
		(property "Device Type" "SOT23DGS2D4H48"
			(at 0.127 -10.4902 270)
			(unlocked yes)
			(layer "F.Fab")
			(hide yes)
			(effects
				(font
					(size 1.016 1.016)
					(thickness 0.1524)
				)
			)
		)
		(duplicate_pad_numbers_are_jumpers no)
		(fp_line
			(start -1.651 1.778)
			(end 1.651 1.778)
			(stroke
				(width 0.1524)
				(type default)
			)
			(layer "F.SilkS")
		)
		(fp_line
			(start 1.651 1.778)
			(end 1.651 -1.778)
			(stroke
				(width 0.1524)
				(type default)
			)
			(layer "F.SilkS")
		)
		(fp_line
			(start -1.651 -1.778)
			(end -1.651 1.778)
			(stroke
				(width 0.1524)
				(type default)
			)
			(layer "F.SilkS")
		)
		(fp_line
			(start 1.651 -1.778)
			(end -1.651 -1.778)
			(stroke
				(width 0.1524)
				(type default)
			)
			(layer "F.SilkS")
		)
		(fp_poly
			(pts
				(xy -1.778 1.8796) (xy -1.778 -1.8796) (xy 1.778 -1.8796) (xy 1.778 1.8796)
			)
			(stroke
				(width 0)
				(type default)
			)
			(fill no)
			(layer "F.CrtYd")
		)
		(fp_poly
			(pts
				(xy -1.778 1.8796) (xy -1.778 -1.8796) (xy 1.778 -1.8796) (xy 1.778 1.8796)
			)
			(stroke
				(width 0)
				(type default)
			)
			(fill no)
			(layer "F.Fab")
		)
		(pad "D" smd custom
			(at 0 -0.9525 270)
			(size 0.1905 0.1905)
			(layers "F.Cu" "F.Mask" "F.Paste")
			(net "SSD4_CLK0_OE_MOS_N")
			(options
				(clearance outline)
				(anchor circle)
			)
			(primitives
				(gr_poly
					(pts
						(arc
							(start -0.1778 0.5715)
							(mid -0.321484 0.511984)
							(end -0.381 0.3683)
						)
						(arc
							(start -0.381 -0.3683)
							(mid -0.321484 -0.511984)
							(end -0.1778 -0.5715)
						)
						(arc
							(start 0.1778 -0.5715)
							(mid 0.321484 -0.511984)
							(end 0.381 -0.3683)
						)
						(arc
							(start 0.381 0.3683)
							(mid 0.321484 0.511984)
							(end 0.1778 0.5715)
						)
					)
					(width 0)
					(fill yes)
				)
			)
		)
		(pad "G" smd custom
			(at -0.98425 0.9525 270)
			(size 0.1905 0.1905)
			(layers "F.Cu" "F.Mask" "F.Paste")
			(net "SSD4_CLK0_OE_R_N")
			(options
				(clearance outline)
				(anchor circle)
			)
			(primitives
				(gr_poly
					(pts
						(arc
							(start -0.1778 0.5715)
							(mid -0.321484 0.511984)
							(end -0.381 0.3683)
						)
						(arc
							(start -0.381 -0.3683)
							(mid -0.321484 -0.511984)
							(end -0.1778 -0.5715)
						)
						(arc
							(start 0.1778 -0.5715)
							(mid 0.321484 -0.511984)
							(end 0.381 -0.3683)
						)
						(arc
							(start 0.381 0.3683)
							(mid 0.321484 0.511984)
							(end 0.1778 0.5715)
						)
					)
					(width 0)
					(fill yes)
				)
			)
		)
		(pad "S" smd custom
			(at 0.98425 0.9525 270)
			(size 0.1905 0.1905)
			(layers "F.Cu" "F.Mask" "F.Paste")
			(net "GND")
			(options
				(clearance outline)
				(anchor circle)
			)
			(primitives
				(gr_poly
					(pts
						(arc
							(start -0.1778 0.5715)
							(mid -0.321484 0.511984)
							(end -0.381 0.3683)
						)
						(arc
							(start -0.381 -0.3683)
							(mid -0.321484 -0.511984)
							(end -0.1778 -0.5715)
						)
						(arc
							(start 0.1778 -0.5715)
							(mid 0.321484 -0.511984)
							(end 0.381 -0.3683)
						)
						(arc
							(start 0.381 0.3683)
							(mid 0.321484 0.511984)
							(end 0.1778 0.5715)
						)
					)
					(width 0)
					(fill yes)
				)
			)
		)
	)
	(footprint ""
		(layer "F.Cu")
		(at 19.7485 -266.988544)
		(property "Reference" "SR1146"
			(at 0 0 0)
			(layer "F.SilkS")
			(hide yes)
			(effects
				(font
					(size 1.27 1.27)
				)
			)
		)
		(property "Value" "4K7R2J-2-GP"
			(at 0.064008 -3.993896 0)
			(unlocked yes)
			(layer "F.Fab")
			(hide yes)
			(effects
				(font
					(size 1.016 1.016)
					(thickness 0.1524)
				)
			)
		)
		(property "Device Type" "R402H16"
			(at 0.064008 -5.517896 0)
			(unlocked yes)
			(layer "F.Fab")
			(hide yes)
			(effects
				(font
					(size 1.016 1.016)
					(thickness 0.1524)
				)
			)
		)
		(duplicate_pad_numbers_are_jumpers no)
		(fp_line
			(start -0.508 -0.9398)
			(end -0.508 0.9398)
			(stroke
				(width 0.1524)
				(type default)
			)
			(layer "F.SilkS")
		)
		(fp_line
			(start 0.508 -0.9398)
			(end -0.508 -0.9398)
			(stroke
				(width 0.1524)
				(type default)
			)
			(layer "F.SilkS")
		)
		(fp_rect
			(start -0.508 0.9398)
			(end 0.508 -0.9398)
			(stroke
				(width 0)
				(type default)
			)
			(fill no)
			(layer "F.CrtYd")
		)
		(fp_rect
			(start -0.508 0.9398)
			(end 0.508 -0.9398)
			(stroke
				(width 0)
				(type default)
			)
			(fill no)
			(layer "F.Fab")
		)
		(pad "1" smd custom
			(at 0 -0.4445)
			(size 0.1397 0.1397)
			(layers "F.Cu" "F.Mask" "F.Paste")
			(net "P3V3")
			(options
				(clearance outline)
				(anchor circle)
			)
			(primitives
				(gr_poly
					(pts
						(arc
							(start -0.1778 -0.2794)
							(mid -0.249642 -0.249642)
							(end -0.2794 -0.1778)
						)
						(arc
							(start -0.2794 0.1778)
							(mid -0.249642 0.249642)
							(end -0.1778 0.2794)
						)
						(arc
							(start 0.1778 0.2794)
							(mid 0.249642 0.249642)
							(end 0.2794 0.1778)
						)
						(arc
							(start 0.2794 -0.1778)
							(mid 0.249642 -0.249642)
							(end 0.1778 -0.2794)
						)
					)
					(width 0)
					(fill yes)
				)
			)
		)
		(pad "2" smd custom
			(at 0 0.4445)
			(size 0.1397 0.1397)
			(layers "F.Cu" "F.Mask" "F.Paste")
			(net "SSD_ACT_DR12")
			(options
				(clearance outline)
				(anchor circle)
			)
			(primitives
				(gr_poly
					(pts
						(arc
							(start -0.1778 -0.2794)
							(mid -0.249642 -0.249642)
							(end -0.2794 -0.1778)
						)
						(arc
							(start -0.2794 0.1778)
							(mid -0.249642 0.249642)
							(end -0.1778 0.2794)
						)
						(arc
							(start 0.1778 0.2794)
							(mid 0.249642 0.249642)
							(end 0.2794 0.1778)
						)
						(arc
							(start 0.2794 -0.1778)
							(mid 0.249642 -0.249642)
							(end 0.1778 -0.2794)
						)
					)
					(width 0)
					(fill yes)
				)
			)
		)
	)
	(footprint ""
		(layer "F.Cu")
		(at 89.789 -443.865 -90)
		(property "Reference" "C9343"
			(at 0 0 270)
			(layer "F.SilkS")
			(hide yes)
			(effects
				(font
					(size 1.27 1.27)
				)
			)
		)
		(property "Value" "SC1KP50V2KX-1GP"
			(at 1.1811 -2.7051 270)
			(unlocked yes)
			(layer "F.Fab")
			(hide yes)
			(effects
				(font
					(size 1.016 1.016)
					(thickness 0.1524)
				)
			)
		)
		(property "Device Type" "C402H22"
			(at 1.1811 -4.2291 270)
			(unlocked yes)
			(layer "F.Fab")
			(hide yes)
			(effects
				(font
					(size 1.016 1.016)
					(thickness 0.1524)
				)
			)
		)
		(duplicate_pad_numbers_are_jumpers no)
		(fp_rect
			(start -0.4318 0.9525)
			(end 0.4318 -0.9525)
			(stroke
				(width 0)
				(type default)
			)
			(fill no)
			(layer "F.CrtYd")
		)
		(fp_rect
			(start -0.4318 0.9525)
			(end 0.4318 -0.9525)
			(stroke
				(width 0)
				(type default)
			)
			(fill no)
			(layer "F.Fab")
		)
		(pad "1" smd custom
			(at 0 -0.4445 270)
			(size 0.1524 0.1524)
			(layers "F.Cu" "F.Mask" "F.Paste")
			(net "SSD_PRSNT5")
			(options
				(clearance outline)
				(anchor circle)
			)
			(primitives
				(gr_poly
					(pts
						(arc
							(start 0.3048 -0.2032)
							(mid 0.275042 -0.275042)
							(end 0.2032 -0.3048)
						)
						(arc
							(start -0.2032 -0.3048)
							(mid -0.275042 -0.275042)
							(end -0.3048 -0.2032)
						)
						(arc
							(start -0.3048 0.2032)
							(mid -0.275042 0.275042)
							(end -0.2032 0.3048)
						)
						(arc
							(start 0.2032 0.3048)
							(mid 0.275042 0.275042)
							(end 0.3048 0.2032)
						)
					)
					(width 0)
					(fill yes)
				)
			)
		)
		(pad "2" smd custom
			(at 0 0.4445 270)
			(size 0.1524 0.1524)
			(layers "F.Cu" "F.Mask" "F.Paste")
			(net "GND")
			(options
				(clearance outline)
				(anchor circle)
			)
			(primitives
				(gr_poly
					(pts
						(arc
							(start 0.3048 -0.2032)
							(mid 0.275042 -0.275042)
							(end 0.2032 -0.3048)
						)
						(arc
							(start -0.2032 -0.3048)
							(mid -0.275042 -0.275042)
							(end -0.3048 -0.2032)
						)
						(arc
							(start -0.3048 0.2032)
							(mid -0.275042 0.275042)
							(end -0.2032 0.3048)
						)
						(arc
							(start 0.2032 0.3048)
							(mid 0.275042 0.275042)
							(end 0.3048 0.2032)
						)
					)
					(width 0)
					(fill yes)
				)
			)
		)
	)
	(footprint ""
		(layer "F.Cu")
		(at 82.931 -103.759 90)
		(property "Reference" "SR956"
			(at 0 0 90)
			(layer "F.SilkS")
			(hide yes)
			(effects
				(font
					(size 1.27 1.27)
				)
			)
		)
		(property "Value" "4K7R2F-GP"
			(at 0.064008 -3.993896 90)
			(unlocked yes)
			(layer "F.Fab")
			(hide yes)
			(effects
				(font
					(size 1.016 1.016)
					(thickness 0.1524)
				)
			)
		)
		(property "Device Type" "R402H16"
			(at 0.064008 -5.517896 90)
			(unlocked yes)
			(layer "F.Fab")
			(hide yes)
			(effects
				(font
					(size 1.016 1.016)
					(thickness 0.1524)
				)
			)
		)
		(duplicate_pad_numbers_are_jumpers no)
		(fp_line
			(start 0.508 -0.9398)
			(end -0.508 -0.9398)
			(stroke
				(width 0.1524)
				(type default)
			)
			(layer "F.SilkS")
		)
		(fp_line
			(start -0.508 -0.9398)
			(end -0.508 0.9398)
			(stroke
				(width 0.1524)
				(type default)
			)
			(layer "F.SilkS")
		)
		(fp_rect
			(start -0.508 0.9398)
			(end 0.508 -0.9398)
			(stroke
				(width 0)
				(type default)
			)
			(fill no)
			(layer "F.CrtYd")
		)
		(fp_rect
			(start -0.508 0.9398)
			(end 0.508 -0.9398)
			(stroke
				(width 0)
				(type default)
			)
			(fill no)
			(layer "F.Fab")
		)
		(pad "1" smd custom
			(at 0 -0.4445 90)
			(size 0.1397 0.1397)
			(layers "F.Cu" "F.Mask" "F.Paste")
			(net "VDD_DIFF_4")
			(options
				(clearance outline)
				(anchor circle)
			)
			(primitives
				(gr_poly
					(pts
						(arc
							(start -0.1778 -0.2794)
							(mid -0.249642 -0.249642)
							(end -0.2794 -0.1778)
						)
						(arc
							(start -0.2794 0.1778)
							(mid -0.249642 0.249642)
							(end -0.1778 0.2794)
						)
						(arc
							(start 0.1778 0.2794)
							(mid 0.249642 0.249642)
							(end 0.2794 0.1778)
						)
						(arc
							(start 0.2794 -0.1778)
							(mid 0.249642 -0.249642)
							(end 0.1778 -0.2794)
						)
					)
					(width 0)
					(fill yes)
				)
			)
		)
		(pad "2" smd custom
			(at 0 0.4445 90)
			(size 0.1397 0.1397)
			(layers "F.Cu" "F.Mask" "F.Paste")
			(net "P3V3_PG")
			(options
				(clearance outline)
				(anchor circle)
			)
			(primitives
				(gr_poly
					(pts
						(arc
							(start -0.1778 -0.2794)
							(mid -0.249642 -0.249642)
							(end -0.2794 -0.1778)
						)
						(arc
							(start -0.2794 0.1778)
							(mid -0.249642 0.249642)
							(end -0.1778 0.2794)
						)
						(arc
							(start 0.1778 0.2794)
							(mid 0.249642 0.249642)
							(end 0.2794 0.1778)
						)
						(arc
							(start 0.2794 -0.1778)
							(mid 0.249642 -0.249642)
							(end 0.1778 -0.2794)
						)
					)
					(width 0)
					(fill yes)
				)
			)
		)
	)
	(footprint ""
		(layer "F.Cu")
		(at 227.711 -428.752)
		(property "Reference" "PC1281"
			(at 0 0 0)
			(layer "F.SilkS")
			(hide yes)
			(effects
				(font
					(size 1.27 1.27)
				)
			)
		)
		(property "Value" "SC1U25V3KX-GP"
			(at 0 -2.8194 0)
			(unlocked yes)
			(layer "F.Fab")
			(hide yes)
			(effects
				(font
					(size 1.016 1.016)
					(thickness 0.1524)
				)
			)
		)
		(property "Device Type" "C603H36"
			(at 0 -4.3434 0)
			(unlocked yes)
			(layer "F.Fab")
			(hide yes)
			(effects
				(font
					(size 1.016 1.016)
					(thickness 0.1524)
				)
			)
		)
		(duplicate_pad_numbers_are_jumpers no)
		(fp_line
			(start 0.508 0)
			(end -0.508 0)
			(stroke
				(width 0.2032)
				(type default)
			)
			(layer "F.SilkS")
		)
		(fp_rect
			(start -0.5842 1.3335)
			(end 0.5842 -1.3335)
			(stroke
				(width 0)
				(type default)
			)
			(fill no)
			(layer "F.CrtYd")
		)
		(fp_rect
			(start -0.5842 1.3335)
			(end 0.5842 -1.3335)
			(stroke
				(width 0)
				(type default)
			)
			(fill no)
			(layer "F.Fab")
		)
		(pad "1" smd custom
			(at 0 -0.762)
			(size 0.2159 0.2159)
			(layers "F.Cu" "F.Mask" "F.Paste")
			(net "P3V3_VCC")
			(options
				(clearance outline)
				(anchor circle)
			)
			(primitives
				(gr_poly
					(pts
						(arc
							(start -0.3302 -0.4318)
							(mid -0.402042 -0.402042)
							(end -0.4318 -0.3302)
						)
						(arc
							(start -0.4318 0.3302)
							(mid -0.402042 0.402042)
							(end -0.3302 0.4318)
						)
						(arc
							(start 0.3302 0.4318)
							(mid 0.402042 0.402042)
							(end 0.4318 0.3302)
						)
						(arc
							(start 0.4318 -0.3302)
							(mid 0.402042 -0.402042)
							(end 0.3302 -0.4318)
						)
					)
					(width 0)
					(fill yes)
				)
			)
		)
		(pad "2" smd custom
			(at 0 0.762)
			(size 0.2159 0.2159)
			(layers "F.Cu" "F.Mask" "F.Paste")
			(net "AGND_P3V3")
			(options
				(clearance outline)
				(anchor circle)
			)
			(primitives
				(gr_poly
					(pts
						(arc
							(start -0.3302 -0.4318)
							(mid -0.402042 -0.402042)
							(end -0.4318 -0.3302)
						)
						(arc
							(start -0.4318 0.3302)
							(mid -0.402042 0.402042)
							(end -0.3302 0.4318)
						)
						(arc
							(start 0.3302 0.4318)
							(mid 0.402042 0.402042)
							(end 0.4318 0.3302)
						)
						(arc
							(start 0.4318 -0.3302)
							(mid 0.402042 -0.402042)
							(end 0.3302 -0.4318)
						)
					)
					(width 0)
					(fill yes)
				)
			)
		)
	)
	(footprint ""
		(layer "F.Cu")
		(at 24.253698 -463.78241 -90)
		(property "Reference" "R115"
			(at 0 0 270)
			(layer "F.SilkS")
			(hide yes)
			(effects
				(font
					(size 1.27 1.27)
				)
			)
		)
		(property "Value" "100R2J-2-GP"
			(at 0.064008 -3.993896 270)
			(unlocked yes)
			(layer "F.Fab")
			(hide yes)
			(effects
				(font
					(size 1.016 1.016)
					(thickness 0.1524)
				)
			)
		)
		(property "Device Type" "R402H14"
			(at 0.064008 -5.517896 270)
			(unlocked yes)
			(layer "F.Fab")
			(hide yes)
			(effects
				(font
					(size 1.016 1.016)
					(thickness 0.1524)
				)
			)
		)
		(duplicate_pad_numbers_are_jumpers no)
		(fp_line
			(start -0.508 -0.9398)
			(end -0.508 0.9398)
			(stroke
				(width 0.1524)
				(type default)
			)
			(layer "F.SilkS")
		)
		(fp_line
			(start 0.508 -0.9398)
			(end -0.508 -0.9398)
			(stroke
				(width 0.1524)
				(type default)
			)
			(layer "F.SilkS")
		)
		(fp_rect
			(start -0.508 0.9398)
			(end 0.508 -0.9398)
			(stroke
				(width 0)
				(type default)
			)
			(fill no)
			(layer "F.CrtYd")
		)
		(fp_rect
			(start -0.508 0.9398)
			(end 0.508 -0.9398)
			(stroke
				(width 0)
				(type default)
			)
			(fill no)
			(layer "F.Fab")
		)
		(pad "1" smd custom
			(at 0 -0.4445 270)
			(size 0.1397 0.1397)
			(layers "F.Cu" "F.Mask" "F.Paste")
			(net "P3V3")
			(options
				(clearance outline)
				(anchor circle)
			)
			(primitives
				(gr_poly
					(pts
						(arc
							(start -0.1778 -0.2794)
							(mid -0.249642 -0.249642)
							(end -0.2794 -0.1778)
						)
						(arc
							(start -0.2794 0.1778)
							(mid -0.249642 0.249642)
							(end -0.1778 0.2794)
						)
						(arc
							(start 0.1778 0.2794)
							(mid 0.249642 0.249642)
							(end 0.2794 0.1778)
						)
						(arc
							(start 0.2794 -0.1778)
							(mid 0.249642 -0.249642)
							(end 0.1778 -0.2794)
						)
					)
					(width 0)
					(fill yes)
				)
			)
		)
		(pad "2" smd custom
			(at 0 0.4445 270)
			(size 0.1397 0.1397)
			(layers "F.Cu" "F.Mask" "F.Paste")
			(net "DRV_ACT_10")
			(options
				(clearance outline)
				(anchor circle)
			)
			(primitives
				(gr_poly
					(pts
						(arc
							(start -0.1778 -0.2794)
							(mid -0.249642 -0.249642)
							(end -0.2794 -0.1778)
						)
						(arc
							(start -0.2794 0.1778)
							(mid -0.249642 0.249642)
							(end -0.1778 0.2794)
						)
						(arc
							(start 0.1778 0.2794)
							(mid 0.249642 0.249642)
							(end 0.2794 0.1778)
						)
						(arc
							(start 0.2794 -0.1778)
							(mid 0.249642 -0.249642)
							(end 0.1778 -0.2794)
						)
					)
					(width 0)
					(fill yes)
				)
			)
		)
	)
	(footprint ""
		(layer "F.Cu")
		(at 86.614 -211.963 180)
		(property "Reference" "C8916"
			(at 0 0 180)
			(layer "F.SilkS")
			(hide yes)
			(effects
				(font
					(size 1.27 1.27)
				)
			)
		)
		(property "Value" "SC1U10V2KX-7-GP"
			(at 1.1811 -2.7051 180)
			(unlocked yes)
			(layer "F.Fab")
			(hide yes)
			(effects
				(font
					(size 1.016 1.016)
					(thickness 0.1524)
				)
			)
		)
		(property "Device Type" "C402H22"
			(at 1.1811 -4.2291 180)
			(unlocked yes)
			(layer "F.Fab")
			(hide yes)
			(effects
				(font
					(size 1.016 1.016)
					(thickness 0.1524)
				)
			)
		)
		(duplicate_pad_numbers_are_jumpers no)
		(fp_rect
			(start -0.4318 0.9525)
			(end 0.4318 -0.9525)
			(stroke
				(width 0)
				(type default)
			)
			(fill no)
			(layer "F.CrtYd")
		)
		(fp_rect
			(start -0.4318 0.9525)
			(end 0.4318 -0.9525)
			(stroke
				(width 0)
				(type default)
			)
			(fill no)
			(layer "F.Fab")
		)
		(pad "1" smd custom
			(at 0 -0.4445 180)
			(size 0.1524 0.1524)
			(layers "F.Cu" "F.Mask" "F.Paste")
			(net "VDDR_3")
			(options
				(clearance outline)
				(anchor circle)
			)
			(primitives
				(gr_poly
					(pts
						(arc
							(start 0.3048 -0.2032)
							(mid 0.275042 -0.275042)
							(end 0.2032 -0.3048)
						)
						(arc
							(start -0.2032 -0.3048)
							(mid -0.275042 -0.275042)
							(end -0.3048 -0.2032)
						)
						(arc
							(start -0.3048 0.2032)
							(mid -0.275042 0.275042)
							(end -0.2032 0.3048)
						)
						(arc
							(start 0.2032 0.3048)
							(mid 0.275042 0.275042)
							(end 0.3048 0.2032)
						)
					)
					(width 0)
					(fill yes)
				)
			)
		)
		(pad "2" smd custom
			(at 0 0.4445 180)
			(size 0.1524 0.1524)
			(layers "F.Cu" "F.Mask" "F.Paste")
			(net "GND")
			(options
				(clearance outline)
				(anchor circle)
			)
			(primitives
				(gr_poly
					(pts
						(arc
							(start 0.3048 -0.2032)
							(mid 0.275042 -0.275042)
							(end 0.2032 -0.3048)
						)
						(arc
							(start -0.2032 -0.3048)
							(mid -0.275042 -0.275042)
							(end -0.3048 -0.2032)
						)
						(arc
							(start -0.3048 0.2032)
							(mid -0.275042 0.275042)
							(end -0.2032 0.3048)
						)
						(arc
							(start 0.2032 0.3048)
							(mid 0.275042 0.275042)
							(end 0.3048 0.2032)
						)
					)
					(width 0)
					(fill yes)
				)
			)
		)
	)
	(footprint ""
		(layer "F.Cu")
		(at 58.293 -241.675158 180)
		(property "Reference" "SR1135"
			(at 0 0 180)
			(layer "F.SilkS")
			(hide yes)
			(effects
				(font
					(size 1.27 1.27)
				)
			)
		)
		(property "Value" "4K7R2F-GP"
			(at 0.064008 -3.993896 180)
			(unlocked yes)
			(layer "F.Fab")
			(hide yes)
			(effects
				(font
					(size 1.016 1.016)
					(thickness 0.1524)
				)
			)
		)
		(property "Device Type" "R402H16"
			(at 0.064008 -5.517896 180)
			(unlocked yes)
			(layer "F.Fab")
			(hide yes)
			(effects
				(font
					(size 1.016 1.016)
					(thickness 0.1524)
				)
			)
		)
		(duplicate_pad_numbers_are_jumpers no)
		(fp_line
			(start 0.508 -0.9398)
			(end -0.508 -0.9398)
			(stroke
				(width 0.1524)
				(type default)
			)
			(layer "F.SilkS")
		)
		(fp_line
			(start -0.508 -0.9398)
			(end -0.508 0.9398)
			(stroke
				(width 0.1524)
				(type default)
			)
			(layer "F.SilkS")
		)
		(fp_rect
			(start -0.508 0.9398)
			(end 0.508 -0.9398)
			(stroke
				(width 0)
				(type default)
			)
			(fill no)
			(layer "F.CrtYd")
		)
		(fp_rect
			(start -0.508 0.9398)
			(end 0.508 -0.9398)
			(stroke
				(width 0)
				(type default)
			)
			(fill no)
			(layer "F.Fab")
		)
		(pad "1" smd custom
			(at 0 -0.4445 180)
			(size 0.1397 0.1397)
			(layers "F.Cu" "F.Mask" "F.Paste")
			(net "P3V3")
			(options
				(clearance outline)
				(anchor circle)
			)
			(primitives
				(gr_poly
					(pts
						(arc
							(start -0.1778 -0.2794)
							(mid -0.249642 -0.249642)
							(end -0.2794 -0.1778)
						)
						(arc
							(start -0.2794 0.1778)
							(mid -0.249642 0.249642)
							(end -0.1778 0.2794)
						)
						(arc
							(start 0.1778 0.2794)
							(mid 0.249642 0.249642)
							(end 0.2794 0.1778)
						)
						(arc
							(start 0.2794 -0.1778)
							(mid 0.249642 -0.249642)
							(end 0.1778 -0.2794)
						)
					)
					(width 0)
					(fill yes)
				)
			)
		)
		(pad "2" smd custom
			(at 0 0.4445 180)
			(size 0.1397 0.1397)
			(layers "F.Cu" "F.Mask" "F.Paste")
			(net "SSD7_CLK0_OE_MOS_N")
			(options
				(clearance outline)
				(anchor circle)
			)
			(primitives
				(gr_poly
					(pts
						(arc
							(start -0.1778 -0.2794)
							(mid -0.249642 -0.249642)
							(end -0.2794 -0.1778)
						)
						(arc
							(start -0.2794 0.1778)
							(mid -0.249642 0.249642)
							(end -0.1778 0.2794)
						)
						(arc
							(start 0.1778 0.2794)
							(mid 0.249642 0.249642)
							(end 0.2794 0.1778)
						)
						(arc
							(start 0.2794 -0.1778)
							(mid 0.249642 -0.249642)
							(end 0.1778 -0.2794)
						)
					)
					(width 0)
					(fill yes)
				)
			)
		)
	)
	(footprint ""
		(layer "F.Cu")
		(at 246.253 -425.831)
		(property "Reference" "TP2"
			(at 0 0 0)
			(layer "F.SilkS")
			(hide yes)
			(effects
				(font
					(size 1.27 1.27)
				)
			)
		)
		(property "Value" "TPAD28-2-GP"
			(at -0.0127 -1.6637 0)
			(unlocked yes)
			(layer "F.Fab")
			(hide yes)
			(effects
				(font
					(size 1.016 1.016)
					(thickness 0.1524)
				)
			)
		)
		(property "Device Type" "TPAD28"
			(at -0.0127 -3.1877 0)
			(unlocked yes)
			(layer "F.Fab")
			(hide yes)
			(effects
				(font
					(size 1.016 1.016)
					(thickness 0.1524)
				)
			)
		)
		(duplicate_pad_numbers_are_jumpers no)
		(fp_poly
			(pts
				(arc
					(start 0.3556 0)
					(mid -0.3556 0)
					(end 0.3556 0)
				)
			)
			(stroke
				(width 0)
				(type default)
			)
			(fill no)
			(layer "F.CrtYd")
		)
		(fp_poly
			(pts
				(arc
					(start 0.6096 0)
					(mid -0.6096 0)
					(end 0.6096 0)
				)
			)
			(stroke
				(width 0)
				(type default)
			)
			(fill no)
			(layer "F.Fab")
		)
		(pad "1" smd circle
			(at 0 0)
			(size 0.7112 0.7112)
			(layers "F.Cu" "F.Mask" "F.Paste")
			(net "N70930468")
		)
	)
	(footprint ""
		(layer "F.Cu")
		(at 78.5622 -305.6255)
		(property "Reference" "R9963"
			(at 0 0 0)
			(layer "F.SilkS")
			(hide yes)
			(effects
				(font
					(size 1.27 1.27)
				)
			)
		)
		(property "Value" "470R2F-GP"
			(at 0.064008 -3.993896 0)
			(unlocked yes)
			(layer "F.Fab")
			(hide yes)
			(effects
				(font
					(size 1.016 1.016)
					(thickness 0.1524)
				)
			)
		)
		(property "Device Type" "R402H16"
			(at 0.064008 -5.517896 0)
			(unlocked yes)
			(layer "F.Fab")
			(hide yes)
			(effects
				(font
					(size 1.016 1.016)
					(thickness 0.1524)
				)
			)
		)
		(duplicate_pad_numbers_are_jumpers no)
		(fp_line
			(start -0.508 -0.9398)
			(end -0.508 0.9398)
			(stroke
				(width 0.1524)
				(type default)
			)
			(layer "F.SilkS")
		)
		(fp_line
			(start 0.508 -0.9398)
			(end -0.508 -0.9398)
			(stroke
				(width 0.1524)
				(type default)
			)
			(layer "F.SilkS")
		)
		(fp_rect
			(start -0.508 0.9398)
			(end 0.508 -0.9398)
			(stroke
				(width 0)
				(type default)
			)
			(fill no)
			(layer "F.CrtYd")
		)
		(fp_rect
			(start -0.508 0.9398)
			(end 0.508 -0.9398)
			(stroke
				(width 0)
				(type default)
			)
			(fill no)
			(layer "F.Fab")
		)
		(pad "1" smd custom
			(at 0 -0.4445)
			(size 0.1397 0.1397)
			(layers "F.Cu" "F.Mask" "F.Paste")
			(net "VDD_DIFF_2")
			(options
				(clearance outline)
				(anchor circle)
			)
			(primitives
				(gr_poly
					(pts
						(arc
							(start -0.1778 -0.2794)
							(mid -0.249642 -0.249642)
							(end -0.2794 -0.1778)
						)
						(arc
							(start -0.2794 0.1778)
							(mid -0.249642 0.249642)
							(end -0.1778 0.2794)
						)
						(arc
							(start 0.1778 0.2794)
							(mid 0.249642 0.249642)
							(end 0.2794 0.1778)
						)
						(arc
							(start 0.2794 -0.1778)
							(mid 0.249642 -0.249642)
							(end 0.1778 -0.2794)
						)
					)
					(width 0)
					(fill yes)
				)
			)
		)
		(pad "2" smd custom
			(at 0 0.4445)
			(size 0.1397 0.1397)
			(layers "F.Cu" "F.Mask" "F.Paste")
			(net "PE_100M_CLK3_P")
			(options
				(clearance outline)
				(anchor circle)
			)
			(primitives
				(gr_poly
					(pts
						(arc
							(start -0.1778 -0.2794)
							(mid -0.249642 -0.249642)
							(end -0.2794 -0.1778)
						)
						(arc
							(start -0.2794 0.1778)
							(mid -0.249642 0.249642)
							(end -0.1778 0.2794)
						)
						(arc
							(start 0.1778 0.2794)
							(mid 0.249642 0.249642)
							(end 0.2794 0.1778)
						)
						(arc
							(start 0.2794 -0.1778)
							(mid 0.249642 -0.249642)
							(end 0.1778 -0.2794)
						)
					)
					(width 0)
					(fill yes)
				)
			)
		)
	)
	(footprint ""
		(layer "F.Cu")
		(at 20.850098 -438.330086 -90)
		(property "Reference" "J10"
			(at 0 0 270)
			(layer "F.SilkS")
			(hide yes)
			(effects
				(font
					(size 1.27 1.27)
				)
			)
		)
		(property "Value" "PCISLT68-14-GP-U1"
			(at -22.225 12.7508 270)
			(unlocked yes)
			(layer "F.Fab")
			(hide yes)
			(effects
				(font
					(size 1.016 1.016)
					(thickness 0.1524)
				)
			)
		)
		(property "Device Type" "SD-78827-0001"
			(at -22.225 11.2268 270)
			(unlocked yes)
			(layer "F.Fab")
			(hide yes)
			(effects
				(font
					(size 1.016 1.016)
					(thickness 0.1524)
				)
			)
		)
		(duplicate_pad_numbers_are_jumpers no)
		(fp_line
			(start -20.4724 12.0142)
			(end -20.4724 4.6736)
			(stroke
				(width 0.1524)
				(type default)
			)
			(layer "F.SilkS")
		)
		(fp_line
			(start -17.8435 12.0142)
			(end -20.4724 12.0142)
			(stroke
				(width 0.1524)
				(type default)
			)
			(layer "F.SilkS")
		)
		(fp_line
			(start 17.8435 12.0142)
			(end 17.8435 10.3124)
			(stroke
				(width 0.1524)
				(type default)
			)
			(layer "F.SilkS")
		)
		(fp_line
			(start 20.4724 12.0142)
			(end 17.8435 12.0142)
			(stroke
				(width 0.1524)
				(type default)
			)
			(layer "F.SilkS")
		)
		(fp_line
			(start -17.8435 10.3124)
			(end -17.8435 12.0142)
			(stroke
				(width 0.1524)
				(type default)
			)
			(layer "F.SilkS")
		)
		(fp_line
			(start 17.8435 10.3124)
			(end -17.8435 10.3124)
			(stroke
				(width 0.1524)
				(type default)
			)
			(layer "F.SilkS")
		)
		(fp_line
			(start -23.749 4.6736)
			(end -23.749 0.0254)
			(stroke
				(width 0.1524)
				(type default)
			)
			(layer "F.SilkS")
		)
		(fp_line
			(start -20.4724 4.6736)
			(end -23.749 4.6736)
			(stroke
				(width 0.1524)
				(type default)
			)
			(layer "F.SilkS")
		)
		(fp_line
			(start 20.4724 4.6736)
			(end 20.4724 12.0142)
			(stroke
				(width 0.1524)
				(type default)
			)
			(layer "F.SilkS")
		)
		(fp_line
			(start 23.749 4.6736)
			(end 20.4724 4.6736)
			(stroke
				(width 0.1524)
				(type default)
			)
			(layer "F.SilkS")
		)
		(fp_line
			(start -23.117556 2.896108)
			(end -23.117556 1.803908)
			(stroke
				(width 0.3048)
				(type default)
			)
			(layer "F.SilkS")
		)
		(fp_line
			(start 20.882356 2.896108)
			(end 20.882356 1.803908)
			(stroke
				(width 0.3048)
				(type default)
			)
			(layer "F.SilkS")
		)
		(fp_line
			(start -20.882356 1.803908)
			(end -20.882356 2.896108)
			(stroke
				(width 0.3048)
				(type default)
			)
			(layer "F.SilkS")
		)
		(fp_line
			(start 23.117556 1.803908)
			(end 23.117556 2.896108)
			(stroke
				(width 0.3048)
				(type default)
			)
			(layer "F.SilkS")
		)
		(fp_line
			(start -23.749 0.0254)
			(end -20.4724 0.0254)
			(stroke
				(width 0.1524)
				(type default)
			)
			(layer "F.SilkS")
		)
		(fp_line
			(start -20.4724 0.0254)
			(end -20.4724 -3.4036)
			(stroke
				(width 0.1524)
				(type default)
			)
			(layer "F.SilkS")
		)
		(fp_line
			(start 20.4724 0.0254)
			(end 23.749 0.0254)
			(stroke
				(width 0.1524)
				(type default)
			)
			(layer "F.SilkS")
		)
		(fp_line
			(start 23.749 0.0254)
			(end 23.749 4.6736)
			(stroke
				(width 0.1524)
				(type default)
			)
			(layer "F.SilkS")
		)
		(fp_line
			(start -20.4724 -3.4036)
			(end 20.4724 -3.4036)
			(stroke
				(width 0.1524)
				(type default)
			)
			(layer "F.SilkS")
		)
		(fp_line
			(start 20.4724 -3.4036)
			(end 20.4724 0.0254)
			(stroke
				(width 0.1524)
				(type default)
			)
			(layer "F.SilkS")
		)
		(fp_arc
			(start -20.882356 2.896108)
			(mid -21.999956 4.013708)
			(end -23.117556 2.896108)
			(stroke
				(width 0.3048)
				(type default)
			)
			(layer "F.SilkS")
		)
		(fp_arc
			(start 23.117556 2.896108)
			(mid 21.999956 4.013708)
			(end 20.882356 2.896108)
			(stroke
				(width 0.3048)
				(type default)
			)
			(layer "F.SilkS")
		)
		(fp_arc
			(start -23.117556 1.803908)
			(mid -21.999956 0.686308)
			(end -20.882356 1.803908)
			(stroke
				(width 0.3048)
				(type default)
			)
			(layer "F.SilkS")
		)
		(fp_arc
			(start 20.882356 1.803908)
			(mid 21.999956 0.686308)
			(end 23.117556 1.803908)
			(stroke
				(width 0.3048)
				(type default)
			)
			(layer "F.SilkS")
		)
		(fp_poly
			(pts
				(xy -20.2184 11.7602) (xy -20.2184 4.4196) (xy -23.495 4.4196) (xy -23.495 0.2794) (xy -20.2184 0.2794)
				(xy -20.2184 -3.1496) (xy 20.2184 -3.1496) (xy 20.2184 0.2794) (xy 23.495 0.2794) (xy 23.495 4.4196)
				(xy 20.2184 4.4196) (xy 20.2184 11.7602) (xy 18.0975 11.7602) (xy 18.0975 10.0584) (xy -18.0975 10.0584)
				(xy -18.0975 11.7602)
			)
			(stroke
				(width 0)
				(type default)
			)
			(fill no)
			(layer "F.CrtYd")
		)
		(fp_poly
			(pts
				(xy -21.2471 16.256) (xy -21.2471 4.9276) (xy -24.003 4.9276) (xy -24.003 -0.2286) (xy -20.7264 -0.2286)
				(xy -20.7264 -3.6576) (xy 20.7264 -3.6576) (xy 20.7264 -0.2286) (xy 24.003 -0.2286) (xy 24.003 -0.00635)
				(xy 20.2184 -0.00635) (xy 20.2184 -3.1496) (xy -20.2184 -3.1496) (xy -20.2184 0.2794) (xy -23.495 0.2794)
				(xy -23.495 4.4196) (xy -20.2184 4.4196) (xy -20.2184 11.7602) (xy -18.0975 11.7602) (xy -18.0975 10.0584)
				(xy 18.0975 10.0584) (xy 18.0975 11.7602) (xy 20.2184 11.7602) (xy 20.2184 4.4196) (xy 23.495 4.4196)
				(xy 23.495 0.2794) (xy 20.2184 0.2794) (xy 20.2184 0.00635) (xy 24.003 0.00635) (xy 24.003 4.9276)
				(xy 21.2471 4.9276) (xy 21.2471 16.256)
			)
			(stroke
				(width 0)
				(type default)
			)
			(fill no)
			(layer "F.CrtYd")
		)
		(fp_poly
			(pts
				(xy -21.2471 16.256) (xy -21.2471 4.9276) (xy -24.003 4.9276) (xy -24.003 -0.2286) (xy -20.7264 -0.2286)
				(xy -20.7264 -3.6576) (xy 20.7264 -3.6576) (xy 20.7264 -0.2286) (xy 24.003 -0.2286) (xy 24.003 4.9276)
				(xy 21.2471 4.9276) (xy 21.2471 16.256)
			)
			(stroke
				(width 0)
				(type default)
			)
			(fill no)
			(layer "F.Fab")
		)
		(pad "" np_thru_hole circle
			(at -18.999962 0 270)
			(size 0.254 0.254)
			(drill 1.8542)
			(layers "*.Cu" "*.Mask")
			(clearance 1.1557)
			(thermal_gap 1.1557)
		)
		(pad "" np_thru_hole circle
			(at 18.999962 0 270)
			(size 0.254 0.254)
			(drill 1.8542)
			(layers "*.Cu" "*.Mask")
			(clearance 1.1557)
			(thermal_gap 1.1557)
		)
		(pad "E1" smd rect
			(at -7.079996 1.240028 270)
			(size 0.508 2.0066)
			(layers "F.Cu" "F.Mask" "F.Paste")
			(net "PE_CLK100M_DR10_2_P")
		)
		(pad "E2" smd rect
			(at -6.279896 1.240028 270)
			(size 0.508 2.0066)
			(layers "F.Cu" "F.Mask" "F.Paste")
			(net "PE_CLK100M_DR10_2_N")
		)
		(pad "E3" smd rect
			(at -5.48005 1.240028 270)
			(size 0.508 2.0066)
			(layers "F.Cu" "F.Mask" "F.Paste")
			(net "P3V3")
		)
		(pad "E4" smd rect
			(at -4.67995 1.240028 270)
			(size 0.508 2.0066)
			(layers "F.Cu" "F.Mask" "F.Paste")
			(net "SSD10_PERST_N")
		)
		(pad "E5" smd rect
			(at -3.880104 1.240028 270)
			(size 0.508 2.0066)
			(layers "F.Cu" "F.Mask" "F.Paste")
			(net "SSD10_PERST_N")
		)
		(pad "E6" smd rect
			(at -3.080004 1.240028 270)
			(size 0.508 2.0066)
			(layers "F.Cu" "F.Mask" "F.Paste")
			(net "Net_1287")
		)
		(pad "E7" smd rect
			(at -15.48003 -1.949958 270)
			(size 0.508 2.0066)
			(layers "F.Cu" "F.Mask" "F.Paste")
			(net "PE_CLK100M_DR10_1_P")
		)
		(pad "E8" smd rect
			(at -14.67993 -1.949958 270)
			(size 0.508 2.0066)
			(layers "F.Cu" "F.Mask" "F.Paste")
			(net "PE_CLK100M_DR10_1_N")
		)
		(pad "E9" smd rect
			(at -13.880084 -1.949958 270)
			(size 0.508 2.0066)
			(layers "F.Cu" "F.Mask" "F.Paste")
			(net "GND")
		)
		(pad "E10" smd rect
			(at -13.079984 -1.949958 270)
			(size 0.508 2.0066)
			(layers "F.Cu" "F.Mask" "F.Paste")
			(net "PE_TX1_DR10_P")
		)
		(pad "E11" smd rect
			(at -12.279884 -1.949958 270)
			(size 0.508 2.0066)
			(layers "F.Cu" "F.Mask" "F.Paste")
			(net "PE_TX1_DR10_N")
		)
		(pad "E12" smd rect
			(at -11.480038 -1.949958 270)
			(size 0.508 2.0066)
			(layers "F.Cu" "F.Mask" "F.Paste")
			(net "GND")
		)
		(pad "E13" smd rect
			(at -10.679938 -1.949958 270)
			(size 0.508 2.0066)
			(layers "F.Cu" "F.Mask" "F.Paste")
			(net "PE_RX1_DR10_P")
		)
		(pad "E14" smd rect
			(at -9.880092 -1.949958 270)
			(size 0.508 2.0066)
			(layers "F.Cu" "F.Mask" "F.Paste")
			(net "PE_RX1_DR10_N")
		)
		(pad "E15" smd rect
			(at -9.079992 -1.949958 270)
			(size 0.508 2.0066)
			(layers "F.Cu" "F.Mask" "F.Paste")
			(net "GND")
		)
		(pad "E16" smd rect
			(at -8.279892 -1.949958 270)
			(size 0.508 2.0066)
			(layers "F.Cu" "F.Mask" "F.Paste")
			(net "Net_1294")
		)
		(pad "E17" smd rect
			(at 9.320022 -1.949958 270)
			(size 0.508 2.0066)
			(layers "F.Cu" "F.Mask" "F.Paste")
			(net "PE_TX4_DR10_P")
		)
		(pad "E18" smd rect
			(at 10.120122 -1.949958 270)
			(size 0.508 2.0066)
			(layers "F.Cu" "F.Mask" "F.Paste")
			(net "PE_TX4_DR10_N")
		)
		(pad "E19" smd rect
			(at 10.919968 -1.949958 270)
			(size 0.508 2.0066)
			(layers "F.Cu" "F.Mask" "F.Paste")
			(net "GND")
		)
		(pad "E20" smd rect
			(at 11.720068 -1.949958 270)
			(size 0.508 2.0066)
			(layers "F.Cu" "F.Mask" "F.Paste")
			(net "PE_RX4_DR10_P")
		)
		(pad "E21" smd rect
			(at 12.519914 -1.949958 270)
			(size 0.508 2.0066)
			(layers "F.Cu" "F.Mask" "F.Paste")
			(net "PE_RX4_DR10_N")
		)
		(pad "E22" smd rect
			(at 13.320014 -1.949958 270)
			(size 0.508 2.0066)
			(layers "F.Cu" "F.Mask" "F.Paste")
			(net "GND")
		)
		(pad "E23" smd rect
			(at 14.120114 -1.949958 270)
			(size 0.508 2.0066)
			(layers "F.Cu" "F.Mask" "F.Paste")
			(net "SCL_DR10_R")
		)
		(pad "E24" smd rect
			(at 14.91996 -1.949958 270)
			(size 0.508 2.0066)
			(layers "F.Cu" "F.Mask" "F.Paste")
			(net "SDA_DR10_R")
		)
		(pad "E25" smd rect
			(at 15.72006 -1.949958 270)
			(size 0.508 2.0066)
			(layers "F.Cu" "F.Mask" "F.Paste")
			(net "DUALPORTEN#10")
		)
		(pad "P1" smd rect
			(at -1.905 0.824992 270)
			(size 0.6604 2.0574)
			(layers "F.Cu" "F.Mask" "F.Paste")
			(net "Net_1290")
		)
		(pad "P2" smd rect
			(at -0.635 0.824992 270)
			(size 0.6604 2.0574)
			(layers "F.Cu" "F.Mask" "F.Paste")
			(net "Net_1289")
		)
		(pad "P3" smd rect
			(at 0.635 0.824992 270)
			(size 0.6604 2.0574)
			(layers "F.Cu" "F.Mask" "F.Paste")
			(net "Net_1288")
		)
		(pad "P4" smd rect
			(at 1.905 0.824992 270)
			(size 0.6604 2.0574)
			(layers "F.Cu" "F.Mask" "F.Paste")
			(net "SSD10_CLK0_OE_N")
		)
		(pad "P5" smd rect
			(at 3.175 0.824992 270)
			(size 0.6604 2.0574)
			(layers "F.Cu" "F.Mask" "F.Paste")
			(net "GND")
		)
		(pad "P6" smd rect
			(at 4.445 0.824992 270)
			(size 0.6604 2.0574)
			(layers "F.Cu" "F.Mask" "F.Paste")
			(net "GND")
		)
		(pad "P7" smd rect
			(at 5.715 0.824992 270)
			(size 0.6604 2.0574)
			(layers "F.Cu" "F.Mask" "F.Paste")
			(net "Net_95")
		)
		(pad "P8" smd rect
			(at 6.985 0.824992 270)
			(size 0.6604 2.0574)
			(layers "F.Cu" "F.Mask" "F.Paste")
			(net "Net_67")
		)
		(pad "P9" smd rect
			(at 8.255 0.824992 270)
			(size 0.6604 2.0574)
			(layers "F.Cu" "F.Mask" "F.Paste")
			(net "Net_81")
		)
		(pad "P10" smd rect
			(at 9.525 0.824992 270)
			(size 0.6604 2.0574)
			(layers "F.Cu" "F.Mask" "F.Paste")
			(net "SSD_PRSNT_NET10")
		)
		(pad "P11" smd rect
			(at 10.795 0.824992 270)
			(size 0.6604 2.0574)
			(layers "F.Cu" "F.Mask" "F.Paste")
			(net "SSD_ACT_DR10")
		)
		(pad "P12" smd rect
			(at 12.065 0.824992 270)
			(size 0.6604 2.0574)
			(layers "F.Cu" "F.Mask" "F.Paste")
			(net "GND")
		)
		(pad "P13" smd rect
			(at 13.335 0.824992 270)
			(size 0.6604 2.0574)
			(layers "F.Cu" "F.Mask" "F.Paste")
			(net "12V_PRECH_SSD10")
		)
		(pad "P14" smd rect
			(at 14.605 0.824992 270)
			(size 0.6604 2.0574)
			(layers "F.Cu" "F.Mask" "F.Paste")
			(net "P12V_SSD10")
		)
		(pad "P15" smd rect
			(at 15.875 0.824992 270)
			(size 0.6604 2.0574)
			(layers "F.Cu" "F.Mask" "F.Paste")
			(net "P12V_SSD10")
		)
		(pad "PTH1" thru_hole oval
			(at -21.999956 2.350008 270)
			(size 1.524 2.6162)
			(drill oval 0.8128 1.905)
			(layers "*.Cu" "*.Mask")
			(remove_unused_layers no)
			(net "Net_1299")
			(clearance 0.1524)
			(thermal_gap 0.1524)
		)
		(pad "PTH2" thru_hole oval
			(at 21.999956 2.350008 270)
			(size 1.524 2.6162)
			(drill oval 0.8128 1.905)
			(layers "*.Cu" "*.Mask")
			(remove_unused_layers no)
			(net "Net_1283")
			(clearance 0.1524)
			(thermal_gap 0.1524)
		)
		(pad "S1" smd rect
			(at -15.875 0.824992 270)
			(size 0.6604 2.0574)
			(layers "F.Cu" "F.Mask" "F.Paste")
			(net "GND")
		)
		(pad "S2" smd rect
			(at -14.605 0.824992 270)
			(size 0.6604 2.0574)
			(layers "F.Cu" "F.Mask" "F.Paste")
			(net "Net_1298")
		)
		(pad "S3" smd rect
			(at -13.335 0.824992 270)
			(size 0.6604 2.0574)
			(layers "F.Cu" "F.Mask" "F.Paste")
			(net "Net_1297")
		)
		(pad "S4" smd rect
			(at -12.065 0.824992 270)
			(size 0.6604 2.0574)
			(layers "F.Cu" "F.Mask" "F.Paste")
			(net "GND")
		)
		(pad "S5" smd rect
			(at -10.795 0.824992 270)
			(size 0.6604 2.0574)
			(layers "F.Cu" "F.Mask" "F.Paste")
			(net "Net_1296")
		)
		(pad "S6" smd rect
			(at -9.525 0.824992 270)
			(size 0.6604 2.0574)
			(layers "F.Cu" "F.Mask" "F.Paste")
			(net "Net_1295")
		)
		(pad "S7" smd rect
			(at -8.255 0.824992 270)
			(size 0.6604 2.0574)
			(layers "F.Cu" "F.Mask" "F.Paste")
			(net "GND")
		)
		(pad "S8" smd rect
			(at -7.480046 -1.949958 270)
			(size 0.508 2.0066)
			(layers "F.Cu" "F.Mask" "F.Paste")
			(net "GND")
		)
		(pad "S9" smd rect
			(at -6.679946 -1.949958 270)
			(size 0.508 2.0066)
			(layers "F.Cu" "F.Mask" "F.Paste")
			(net "Net_1293")
		)
		(pad "S10" smd rect
			(at -5.8801 -1.949958 270)
			(size 0.508 2.0066)
			(layers "F.Cu" "F.Mask" "F.Paste")
			(net "Net_1292")
		)
		(pad "S11" smd rect
			(at -5.08 -1.949958 270)
			(size 0.508 2.0066)
			(layers "F.Cu" "F.Mask" "F.Paste")
			(net "GND")
		)
		(pad "S12" smd rect
			(at -4.2799 -1.949958 270)
			(size 0.508 2.0066)
			(layers "F.Cu" "F.Mask" "F.Paste")
			(net "Net_1291")
		)
		(pad "S13" smd rect
			(at -3.480054 -1.949958 270)
			(size 0.508 2.0066)
			(layers "F.Cu" "F.Mask" "F.Paste")
			(net "Net_1286")
		)
		(pad "S14" smd rect
			(at -2.679954 -1.949958 270)
			(size 0.508 2.0066)
			(layers "F.Cu" "F.Mask" "F.Paste")
			(net "GND")
		)
		(pad "S15" smd rect
			(at -1.880108 -1.949958 270)
			(size 0.508 2.0066)
			(layers "F.Cu" "F.Mask" "F.Paste")
			(net "Net_1285")
		)
		(pad "S16" smd rect
			(at -1.080008 -1.949958 270)
			(size 0.508 2.0066)
			(layers "F.Cu" "F.Mask" "F.Paste")
			(net "GND")
		)
		(pad "S17" smd rect
			(at -0.279908 -1.949958 270)
			(size 0.508 2.0066)
			(layers "F.Cu" "F.Mask" "F.Paste")
			(net "PE_TX2_DR10_P")
		)
		(pad "S18" smd rect
			(at 0.519938 -1.949958 270)
			(size 0.508 2.0066)
			(layers "F.Cu" "F.Mask" "F.Paste")
			(net "PE_TX2_DR10_N")
		)
		(pad "S19" smd rect
			(at 1.320038 -1.949958 270)
			(size 0.508 2.0066)
			(layers "F.Cu" "F.Mask" "F.Paste")
			(net "GND")
		)
		(pad "S20" smd rect
			(at 2.119884 -1.949958 270)
			(size 0.508 2.0066)
			(layers "F.Cu" "F.Mask" "F.Paste")
			(net "PE_RX2_DR10_P")
		)
		(pad "S21" smd rect
			(at 2.919984 -1.949958 270)
			(size 0.508 2.0066)
			(layers "F.Cu" "F.Mask" "F.Paste")
			(net "PE_RX2_DR10_N")
		)
		(pad "S22" smd rect
			(at 3.720084 -1.949958 270)
			(size 0.508 2.0066)
			(layers "F.Cu" "F.Mask" "F.Paste")
			(net "GND")
		)
		(pad "S23" smd rect
			(at 4.51993 -1.949958 270)
			(size 0.508 2.0066)
			(layers "F.Cu" "F.Mask" "F.Paste")
			(net "PE_TX3_DR10_P")
		)
		(pad "S24" smd rect
			(at 5.32003 -1.949958 270)
			(size 0.508 2.0066)
			(layers "F.Cu" "F.Mask" "F.Paste")
			(net "PE_TX3_DR10_N")
		)
		(pad "S25" smd rect
			(at 6.119876 -1.949958 270)
			(size 0.508 2.0066)
			(layers "F.Cu" "F.Mask" "F.Paste")
			(net "GND")
		)
		(pad "S26" smd rect
			(at 6.919976 -1.949958 270)
			(size 0.508 2.0066)
			(layers "F.Cu" "F.Mask" "F.Paste")
			(net "PE_RX3_DR10_P")
		)
		(pad "S27" smd rect
			(at 7.720076 -1.949958 270)
			(size 0.508 2.0066)
			(layers "F.Cu" "F.Mask" "F.Paste")
			(net "PE_RX3_DR10_N")
		)
		(pad "S28" smd rect
			(at 8.519922 -1.949958 270)
			(size 0.508 2.0066)
			(layers "F.Cu" "F.Mask" "F.Paste")
			(net "GND")
		)
		(zone
			(layers "F.Cu" "B.Cu" "In1.Cu" "In2.Cu" "In3.Cu" "In4.Cu" "In5.Cu" "In6.Cu")
			(hatch none 0.5)
			(connect_pads
				(clearance 0)
			)
			(min_thickness 0.25)
			(keepout
				(tracks not_allowed)
				(vias allowed)
				(pads allowed)
				(copperpour not_allowed)
				(footprints allowed)
			)
			(placement
				(enabled no)
				(sheetname "")
			)
			(fill
				(thermal_gap 0.5)
				(thermal_bridge_width 0.5)
				(island_removal_mode 0)
			)
			(polygon
				(pts
					(arc
						(start 22.081998 -457.330048)
						(mid 19.618198 -457.330048)
						(end 22.081998 -457.330048)
					)
				)
			)
		)
		(zone
			(layers "F.Cu" "B.Cu" "In1.Cu" "In2.Cu" "In3.Cu" "In4.Cu" "In5.Cu" "In6.Cu")
			(hatch none 0.5)
			(connect_pads
				(clearance 0)
			)
			(min_thickness 0.25)
			(keepout
				(tracks not_allowed)
				(vias allowed)
				(pads allowed)
				(copperpour not_allowed)
				(footprints allowed)
			)
			(placement
				(enabled no)
				(sheetname "")
			)
			(fill
				(thermal_gap 0.5)
				(thermal_bridge_width 0.5)
				(island_removal_mode 0)
			)
			(polygon
				(pts
					(arc
						(start 22.081998 -419.330124)
						(mid 19.618198 -419.330124)
						(end 22.081998 -419.330124)
					)
				)
			)
		)
	)
	(footprint ""
		(layer "F.Cu")
		(at 24.003 -360.045 -90)
		(property "Reference" "R9903"
			(at 0 0 270)
			(layer "F.SilkS")
			(hide yes)
			(effects
				(font
					(size 1.27 1.27)
				)
			)
		)
		(property "Value" "1K82R2F-1-GP"
			(at 0.064008 -3.993896 270)
			(unlocked yes)
			(layer "F.Fab")
			(hide yes)
			(effects
				(font
					(size 1.016 1.016)
					(thickness 0.1524)
				)
			)
		)
		(property "Device Type" "R402H16"
			(at 0.064008 -5.517896 270)
			(unlocked yes)
			(layer "F.Fab")
			(hide yes)
			(effects
				(font
					(size 1.016 1.016)
					(thickness 0.1524)
				)
			)
		)
		(duplicate_pad_numbers_are_jumpers no)
		(fp_line
			(start -0.508 -0.9398)
			(end -0.508 0.9398)
			(stroke
				(width 0.1524)
				(type default)
			)
			(layer "F.SilkS")
		)
		(fp_line
			(start 0.508 -0.9398)
			(end -0.508 -0.9398)
			(stroke
				(width 0.1524)
				(type default)
			)
			(layer "F.SilkS")
		)
		(fp_rect
			(start -0.508 0.9398)
			(end 0.508 -0.9398)
			(stroke
				(width 0)
				(type default)
			)
			(fill no)
			(layer "F.CrtYd")
		)
		(fp_rect
			(start -0.508 0.9398)
			(end 0.508 -0.9398)
			(stroke
				(width 0)
				(type default)
			)
			(fill no)
			(layer "F.Fab")
		)
		(pad "1" smd custom
			(at 0 -0.4445 270)
			(size 0.1397 0.1397)
			(layers "F.Cu" "F.Mask" "F.Paste")
			(net "P12V")
			(options
				(clearance outline)
				(anchor circle)
			)
			(primitives
				(gr_poly
					(pts
						(arc
							(start -0.1778 -0.2794)
							(mid -0.249642 -0.249642)
							(end -0.2794 -0.1778)
						)
						(arc
							(start -0.2794 0.1778)
							(mid -0.249642 0.249642)
							(end -0.1778 0.2794)
						)
						(arc
							(start 0.1778 0.2794)
							(mid 0.249642 0.249642)
							(end 0.2794 0.1778)
						)
						(arc
							(start 0.2794 -0.1778)
							(mid 0.249642 -0.249642)
							(end 0.1778 -0.2794)
						)
					)
					(width 0)
					(fill yes)
				)
			)
		)
		(pad "2" smd custom
			(at 0 0.4445 270)
			(size 0.1397 0.1397)
			(layers "F.Cu" "F.Mask" "F.Paste")
			(net "DRV_ACT_11")
			(options
				(clearance outline)
				(anchor circle)
			)
			(primitives
				(gr_poly
					(pts
						(arc
							(start -0.1778 -0.2794)
							(mid -0.249642 -0.249642)
							(end -0.2794 -0.1778)
						)
						(arc
							(start -0.2794 0.1778)
							(mid -0.249642 0.249642)
							(end -0.1778 0.2794)
						)
						(arc
							(start 0.1778 0.2794)
							(mid 0.249642 0.249642)
							(end 0.2794 0.1778)
						)
						(arc
							(start 0.2794 -0.1778)
							(mid 0.249642 -0.249642)
							(end 0.1778 -0.2794)
						)
					)
					(width 0)
					(fill yes)
				)
			)
		)
	)
	(footprint ""
		(layer "F.Cu")
		(at 99.949 -215.011)
		(property "Reference" "C8862"
			(at 0 0 0)
			(layer "F.SilkS")
			(hide yes)
			(effects
				(font
					(size 1.27 1.27)
				)
			)
		)
		(property "Value" "SCD1U16V2KX-3GP"
			(at 1.1811 -2.7051 0)
			(unlocked yes)
			(layer "F.Fab")
			(hide yes)
			(effects
				(font
					(size 1.016 1.016)
					(thickness 0.1524)
				)
			)
		)
		(property "Device Type" "C402H22"
			(at 1.1811 -4.2291 0)
			(unlocked yes)
			(layer "F.Fab")
			(hide yes)
			(effects
				(font
					(size 1.016 1.016)
					(thickness 0.1524)
				)
			)
		)
		(duplicate_pad_numbers_are_jumpers no)
		(fp_rect
			(start -0.4318 0.9525)
			(end 0.4318 -0.9525)
			(stroke
				(width 0)
				(type default)
			)
			(fill no)
			(layer "F.CrtYd")
		)
		(fp_rect
			(start -0.4318 0.9525)
			(end 0.4318 -0.9525)
			(stroke
				(width 0)
				(type default)
			)
			(fill no)
			(layer "F.Fab")
		)
		(pad "1" smd custom
			(at 0 -0.4445)
			(size 0.1524 0.1524)
			(layers "F.Cu" "F.Mask" "F.Paste")
			(net "VDD_IO_3")
			(options
				(clearance outline)
				(anchor circle)
			)
			(primitives
				(gr_poly
					(pts
						(arc
							(start 0.3048 -0.2032)
							(mid 0.275042 -0.275042)
							(end 0.2032 -0.3048)
						)
						(arc
							(start -0.2032 -0.3048)
							(mid -0.275042 -0.275042)
							(end -0.3048 -0.2032)
						)
						(arc
							(start -0.3048 0.2032)
							(mid -0.275042 0.275042)
							(end -0.2032 0.3048)
						)
						(arc
							(start 0.2032 0.3048)
							(mid 0.275042 0.275042)
							(end 0.3048 0.2032)
						)
					)
					(width 0)
					(fill yes)
				)
			)
		)
		(pad "2" smd custom
			(at 0 0.4445)
			(size 0.1524 0.1524)
			(layers "F.Cu" "F.Mask" "F.Paste")
			(net "GND")
			(options
				(clearance outline)
				(anchor circle)
			)
			(primitives
				(gr_poly
					(pts
						(arc
							(start 0.3048 -0.2032)
							(mid 0.275042 -0.275042)
							(end 0.2032 -0.3048)
						)
						(arc
							(start -0.2032 -0.3048)
							(mid -0.275042 -0.275042)
							(end -0.3048 -0.2032)
						)
						(arc
							(start -0.3048 0.2032)
							(mid -0.275042 0.275042)
							(end -0.2032 0.3048)
						)
						(arc
							(start 0.2032 0.3048)
							(mid 0.275042 0.275042)
							(end 0.3048 0.2032)
						)
					)
					(width 0)
					(fill yes)
				)
			)
		)
	)
	(footprint ""
		(layer "F.Cu")
		(at 93.98 -101.6 90)
		(property "Reference" "EU4"
			(at 0 0 90)
			(layer "F.SilkS")
			(hide yes)
			(effects
				(font
					(size 1.27 1.27)
				)
			)
		)
		(property "Value" "9ZXL1231AKLFT-GP"
			(at -6.5278 -7.2009 90)
			(unlocked yes)
			(layer "F.Fab")
			(hide yes)
			(effects
				(font
					(size 1.016 1.016)
					(thickness 0.1524)
				)
			)
		)
		(property "Device Type" "QFN64G9-G6D25H40"
			(at -6.5278 -8.7249 90)
			(unlocked yes)
			(layer "F.Fab")
			(hide yes)
			(effects
				(font
					(size 1.016 1.016)
					(thickness 0.1524)
				)
			)
		)
		(duplicate_pad_numbers_are_jumpers no)
		(fp_line
			(start 1.7526 -5.71881)
			(end 1.7526 -5.21081)
			(stroke
				(width 0.1524)
				(type default)
			)
			(layer "F.SilkS")
		)
		(fp_line
			(start -3.2639 -5.71881)
			(end -3.2639 -5.21081)
			(stroke
				(width 0.1524)
				(type default)
			)
			(layer "F.SilkS")
		)
		(fp_line
			(start -3.9878 -5.5118)
			(end -5.5118 -5.5118)
			(stroke
				(width 0.1524)
				(type default)
			)
			(layer "F.SilkS")
		)
		(fp_line
			(start -5.5118 -5.5118)
			(end -5.5118 -3.9243)
			(stroke
				(width 0.1524)
				(type default)
			)
			(layer "F.SilkS")
		)
		(fp_line
			(start -0.74041 -5.21081)
			(end -0.74041 -5.97281)
			(stroke
				(width 0.1524)
				(type default)
			)
			(layer "F.SilkS")
		)
		(fp_line
			(start -5.97281 -2.2606)
			(end -5.21081 -2.2606)
			(stroke
				(width 0.1524)
				(type default)
			)
			(layer "F.SilkS")
		)
		(fp_line
			(start 5.21081 -1.778)
			(end 5.97281 -1.778)
			(stroke
				(width 0.1524)
				(type default)
			)
			(layer "F.SilkS")
		)
		(fp_line
			(start -5.21081 0.254)
			(end -5.71881 0.254)
			(stroke
				(width 0.1524)
				(type default)
			)
			(layer "F.SilkS")
		)
		(fp_line
			(start 5.71881 0.7112)
			(end 5.21081 0.7112)
			(stroke
				(width 0.1524)
				(type default)
			)
			(layer "F.SilkS")
		)
		(fp_line
			(start -5.97281 2.7432)
			(end -5.21081 2.7432)
			(stroke
				(width 0.1524)
				(type default)
			)
			(layer "F.SilkS")
		)
		(fp_line
			(start 5.21081 3.22961)
			(end 5.97281 3.22961)
			(stroke
				(width 0.1524)
				(type default)
			)
			(layer "F.SilkS")
		)
		(fp_line
			(start -5.4991 4.1148)
			(end -5.4991 5.5118)
			(stroke
				(width 0.1524)
				(type default)
			)
			(layer "F.SilkS")
		)
		(fp_line
			(start 2.2352 5.21081)
			(end 2.2352 5.71881)
			(stroke
				(width 0.1524)
				(type default)
			)
			(layer "F.SilkS")
		)
		(fp_line
			(start -2.7432 5.21081)
			(end -2.7432 5.71881)
			(stroke
				(width 0.1524)
				(type default)
			)
			(layer "F.SilkS")
		)
		(fp_line
			(start 5.5118 5.4991)
			(end 5.5118 3.9878)
			(stroke
				(width 0.1524)
				(type default)
			)
			(layer "F.SilkS")
		)
		(fp_line
			(start 4.0767 5.4991)
			(end 5.5118 5.4991)
			(stroke
				(width 0.1524)
				(type default)
			)
			(layer "F.SilkS")
		)
		(fp_line
			(start -5.4991 5.5118)
			(end -4.2037 5.5118)
			(stroke
				(width 0.1524)
				(type default)
			)
			(layer "F.SilkS")
		)
		(fp_line
			(start -0.7366 5.97281)
			(end -0.7366 5.21081)
			(stroke
				(width 0.1524)
				(type default)
			)
			(layer "F.SilkS")
		)
		(fp_poly
			(pts
				(xy 5.5118 -4.05511) (xy 4.05511 -5.5118) (xy 5.5118 -5.5118)
			)
			(stroke
				(width 0)
				(type default)
			)
			(fill yes)
			(layer "F.SilkS")
		)
		(fp_rect
			(start -4.4958 4.4958)
			(end 4.4958 -4.4958)
			(stroke
				(width 0)
				(type default)
			)
			(fill no)
			(layer "F.CrtYd")
		)
		(fp_poly
			(pts
				(xy -5.5118 5.5118) (xy -5.5118 -5.5118) (xy 5.5118 -5.5118) (xy 5.5118 -0.5461) (xy 4.4958 -0.5461)
				(xy 4.4958 -4.4958) (xy -4.4958 -4.4958) (xy -4.4958 4.4958) (xy 4.4958 4.4958) (xy 4.4958 -0.5334)
				(xy 5.5118 -0.5334) (xy 5.5118 5.5118)
			)
			(stroke
				(width 0)
				(type default)
			)
			(fill no)
			(layer "F.CrtYd")
		)
		(fp_rect
			(start -5.5118 5.5118)
			(end 5.5118 -5.5118)
			(stroke
				(width 0)
				(type default)
			)
			(fill no)
			(layer "F.Fab")
		)
		(pad "1" smd rect
			(at 3.75031 -4.550918 90)
			(size 0.3048 0.9144)
			(layers "F.Cu" "F.Mask" "F.Paste")
			(net "VDDA_4")
		)
		(pad "2" smd rect
			(at 3.24993 -4.42341 90)
			(size 0.3048 1.1684)
			(layers "F.Cu" "F.Mask" "F.Paste")
			(net "GND")
		)
		(pad "3" smd rect
			(at 2.74955 -4.42341 90)
			(size 0.3048 1.1684)
			(layers "F.Cu" "F.Mask" "F.Paste")
			(net "Net_1319")
		)
		(pad "4" smd rect
			(at 2.25044 -4.42341 90)
			(size 0.3048 1.1684)
			(layers "F.Cu" "F.Mask" "F.Paste")
			(net "CLK_BUF_EU4_100M_133M#")
		)
		(pad "5" smd rect
			(at 1.75006 -4.42341 90)
			(size 0.3048 1.1684)
			(layers "F.Cu" "F.Mask" "F.Paste")
			(net "CLK_BUF_EU4_HIBW_BYPM_LOBW#")
		)
		(pad "6" smd rect
			(at 1.24968 -4.42341 90)
			(size 0.3048 1.1684)
			(layers "F.Cu" "F.Mask" "F.Paste")
			(net "P3V3_PG")
		)
		(pad "7" smd rect
			(at 0.75057 -4.42341 90)
			(size 0.3048 1.1684)
			(layers "F.Cu" "F.Mask" "F.Paste")
			(net "GND")
		)
		(pad "8" smd rect
			(at 0.25019 -4.42341 90)
			(size 0.3048 1.1684)
			(layers "F.Cu" "F.Mask" "F.Paste")
			(net "VDDR_4")
		)
		(pad "9" smd rect
			(at -0.25019 -4.42341 90)
			(size 0.3048 1.1684)
			(layers "F.Cu" "F.Mask" "F.Paste")
			(net "PE_100M_CLK1_P")
		)
		(pad "10" smd rect
			(at -0.75057 -4.42341 90)
			(size 0.3048 1.1684)
			(layers "F.Cu" "F.Mask" "F.Paste")
			(net "PE_100M_CLK1_N")
		)
		(pad "11" smd rect
			(at -1.24968 -4.42341 90)
			(size 0.3048 1.1684)
			(layers "F.Cu" "F.Mask" "F.Paste")
			(net "CLK_BUF_EU4_SMB_A0_TRI")
		)
		(pad "12" smd rect
			(at -1.75006 -4.42341 90)
			(size 0.3048 1.1684)
			(layers "F.Cu" "F.Mask" "F.Paste")
			(net "I2C_SDA_BUF_8_EU4_R")
		)
		(pad "13" smd rect
			(at -2.25044 -4.42341 90)
			(size 0.3048 1.1684)
			(layers "F.Cu" "F.Mask" "F.Paste")
			(net "I2C_SCL_BUF_8_EU4_R")
		)
		(pad "14" smd rect
			(at -2.74955 -4.42341 90)
			(size 0.3048 1.1684)
			(layers "F.Cu" "F.Mask" "F.Paste")
			(net "CLK_BUF_EU4_SMB_A1_TRI")
		)
		(pad "15" smd rect
			(at -3.24993 -4.42341 90)
			(size 0.3048 1.1684)
			(layers "F.Cu" "F.Mask" "F.Paste")
			(net "Net_1325")
		)
		(pad "16" smd rect
			(at -3.75031 -4.550918 90)
			(size 0.3048 0.9144)
			(layers "F.Cu" "F.Mask" "F.Paste")
			(net "Net_1324")
		)
		(pad "17" smd rect
			(at -4.550918 -3.75031 90)
			(size 0.9144 0.3048)
			(layers "F.Cu" "F.Mask" "F.Paste")
			(net "PE_CLK_100M_DR9_2_R_P")
		)
		(pad "18" smd rect
			(at -4.42341 -3.24993 90)
			(size 1.1684 0.3048)
			(layers "F.Cu" "F.Mask" "F.Paste")
			(net "PE_CLK_100M_DR9_2_R_N")
		)
		(pad "19" smd rect
			(at -4.42341 -2.74955 90)
			(size 1.1684 0.3048)
			(layers "F.Cu" "F.Mask" "F.Paste")
			(net "SSD_PRSNT9")
		)
		(pad "20" smd rect
			(at -4.42341 -2.25044 90)
			(size 1.1684 0.3048)
			(layers "F.Cu" "F.Mask" "F.Paste")
			(net "SSD9_CLK0_OE_R_N")
		)
		(pad "21" smd rect
			(at -4.42341 -1.75006 90)
			(size 1.1684 0.3048)
			(layers "F.Cu" "F.Mask" "F.Paste")
			(net "PE_CLK_100M_DR9_1_R_P")
		)
		(pad "22" smd rect
			(at -4.42341 -1.24968 90)
			(size 1.1684 0.3048)
			(layers "F.Cu" "F.Mask" "F.Paste")
			(net "PE_CLK_100M_DR9_1_R_N")
		)
		(pad "23" smd rect
			(at -4.42341 -0.75057 90)
			(size 1.1684 0.3048)
			(layers "F.Cu" "F.Mask" "F.Paste")
			(net "GND")
		)
		(pad "24" smd rect
			(at -4.42341 -0.25019 90)
			(size 1.1684 0.3048)
			(layers "F.Cu" "F.Mask" "F.Paste")
			(net "VDD_DIFF_4")
		)
		(pad "25" smd rect
			(at -4.42341 0.25019 90)
			(size 1.1684 0.3048)
			(layers "F.Cu" "F.Mask" "F.Paste")
			(net "VDD_IO_4")
		)
		(pad "26" smd rect
			(at -4.42341 0.75057 90)
			(size 1.1684 0.3048)
			(layers "F.Cu" "F.Mask" "F.Paste")
			(net "PE_CLK_100M_DR14_2_R_P")
		)
		(pad "27" smd rect
			(at -4.42341 1.24968 90)
			(size 1.1684 0.3048)
			(layers "F.Cu" "F.Mask" "F.Paste")
			(net "PE_CLK_100M_DR14_2_R_N")
		)
		(pad "28" smd rect
			(at -4.42341 1.75006 90)
			(size 1.1684 0.3048)
			(layers "F.Cu" "F.Mask" "F.Paste")
			(net "SSD_PRSNT14")
		)
		(pad "29" smd rect
			(at -4.42341 2.25044 90)
			(size 1.1684 0.3048)
			(layers "F.Cu" "F.Mask" "F.Paste")
			(net "SSD14_CLK0_OE_R_N")
		)
		(pad "30" smd rect
			(at -4.42341 2.74955 90)
			(size 1.1684 0.3048)
			(layers "F.Cu" "F.Mask" "F.Paste")
			(net "PE_CLK_100M_DR14_1_R_P")
		)
		(pad "31" smd rect
			(at -4.42341 3.24993 90)
			(size 1.1684 0.3048)
			(layers "F.Cu" "F.Mask" "F.Paste")
			(net "PE_CLK_100M_DR14_1_R_N")
		)
		(pad "32" smd rect
			(at -4.550918 3.75031 90)
			(size 0.9144 0.3048)
			(layers "F.Cu" "F.Mask" "F.Paste")
			(net "VDD_IO_4")
		)
		(pad "33" smd rect
			(at -3.75031 4.550918 90)
			(size 0.3048 0.9144)
			(layers "F.Cu" "F.Mask" "F.Paste")
			(net "GND")
		)
		(pad "34" smd rect
			(at -3.24993 4.42341 90)
			(size 0.3048 1.1684)
			(layers "F.Cu" "F.Mask" "F.Paste")
			(net "Net_317")
		)
		(pad "35" smd rect
			(at -2.74955 4.42341 90)
			(size 0.3048 1.1684)
			(layers "F.Cu" "F.Mask" "F.Paste")
			(net "Net_316")
		)
		(pad "36" smd rect
			(at -2.25044 4.42341 90)
			(size 0.3048 1.1684)
			(layers "F.Cu" "F.Mask" "F.Paste")
			(net "CLK_BUFFER_EU4_VOE_N")
		)
		(pad "37" smd rect
			(at -1.75006 4.42341 90)
			(size 0.3048 1.1684)
			(layers "F.Cu" "F.Mask" "F.Paste")
			(net "CLK_BUFFER_EU4_VOE_N")
		)
		(pad "38" smd rect
			(at -1.24968 4.42341 90)
			(size 0.3048 1.1684)
			(layers "F.Cu" "F.Mask" "F.Paste")
			(net "Net_319")
		)
		(pad "39" smd rect
			(at -0.75057 4.42341 90)
			(size 0.3048 1.1684)
			(layers "F.Cu" "F.Mask" "F.Paste")
			(net "Net_318")
		)
		(pad "40" smd rect
			(at -0.25019 4.42341 90)
			(size 0.3048 1.1684)
			(layers "F.Cu" "F.Mask" "F.Paste")
			(net "VDD_DIFF_4")
		)
		(pad "41" smd rect
			(at 0.25019 4.42341 90)
			(size 0.3048 1.1684)
			(layers "F.Cu" "F.Mask" "F.Paste")
			(net "GND")
		)
		(pad "42" smd rect
			(at 0.75057 4.42341 90)
			(size 0.3048 1.1684)
			(layers "F.Cu" "F.Mask" "F.Paste")
			(net "Net_1320")
		)
		(pad "43" smd rect
			(at 1.24968 4.42341 90)
			(size 0.3048 1.1684)
			(layers "F.Cu" "F.Mask" "F.Paste")
			(net "Net_1321")
		)
		(pad "44" smd rect
			(at 1.75006 4.42341 90)
			(size 0.3048 1.1684)
			(layers "F.Cu" "F.Mask" "F.Paste")
			(net "CLK_BUFFER_EU4_VOE_N")
		)
		(pad "45" smd rect
			(at 2.25044 4.42341 90)
			(size 0.3048 1.1684)
			(layers "F.Cu" "F.Mask" "F.Paste")
			(net "CLK_BUFFER_EU4_VOE_N")
		)
		(pad "46" smd rect
			(at 2.74955 4.42341 90)
			(size 0.3048 1.1684)
			(layers "F.Cu" "F.Mask" "F.Paste")
			(net "Net_1322")
		)
		(pad "47" smd rect
			(at 3.24993 4.42341 90)
			(size 0.3048 1.1684)
			(layers "F.Cu" "F.Mask" "F.Paste")
			(net "Net_1323")
		)
		(pad "48" smd rect
			(at 3.75031 4.550918 90)
			(size 0.3048 0.9144)
			(layers "F.Cu" "F.Mask" "F.Paste")
			(net "GND")
		)
		(pad "49" smd rect
			(at 4.550918 3.75031 90)
			(size 0.9144 0.3048)
			(layers "F.Cu" "F.Mask" "F.Paste")
			(net "VDD_IO_4")
		)
		(pad "50" smd rect
			(at 4.42341 3.24993 90)
			(size 1.1684 0.3048)
			(layers "F.Cu" "F.Mask" "F.Paste")
			(net "PE_CLK_100M_DR8_2_R_P")
		)
		(pad "51" smd rect
			(at 4.42341 2.74955 90)
			(size 1.1684 0.3048)
			(layers "F.Cu" "F.Mask" "F.Paste")
			(net "PE_CLK_100M_DR8_2_R_N")
		)
		(pad "52" smd rect
			(at 4.42341 2.25044 90)
			(size 1.1684 0.3048)
			(layers "F.Cu" "F.Mask" "F.Paste")
			(net "SSD_PRSNT8")
		)
		(pad "53" smd rect
			(at 4.42341 1.75006 90)
			(size 1.1684 0.3048)
			(layers "F.Cu" "F.Mask" "F.Paste")
			(net "SSD8_CLK0_OE_R_N")
		)
		(pad "54" smd rect
			(at 4.42341 1.24968 90)
			(size 1.1684 0.3048)
			(layers "F.Cu" "F.Mask" "F.Paste")
			(net "PE_CLK_100M_DR8_1_R_P")
		)
		(pad "55" smd rect
			(at 4.42341 0.75057 90)
			(size 1.1684 0.3048)
			(layers "F.Cu" "F.Mask" "F.Paste")
			(net "PE_CLK_100M_DR8_1_R_N")
		)
		(pad "56" smd rect
			(at 4.42341 0.25019 90)
			(size 1.1684 0.3048)
			(layers "F.Cu" "F.Mask" "F.Paste")
			(net "VDD_IO_4")
		)
		(pad "57" smd rect
			(at 4.42341 -0.25019 90)
			(size 1.1684 0.3048)
			(layers "F.Cu" "F.Mask" "F.Paste")
			(net "VDD_DIFF_4")
		)
		(pad "58" smd rect
			(at 4.42341 -0.75057 90)
			(size 1.1684 0.3048)
			(layers "F.Cu" "F.Mask" "F.Paste")
			(net "GND")
		)
		(pad "59" smd rect
			(at 4.42341 -1.24968 90)
			(size 1.1684 0.3048)
			(layers "F.Cu" "F.Mask" "F.Paste")
			(net "PE_CLK_100M_DR13_2_R_P")
		)
		(pad "60" smd rect
			(at 4.42341 -1.75006 90)
			(size 1.1684 0.3048)
			(layers "F.Cu" "F.Mask" "F.Paste")
			(net "PE_CLK_100M_DR13_2_R_N")
		)
		(pad "61" smd rect
			(at 4.42341 -2.25044 90)
			(size 1.1684 0.3048)
			(layers "F.Cu" "F.Mask" "F.Paste")
			(net "SSD_PRSNT13")
		)
		(pad "62" smd rect
			(at 4.42341 -2.74955 90)
			(size 1.1684 0.3048)
			(layers "F.Cu" "F.Mask" "F.Paste")
			(net "SSD13_CLK0_OE_R_N")
		)
		(pad "63" smd rect
			(at 4.42341 -3.24993 90)
			(size 1.1684 0.3048)
			(layers "F.Cu" "F.Mask" "F.Paste")
			(net "PE_CLK_100M_DR13_1_R_P")
		)
		(pad "64" smd rect
			(at 4.550918 -3.75031 90)
			(size 0.9144 0.3048)
			(layers "F.Cu" "F.Mask" "F.Paste")
			(net "PE_CLK_100M_DR13_1_R_N")
		)
		(pad "65" smd rect
			(at 0 0 90)
			(size 6.2484 6.2484)
			(layers "F.Cu" "F.Mask" "F.Paste")
			(net "GND")
		)
	)
	(footprint ""
		(layer "F.Cu")
		(at 98.298 -425.831 90)
		(property "Reference" "C8838"
			(at 0 0 90)
			(layer "F.SilkS")
			(hide yes)
			(effects
				(font
					(size 1.27 1.27)
				)
			)
		)
		(property "Value" "SCD1U16V2KX-3GP"
			(at 1.1811 -2.7051 90)
			(unlocked yes)
			(layer "F.Fab")
			(hide yes)
			(effects
				(font
					(size 1.016 1.016)
					(thickness 0.1524)
				)
			)
		)
		(property "Device Type" "C402H22"
			(at 1.1811 -4.2291 90)
			(unlocked yes)
			(layer "F.Fab")
			(hide yes)
			(effects
				(font
					(size 1.016 1.016)
					(thickness 0.1524)
				)
			)
		)
		(duplicate_pad_numbers_are_jumpers no)
		(fp_rect
			(start -0.4318 0.9525)
			(end 0.4318 -0.9525)
			(stroke
				(width 0)
				(type default)
			)
			(fill no)
			(layer "F.CrtYd")
		)
		(fp_rect
			(start -0.4318 0.9525)
			(end 0.4318 -0.9525)
			(stroke
				(width 0)
				(type default)
			)
			(fill no)
			(layer "F.Fab")
		)
		(pad "1" smd custom
			(at 0 -0.4445 90)
			(size 0.1524 0.1524)
			(layers "F.Cu" "F.Mask" "F.Paste")
			(net "VDD_IO_1")
			(options
				(clearance outline)
				(anchor circle)
			)
			(primitives
				(gr_poly
					(pts
						(arc
							(start 0.3048 -0.2032)
							(mid 0.275042 -0.275042)
							(end 0.2032 -0.3048)
						)
						(arc
							(start -0.2032 -0.3048)
							(mid -0.275042 -0.275042)
							(end -0.3048 -0.2032)
						)
						(arc
							(start -0.3048 0.2032)
							(mid -0.275042 0.275042)
							(end -0.2032 0.3048)
						)
						(arc
							(start 0.2032 0.3048)
							(mid 0.275042 0.275042)
							(end 0.3048 0.2032)
						)
					)
					(width 0)
					(fill yes)
				)
			)
		)
		(pad "2" smd custom
			(at 0 0.4445 90)
			(size 0.1524 0.1524)
			(layers "F.Cu" "F.Mask" "F.Paste")
			(net "GND")
			(options
				(clearance outline)
				(anchor circle)
			)
			(primitives
				(gr_poly
					(pts
						(arc
							(start 0.3048 -0.2032)
							(mid 0.275042 -0.275042)
							(end 0.2032 -0.3048)
						)
						(arc
							(start -0.2032 -0.3048)
							(mid -0.275042 -0.275042)
							(end -0.3048 -0.2032)
						)
						(arc
							(start -0.3048 0.2032)
							(mid -0.275042 0.275042)
							(end -0.2032 0.3048)
						)
						(arc
							(start 0.2032 0.3048)
							(mid 0.275042 0.275042)
							(end 0.3048 0.2032)
						)
					)
					(width 0)
					(fill yes)
				)
			)
		)
	)
	(footprint ""
		(layer "F.Cu")
		(at 38.989 -144.653 90)
		(property "Reference" "C9526"
			(at 0 0 90)
			(layer "F.SilkS")
			(hide yes)
			(effects
				(font
					(size 1.27 1.27)
				)
			)
		)
		(property "Value" "SCD1U16V2KX-3GP"
			(at 1.1811 -2.7051 90)
			(unlocked yes)
			(layer "F.Fab")
			(hide yes)
			(effects
				(font
					(size 1.016 1.016)
					(thickness 0.1524)
				)
			)
		)
		(property "Device Type" "C402H22"
			(at 1.1811 -4.2291 90)
			(unlocked yes)
			(layer "F.Fab")
			(hide yes)
			(effects
				(font
					(size 1.016 1.016)
					(thickness 0.1524)
				)
			)
		)
		(duplicate_pad_numbers_are_jumpers no)
		(fp_rect
			(start -0.4318 0.9525)
			(end 0.4318 -0.9525)
			(stroke
				(width 0)
				(type default)
			)
			(fill no)
			(layer "F.CrtYd")
		)
		(fp_rect
			(start -0.4318 0.9525)
			(end 0.4318 -0.9525)
			(stroke
				(width 0)
				(type default)
			)
			(fill no)
			(layer "F.Fab")
		)
		(pad "1" smd custom
			(at 0 -0.4445 90)
			(size 0.1524 0.1524)
			(layers "F.Cu" "F.Mask" "F.Paste")
			(net "P3V3")
			(options
				(clearance outline)
				(anchor circle)
			)
			(primitives
				(gr_poly
					(pts
						(arc
							(start 0.3048 -0.2032)
							(mid 0.275042 -0.275042)
							(end 0.2032 -0.3048)
						)
						(arc
							(start -0.2032 -0.3048)
							(mid -0.275042 -0.275042)
							(end -0.3048 -0.2032)
						)
						(arc
							(start -0.3048 0.2032)
							(mid -0.275042 0.275042)
							(end -0.2032 0.3048)
						)
						(arc
							(start 0.2032 0.3048)
							(mid 0.275042 0.275042)
							(end 0.3048 0.2032)
						)
					)
					(width 0)
					(fill yes)
				)
			)
		)
		(pad "2" smd custom
			(at 0 0.4445 90)
			(size 0.1524 0.1524)
			(layers "F.Cu" "F.Mask" "F.Paste")
			(net "GND")
			(options
				(clearance outline)
				(anchor circle)
			)
			(primitives
				(gr_poly
					(pts
						(arc
							(start 0.3048 -0.2032)
							(mid 0.275042 -0.275042)
							(end 0.2032 -0.3048)
						)
						(arc
							(start -0.2032 -0.3048)
							(mid -0.275042 -0.275042)
							(end -0.3048 -0.2032)
						)
						(arc
							(start -0.3048 0.2032)
							(mid -0.275042 0.275042)
							(end -0.2032 0.3048)
						)
						(arc
							(start 0.2032 0.3048)
							(mid 0.275042 0.275042)
							(end 0.3048 0.2032)
						)
					)
					(width 0)
					(fill yes)
				)
			)
		)
	)
	(footprint ""
		(layer "F.Cu")
		(at 77.5208 -303.7205)
		(property "Reference" "R9966"
			(at 0 0 0)
			(layer "F.SilkS")
			(hide yes)
			(effects
				(font
					(size 1.27 1.27)
				)
			)
		)
		(property "Value" "56R2F-1-GP"
			(at 0.064008 -3.993896 0)
			(unlocked yes)
			(layer "F.Fab")
			(hide yes)
			(effects
				(font
					(size 1.016 1.016)
					(thickness 0.1524)
				)
			)
		)
		(property "Device Type" "R402H16"
			(at 0.064008 -5.517896 0)
			(unlocked yes)
			(layer "F.Fab")
			(hide yes)
			(effects
				(font
					(size 1.016 1.016)
					(thickness 0.1524)
				)
			)
		)
		(duplicate_pad_numbers_are_jumpers no)
		(fp_line
			(start -0.508 -0.9398)
			(end -0.508 0.9398)
			(stroke
				(width 0.1524)
				(type default)
			)
			(layer "F.SilkS")
		)
		(fp_line
			(start 0.508 -0.9398)
			(end -0.508 -0.9398)
			(stroke
				(width 0.1524)
				(type default)
			)
			(layer "F.SilkS")
		)
		(fp_rect
			(start -0.508 0.9398)
			(end 0.508 -0.9398)
			(stroke
				(width 0)
				(type default)
			)
			(fill no)
			(layer "F.CrtYd")
		)
		(fp_rect
			(start -0.508 0.9398)
			(end 0.508 -0.9398)
			(stroke
				(width 0)
				(type default)
			)
			(fill no)
			(layer "F.Fab")
		)
		(pad "1" smd custom
			(at 0 -0.4445)
			(size 0.1397 0.1397)
			(layers "F.Cu" "F.Mask" "F.Paste")
			(net "PE_100M_CLK3_N")
			(options
				(clearance outline)
				(anchor circle)
			)
			(primitives
				(gr_poly
					(pts
						(arc
							(start -0.1778 -0.2794)
							(mid -0.249642 -0.249642)
							(end -0.2794 -0.1778)
						)
						(arc
							(start -0.2794 0.1778)
							(mid -0.249642 0.249642)
							(end -0.1778 0.2794)
						)
						(arc
							(start 0.1778 0.2794)
							(mid 0.249642 0.249642)
							(end 0.2794 0.1778)
						)
						(arc
							(start 0.2794 -0.1778)
							(mid 0.249642 -0.249642)
							(end 0.1778 -0.2794)
						)
					)
					(width 0)
					(fill yes)
				)
			)
		)
		(pad "2" smd custom
			(at 0 0.4445)
			(size 0.1397 0.1397)
			(layers "F.Cu" "F.Mask" "F.Paste")
			(net "GND")
			(options
				(clearance outline)
				(anchor circle)
			)
			(primitives
				(gr_poly
					(pts
						(arc
							(start -0.1778 -0.2794)
							(mid -0.249642 -0.249642)
							(end -0.2794 -0.1778)
						)
						(arc
							(start -0.2794 0.1778)
							(mid -0.249642 0.249642)
							(end -0.1778 0.2794)
						)
						(arc
							(start 0.1778 0.2794)
							(mid 0.249642 0.249642)
							(end 0.2794 0.1778)
						)
						(arc
							(start 0.2794 -0.1778)
							(mid 0.249642 -0.249642)
							(end 0.1778 -0.2794)
						)
					)
					(width 0)
					(fill yes)
				)
			)
		)
	)
	(footprint ""
		(layer "F.Cu")
		(at 213.741 -454.66 180)
		(property "Reference" "R315"
			(at 0 0 180)
			(layer "F.SilkS")
			(hide yes)
			(effects
				(font
					(size 1.27 1.27)
				)
			)
		)
		(property "Value" "4K7R2F-GP"
			(at 0.064008 -3.993896 180)
			(unlocked yes)
			(layer "F.Fab")
			(hide yes)
			(effects
				(font
					(size 1.016 1.016)
					(thickness 0.1524)
				)
			)
		)
		(property "Device Type" "R402H16"
			(at 0.064008 -5.517896 180)
			(unlocked yes)
			(layer "F.Fab")
			(hide yes)
			(effects
				(font
					(size 1.016 1.016)
					(thickness 0.1524)
				)
			)
		)
		(duplicate_pad_numbers_are_jumpers no)
		(fp_line
			(start 0.508 -0.9398)
			(end -0.508 -0.9398)
			(stroke
				(width 0.1524)
				(type default)
			)
			(layer "F.SilkS")
		)
		(fp_line
			(start -0.508 -0.9398)
			(end -0.508 0.9398)
			(stroke
				(width 0.1524)
				(type default)
			)
			(layer "F.SilkS")
		)
		(fp_rect
			(start -0.508 0.9398)
			(end 0.508 -0.9398)
			(stroke
				(width 0)
				(type default)
			)
			(fill no)
			(layer "F.CrtYd")
		)
		(fp_rect
			(start -0.508 0.9398)
			(end 0.508 -0.9398)
			(stroke
				(width 0)
				(type default)
			)
			(fill no)
			(layer "F.Fab")
		)
		(pad "1" smd custom
			(at 0 -0.4445 180)
			(size 0.1397 0.1397)
			(layers "F.Cu" "F.Mask" "F.Paste")
			(net "P3V3")
			(options
				(clearance outline)
				(anchor circle)
			)
			(primitives
				(gr_poly
					(pts
						(arc
							(start -0.1778 -0.2794)
							(mid -0.249642 -0.249642)
							(end -0.2794 -0.1778)
						)
						(arc
							(start -0.2794 0.1778)
							(mid -0.249642 0.249642)
							(end -0.1778 0.2794)
						)
						(arc
							(start 0.1778 0.2794)
							(mid 0.249642 0.249642)
							(end 0.2794 0.1778)
						)
						(arc
							(start 0.2794 -0.1778)
							(mid 0.249642 -0.249642)
							(end 0.1778 -0.2794)
						)
					)
					(width 0)
					(fill yes)
				)
			)
		)
		(pad "2" smd custom
			(at 0 0.4445 180)
			(size 0.1397 0.1397)
			(layers "F.Cu" "F.Mask" "F.Paste")
			(net "I2C_B_TMP2_A2")
			(options
				(clearance outline)
				(anchor circle)
			)
			(primitives
				(gr_poly
					(pts
						(arc
							(start -0.1778 -0.2794)
							(mid -0.249642 -0.249642)
							(end -0.2794 -0.1778)
						)
						(arc
							(start -0.2794 0.1778)
							(mid -0.249642 0.249642)
							(end -0.1778 0.2794)
						)
						(arc
							(start 0.1778 0.2794)
							(mid 0.249642 0.249642)
							(end 0.2794 0.1778)
						)
						(arc
							(start 0.2794 -0.1778)
							(mid 0.249642 -0.249642)
							(end 0.1778 -0.2794)
						)
					)
					(width 0)
					(fill yes)
				)
			)
		)
	)
	(footprint ""
		(layer "F.Cu")
		(at 27.0256 -316.6872 180)
		(property "Reference" "PC1221"
			(at 0 0 180)
			(layer "F.SilkS")
			(hide yes)
			(effects
				(font
					(size 1.27 1.27)
				)
			)
		)
		(property "Value" "SC22U25V6KX-GP-U"
			(at -2.860802 -5.279644 180)
			(unlocked yes)
			(layer "F.Fab")
			(hide yes)
			(effects
				(font
					(size 1.016 1.016)
					(thickness 0.1524)
				)
			)
		)
		(property "Device Type" "C1206-TO0D3H75"
			(at -2.860802 -6.803644 180)
			(unlocked yes)
			(layer "F.Fab")
			(hide yes)
			(effects
				(font
					(size 1.016 1.016)
					(thickness 0.1524)
				)
			)
		)
		(duplicate_pad_numbers_are_jumpers no)
		(fp_line
			(start 1.3081 2.3749)
			(end -1.3081 2.3749)
			(stroke
				(width 0.1524)
				(type default)
			)
			(layer "F.SilkS")
		)
		(fp_line
			(start 1.3081 -2.3749)
			(end 1.3081 2.3749)
			(stroke
				(width 0.1524)
				(type default)
			)
			(layer "F.SilkS")
		)
		(fp_line
			(start -1.3081 2.3749)
			(end -1.3081 -2.3749)
			(stroke
				(width 0.1524)
				(type default)
			)
			(layer "F.SilkS")
		)
		(fp_line
			(start -1.3081 -2.3749)
			(end 1.3081 -2.3749)
			(stroke
				(width 0.1524)
				(type default)
			)
			(layer "F.SilkS")
		)
		(fp_rect
			(start -0.8001 1.6002)
			(end 0.8001 -1.6002)
			(stroke
				(width 0)
				(type default)
			)
			(fill no)
			(layer "F.CrtYd")
		)
		(fp_poly
			(pts
				(xy -1.5621 2.4511) (xy -1.5621 1.6002) (xy 0.8001 1.6002) (xy 0.8001 -1.6002) (xy -0.8001 -1.6002)
				(xy -0.8001 1.5875) (xy -1.5621 1.5875) (xy -1.5621 -2.4511) (xy 1.5621 -2.4511) (xy 1.5621 2.4511)
			)
			(stroke
				(width 0)
				(type default)
			)
			(fill no)
			(layer "F.CrtYd")
		)
		(fp_rect
			(start -1.5621 2.4511)
			(end 1.5621 -2.4511)
			(stroke
				(width 0)
				(type default)
			)
			(fill no)
			(layer "F.Fab")
		)
		(pad "1" smd rect
			(at 0 -1.392936 180)
			(size 2.1082 1.4478)
			(layers "F.Cu" "F.Mask" "F.Paste")
			(net "P12V_SSD11")
		)
		(pad "2" smd rect
			(at 0 1.392936 180)
			(size 2.1082 1.4478)
			(layers "F.Cu" "F.Mask" "F.Paste")
			(net "GND")
		)
	)
	(footprint ""
		(layer "F.Cu")
		(at 19.7485 -264.81913 180)
		(property "Reference" "R9863"
			(at 0 0 180)
			(layer "F.SilkS")
			(hide yes)
			(effects
				(font
					(size 1.27 1.27)
				)
			)
		)
		(property "Value" "0R2J-2-GP"
			(at 0.064008 -3.993896 180)
			(unlocked yes)
			(layer "F.Fab")
			(hide yes)
			(effects
				(font
					(size 1.016 1.016)
					(thickness 0.1524)
				)
			)
		)
		(property "Device Type" "R402H16"
			(at 0.064008 -5.517896 180)
			(unlocked yes)
			(layer "F.Fab")
			(hide yes)
			(effects
				(font
					(size 1.016 1.016)
					(thickness 0.1524)
				)
			)
		)
		(duplicate_pad_numbers_are_jumpers no)
		(fp_line
			(start 0.508 -0.9398)
			(end -0.508 -0.9398)
			(stroke
				(width 0.1524)
				(type default)
			)
			(layer "F.SilkS")
		)
		(fp_line
			(start -0.508 -0.9398)
			(end -0.508 0.9398)
			(stroke
				(width 0.1524)
				(type default)
			)
			(layer "F.SilkS")
		)
		(fp_rect
			(start -0.508 0.9398)
			(end 0.508 -0.9398)
			(stroke
				(width 0)
				(type default)
			)
			(fill no)
			(layer "F.CrtYd")
		)
		(fp_rect
			(start -0.508 0.9398)
			(end 0.508 -0.9398)
			(stroke
				(width 0)
				(type default)
			)
			(fill no)
			(layer "F.Fab")
		)
		(pad "1" smd custom
			(at 0 -0.4445 180)
			(size 0.1397 0.1397)
			(layers "F.Cu" "F.Mask" "F.Paste")
			(net "SSD_ACT_DR12_R")
			(options
				(clearance outline)
				(anchor circle)
			)
			(primitives
				(gr_poly
					(pts
						(arc
							(start -0.1778 -0.2794)
							(mid -0.249642 -0.249642)
							(end -0.2794 -0.1778)
						)
						(arc
							(start -0.2794 0.1778)
							(mid -0.249642 0.249642)
							(end -0.1778 0.2794)
						)
						(arc
							(start 0.1778 0.2794)
							(mid 0.249642 0.249642)
							(end 0.2794 0.1778)
						)
						(arc
							(start 0.2794 -0.1778)
							(mid 0.249642 -0.249642)
							(end 0.1778 -0.2794)
						)
					)
					(width 0)
					(fill yes)
				)
			)
		)
		(pad "2" smd custom
			(at 0 0.4445 180)
			(size 0.1397 0.1397)
			(layers "F.Cu" "F.Mask" "F.Paste")
			(net "SSD_ACT_DR12")
			(options
				(clearance outline)
				(anchor circle)
			)
			(primitives
				(gr_poly
					(pts
						(arc
							(start -0.1778 -0.2794)
							(mid -0.249642 -0.249642)
							(end -0.2794 -0.1778)
						)
						(arc
							(start -0.2794 0.1778)
							(mid -0.249642 0.249642)
							(end -0.1778 0.2794)
						)
						(arc
							(start 0.1778 0.2794)
							(mid 0.249642 0.249642)
							(end 0.2794 0.1778)
						)
						(arc
							(start 0.2794 -0.1778)
							(mid 0.249642 -0.249642)
							(end 0.1778 -0.2794)
						)
					)
					(width 0)
					(fill yes)
				)
			)
		)
	)
	(footprint ""
		(layer "F.Cu")
		(at 39.7764 -9.2964 90)
		(property "Reference" "R9870"
			(at 0 0 90)
			(layer "F.SilkS")
			(hide yes)
			(effects
				(font
					(size 1.27 1.27)
				)
			)
		)
		(property "Value" "2K2R5F-GP"
			(at 0 -8.9535 90)
			(unlocked yes)
			(layer "F.Fab")
			(hide yes)
			(effects
				(font
					(size 1.27 1.016)
					(thickness 0.1524)
				)
			)
		)
		(property "Device Type" "R805H24"
			(at 0 -10.6299 90)
			(unlocked yes)
			(layer "F.Fab")
			(hide yes)
			(effects
				(font
					(size 1.27 1.016)
					(thickness 0.1524)
				)
			)
		)
		(duplicate_pad_numbers_are_jumpers no)
		(fp_line
			(start 0.889 -1.7018)
			(end -0.889 -1.7018)
			(stroke
				(width 0.1524)
				(type default)
			)
			(layer "F.SilkS")
		)
		(fp_line
			(start 0.889 -1.7018)
			(end 0.889 -0.381)
			(stroke
				(width 0.1524)
				(type default)
			)
			(layer "F.SilkS")
		)
		(fp_line
			(start -0.889 -1.7018)
			(end -0.889 0.2794)
			(stroke
				(width 0.1524)
				(type default)
			)
			(layer "F.SilkS")
		)
		(fp_line
			(start -0.889 0.0762)
			(end -0.889 1.7018)
			(stroke
				(width 0.1524)
				(type default)
			)
			(layer "F.SilkS")
		)
		(fp_line
			(start 0.889 1.7018)
			(end 0.889 -0.508)
			(stroke
				(width 0.1524)
				(type default)
			)
			(layer "F.SilkS")
		)
		(fp_line
			(start -0.889 1.7018)
			(end 0.889 1.7018)
			(stroke
				(width 0.1524)
				(type default)
			)
			(layer "F.SilkS")
		)
		(fp_poly
			(pts
				(xy 0.9652 -1.778) (xy 0.9652 1.778) (xy -0.9652 1.778) (xy -0.9652 -1.778)
			)
			(stroke
				(width 0)
				(type default)
			)
			(fill no)
			(layer "F.CrtYd")
		)
		(fp_rect
			(start -0.9652 1.778)
			(end 0.9652 -1.778)
			(stroke
				(width 0)
				(type default)
			)
			(fill no)
			(layer "F.Fab")
		)
		(pad "1" smd rect
			(at 0 -0.9652 90)
			(size 1.397 1.143)
			(layers "F.Cu" "F.Mask" "F.Paste")
			(net "P12V_SSD14")
		)
		(pad "2" smd rect
			(at 0 0.9652 90)
			(size 1.397 1.143)
			(layers "F.Cu" "F.Mask" "F.Paste")
			(net "P12V_MOST14_GATE_D")
		)
	)
	(footprint ""
		(layer "F.Cu")
		(at 51.943 -7.747)
		(property "Reference" "R9755"
			(at 0 0 0)
			(layer "F.SilkS")
			(hide yes)
			(effects
				(font
					(size 1.27 1.27)
				)
			)
		)
		(property "Value" "4K7R2J-2-GP"
			(at 0.064008 -3.993896 0)
			(unlocked yes)
			(layer "F.Fab")
			(hide yes)
			(effects
				(font
					(size 1.016 1.016)
					(thickness 0.1524)
				)
			)
		)
		(property "Device Type" "R402H16"
			(at 0.064008 -5.517896 0)
			(unlocked yes)
			(layer "F.Fab")
			(hide yes)
			(effects
				(font
					(size 1.016 1.016)
					(thickness 0.1524)
				)
			)
		)
		(duplicate_pad_numbers_are_jumpers no)
		(fp_line
			(start -0.508 -0.9398)
			(end -0.508 0.9398)
			(stroke
				(width 0.1524)
				(type default)
			)
			(layer "F.SilkS")
		)
		(fp_line
			(start 0.508 -0.9398)
			(end -0.508 -0.9398)
			(stroke
				(width 0.1524)
				(type default)
			)
			(layer "F.SilkS")
		)
		(fp_rect
			(start -0.508 0.9398)
			(end 0.508 -0.9398)
			(stroke
				(width 0)
				(type default)
			)
			(fill no)
			(layer "F.CrtYd")
		)
		(fp_rect
			(start -0.508 0.9398)
			(end 0.508 -0.9398)
			(stroke
				(width 0)
				(type default)
			)
			(fill no)
			(layer "F.Fab")
		)
		(pad "1" smd custom
			(at 0 -0.4445)
			(size 0.1397 0.1397)
			(layers "F.Cu" "F.Mask" "F.Paste")
			(net "P3V3")
			(options
				(clearance outline)
				(anchor circle)
			)
			(primitives
				(gr_poly
					(pts
						(arc
							(start -0.1778 -0.2794)
							(mid -0.249642 -0.249642)
							(end -0.2794 -0.1778)
						)
						(arc
							(start -0.2794 0.1778)
							(mid -0.249642 0.249642)
							(end -0.1778 0.2794)
						)
						(arc
							(start 0.1778 0.2794)
							(mid 0.249642 0.249642)
							(end 0.2794 0.1778)
						)
						(arc
							(start 0.2794 -0.1778)
							(mid 0.249642 -0.249642)
							(end 0.1778 -0.2794)
						)
					)
					(width 0)
					(fill yes)
				)
			)
		)
		(pad "2" smd custom
			(at 0 0.4445)
			(size 0.1397 0.1397)
			(layers "F.Cu" "F.Mask" "F.Paste")
			(net "SSD14_PWREN")
			(options
				(clearance outline)
				(anchor circle)
			)
			(primitives
				(gr_poly
					(pts
						(arc
							(start -0.1778 -0.2794)
							(mid -0.249642 -0.249642)
							(end -0.2794 -0.1778)
						)
						(arc
							(start -0.2794 0.1778)
							(mid -0.249642 0.249642)
							(end -0.1778 0.2794)
						)
						(arc
							(start 0.1778 0.2794)
							(mid 0.249642 0.249642)
							(end 0.2794 0.1778)
						)
						(arc
							(start 0.2794 -0.1778)
							(mid 0.249642 -0.249642)
							(end 0.1778 -0.2794)
						)
					)
					(width 0)
					(fill yes)
				)
			)
		)
	)
	(footprint ""
		(layer "F.Cu")
		(at 29.9466 -290.6522)
		(property "Reference" "SR1105"
			(at 0 0 0)
			(layer "F.SilkS")
			(hide yes)
			(effects
				(font
					(size 1.27 1.27)
				)
			)
		)
		(property "Value" "4K7R2F-GP"
			(at 0.064008 -3.993896 0)
			(unlocked yes)
			(layer "F.Fab")
			(hide yes)
			(effects
				(font
					(size 1.016 1.016)
					(thickness 0.1524)
				)
			)
		)
		(property "Device Type" "R402H16"
			(at 0.064008 -5.517896 0)
			(unlocked yes)
			(layer "F.Fab")
			(hide yes)
			(effects
				(font
					(size 1.016 1.016)
					(thickness 0.1524)
				)
			)
		)
		(duplicate_pad_numbers_are_jumpers no)
		(fp_line
			(start -0.508 -0.9398)
			(end -0.508 0.9398)
			(stroke
				(width 0.1524)
				(type default)
			)
			(layer "F.SilkS")
		)
		(fp_line
			(start 0.508 -0.9398)
			(end -0.508 -0.9398)
			(stroke
				(width 0.1524)
				(type default)
			)
			(layer "F.SilkS")
		)
		(fp_rect
			(start -0.508 0.9398)
			(end 0.508 -0.9398)
			(stroke
				(width 0)
				(type default)
			)
			(fill no)
			(layer "F.CrtYd")
		)
		(fp_rect
			(start -0.508 0.9398)
			(end 0.508 -0.9398)
			(stroke
				(width 0)
				(type default)
			)
			(fill no)
			(layer "F.Fab")
		)
		(pad "1" smd custom
			(at 0 -0.4445)
			(size 0.1397 0.1397)
			(layers "F.Cu" "F.Mask" "F.Paste")
			(net "P3V3")
			(options
				(clearance outline)
				(anchor circle)
			)
			(primitives
				(gr_poly
					(pts
						(arc
							(start -0.1778 -0.2794)
							(mid -0.249642 -0.249642)
							(end -0.2794 -0.1778)
						)
						(arc
							(start -0.2794 0.1778)
							(mid -0.249642 0.249642)
							(end -0.1778 0.2794)
						)
						(arc
							(start 0.1778 0.2794)
							(mid 0.249642 0.249642)
							(end 0.2794 0.1778)
						)
						(arc
							(start 0.2794 -0.1778)
							(mid 0.249642 -0.249642)
							(end 0.1778 -0.2794)
						)
					)
					(width 0)
					(fill yes)
				)
			)
		)
		(pad "2" smd custom
			(at 0 0.4445)
			(size 0.1397 0.1397)
			(layers "F.Cu" "F.Mask" "F.Paste")
			(net "DUALPORTEN#7")
			(options
				(clearance outline)
				(anchor circle)
			)
			(primitives
				(gr_poly
					(pts
						(arc
							(start -0.1778 -0.2794)
							(mid -0.249642 -0.249642)
							(end -0.2794 -0.1778)
						)
						(arc
							(start -0.2794 0.1778)
							(mid -0.249642 0.249642)
							(end -0.1778 0.2794)
						)
						(arc
							(start 0.1778 0.2794)
							(mid 0.249642 0.249642)
							(end 0.2794 0.1778)
						)
						(arc
							(start 0.2794 -0.1778)
							(mid 0.249642 -0.249642)
							(end 0.1778 -0.2794)
						)
					)
					(width 0)
					(fill yes)
				)
			)
		)
	)
	(footprint ""
		(layer "F.Cu")
		(at 215.9 -94.9706 -90)
		(property "Reference" "Q46"
			(at 0 0 270)
			(layer "F.SilkS")
			(hide yes)
			(effects
				(font
					(size 1.27 1.27)
				)
			)
		)
		(property "Value" "2N7002A-7-GP"
			(at 0.127 -8.9662 270)
			(unlocked yes)
			(layer "F.Fab")
			(hide yes)
			(effects
				(font
					(size 1.016 1.016)
					(thickness 0.1524)
				)
			)
		)
		(property "Device Type" "SOT23DGS2D4H48"
			(at 0.127 -10.4902 270)
			(unlocked yes)
			(layer "F.Fab")
			(hide yes)
			(effects
				(font
					(size 1.016 1.016)
					(thickness 0.1524)
				)
			)
		)
		(duplicate_pad_numbers_are_jumpers no)
		(fp_line
			(start -1.651 1.778)
			(end 1.651 1.778)
			(stroke
				(width 0.1524)
				(type default)
			)
			(layer "F.SilkS")
		)
		(fp_line
			(start 1.651 1.778)
			(end 1.651 -1.778)
			(stroke
				(width 0.1524)
				(type default)
			)
			(layer "F.SilkS")
		)
		(fp_line
			(start -1.651 -1.778)
			(end -1.651 1.778)
			(stroke
				(width 0.1524)
				(type default)
			)
			(layer "F.SilkS")
		)
		(fp_line
			(start 1.651 -1.778)
			(end -1.651 -1.778)
			(stroke
				(width 0.1524)
				(type default)
			)
			(layer "F.SilkS")
		)
		(fp_poly
			(pts
				(xy -1.778 1.8796) (xy -1.778 -1.8796) (xy 1.778 -1.8796) (xy 1.778 1.8796)
			)
			(stroke
				(width 0)
				(type default)
			)
			(fill no)
			(layer "F.CrtYd")
		)
		(fp_poly
			(pts
				(xy -1.778 1.8796) (xy -1.778 -1.8796) (xy 1.778 -1.8796) (xy 1.778 1.8796)
			)
			(stroke
				(width 0)
				(type default)
			)
			(fill no)
			(layer "F.Fab")
		)
		(pad "D" smd custom
			(at 0 -0.9525 270)
			(size 0.1905 0.1905)
			(layers "F.Cu" "F.Mask" "F.Paste")
			(net "P12V_MOST4_GATE_D")
			(options
				(clearance outline)
				(anchor circle)
			)
			(primitives
				(gr_poly
					(pts
						(arc
							(start -0.1778 0.5715)
							(mid -0.321484 0.511984)
							(end -0.381 0.3683)
						)
						(arc
							(start -0.381 -0.3683)
							(mid -0.321484 -0.511984)
							(end -0.1778 -0.5715)
						)
						(arc
							(start 0.1778 -0.5715)
							(mid 0.321484 -0.511984)
							(end 0.381 -0.3683)
						)
						(arc
							(start 0.381 0.3683)
							(mid 0.321484 0.511984)
							(end 0.1778 0.5715)
						)
					)
					(width 0)
					(fill yes)
				)
			)
		)
		(pad "G" smd custom
			(at -0.98425 0.9525 270)
			(size 0.1905 0.1905)
			(layers "F.Cu" "F.Mask" "F.Paste")
			(net "P12V_MOST4_GATE")
			(options
				(clearance outline)
				(anchor circle)
			)
			(primitives
				(gr_poly
					(pts
						(arc
							(start -0.1778 0.5715)
							(mid -0.321484 0.511984)
							(end -0.381 0.3683)
						)
						(arc
							(start -0.381 -0.3683)
							(mid -0.321484 -0.511984)
							(end -0.1778 -0.5715)
						)
						(arc
							(start 0.1778 -0.5715)
							(mid 0.321484 -0.511984)
							(end 0.381 -0.3683)
						)
						(arc
							(start 0.381 0.3683)
							(mid 0.321484 0.511984)
							(end 0.1778 0.5715)
						)
					)
					(width 0)
					(fill yes)
				)
			)
		)
		(pad "S" smd custom
			(at 0.98425 0.9525 270)
			(size 0.1905 0.1905)
			(layers "F.Cu" "F.Mask" "F.Paste")
			(net "GND")
			(options
				(clearance outline)
				(anchor circle)
			)
			(primitives
				(gr_poly
					(pts
						(arc
							(start -0.1778 0.5715)
							(mid -0.321484 0.511984)
							(end -0.381 0.3683)
						)
						(arc
							(start -0.381 -0.3683)
							(mid -0.321484 -0.511984)
							(end -0.1778 -0.5715)
						)
						(arc
							(start 0.1778 -0.5715)
							(mid 0.321484 -0.511984)
							(end 0.381 -0.3683)
						)
						(arc
							(start 0.381 0.3683)
							(mid 0.321484 0.511984)
							(end 0.1778 0.5715)
						)
					)
					(width 0)
					(fill yes)
				)
			)
		)
	)
	(footprint ""
		(layer "F.Cu")
		(at 84.074 -144.92732 -90)
		(property "Reference" "R371"
			(at 0 0 270)
			(layer "F.SilkS")
			(hide yes)
			(effects
				(font
					(size 1.27 1.27)
				)
			)
		)
		(property "Value" "4K7R2J-2-GP"
			(at 0.064008 -3.993896 270)
			(unlocked yes)
			(layer "F.Fab")
			(hide yes)
			(effects
				(font
					(size 1.016 1.016)
					(thickness 0.1524)
				)
			)
		)
		(property "Device Type" "R402H16"
			(at 0.064008 -5.517896 270)
			(unlocked yes)
			(layer "F.Fab")
			(hide yes)
			(effects
				(font
					(size 1.016 1.016)
					(thickness 0.1524)
				)
			)
		)
		(duplicate_pad_numbers_are_jumpers no)
		(fp_line
			(start -0.508 -0.9398)
			(end -0.508 0.9398)
			(stroke
				(width 0.1524)
				(type default)
			)
			(layer "F.SilkS")
		)
		(fp_line
			(start 0.508 -0.9398)
			(end -0.508 -0.9398)
			(stroke
				(width 0.1524)
				(type default)
			)
			(layer "F.SilkS")
		)
		(fp_rect
			(start -0.508 0.9398)
			(end 0.508 -0.9398)
			(stroke
				(width 0)
				(type default)
			)
			(fill no)
			(layer "F.CrtYd")
		)
		(fp_rect
			(start -0.508 0.9398)
			(end 0.508 -0.9398)
			(stroke
				(width 0)
				(type default)
			)
			(fill no)
			(layer "F.Fab")
		)
		(pad "1" smd custom
			(at 0 -0.4445 270)
			(size 0.1397 0.1397)
			(layers "F.Cu" "F.Mask" "F.Paste")
			(net "P3V3")
			(options
				(clearance outline)
				(anchor circle)
			)
			(primitives
				(gr_poly
					(pts
						(arc
							(start -0.1778 -0.2794)
							(mid -0.249642 -0.249642)
							(end -0.2794 -0.1778)
						)
						(arc
							(start -0.2794 0.1778)
							(mid -0.249642 0.249642)
							(end -0.1778 0.2794)
						)
						(arc
							(start 0.1778 0.2794)
							(mid 0.249642 0.249642)
							(end 0.2794 0.1778)
						)
						(arc
							(start 0.2794 -0.1778)
							(mid 0.249642 -0.249642)
							(end 0.1778 -0.2794)
						)
					)
					(width 0)
					(fill yes)
				)
			)
		)
		(pad "2" smd custom
			(at 0 0.4445 270)
			(size 0.1397 0.1397)
			(layers "F.Cu" "F.Mask" "F.Paste")
			(net "BMC_I2C_SCL_BUF_8")
			(options
				(clearance outline)
				(anchor circle)
			)
			(primitives
				(gr_poly
					(pts
						(arc
							(start -0.1778 -0.2794)
							(mid -0.249642 -0.249642)
							(end -0.2794 -0.1778)
						)
						(arc
							(start -0.2794 0.1778)
							(mid -0.249642 0.249642)
							(end -0.1778 0.2794)
						)
						(arc
							(start 0.1778 0.2794)
							(mid 0.249642 0.249642)
							(end 0.2794 0.1778)
						)
						(arc
							(start 0.2794 -0.1778)
							(mid 0.249642 -0.249642)
							(end 0.1778 -0.2794)
						)
					)
					(width 0)
					(fill yes)
				)
			)
		)
	)
	(footprint ""
		(layer "F.Cu")
		(at 51.562 -136.398)
		(property "Reference" "R318"
			(at 0 0 0)
			(layer "F.SilkS")
			(hide yes)
			(effects
				(font
					(size 1.27 1.27)
				)
			)
		)
		(property "Value" "4K7R2F-GP"
			(at 0.064008 -3.993896 0)
			(unlocked yes)
			(layer "F.Fab")
			(hide yes)
			(effects
				(font
					(size 1.016 1.016)
					(thickness 0.1524)
				)
			)
		)
		(property "Device Type" "R402H16"
			(at 0.064008 -5.517896 0)
			(unlocked yes)
			(layer "F.Fab")
			(hide yes)
			(effects
				(font
					(size 1.016 1.016)
					(thickness 0.1524)
				)
			)
		)
		(duplicate_pad_numbers_are_jumpers no)
		(fp_line
			(start -0.508 -0.9398)
			(end -0.508 0.9398)
			(stroke
				(width 0.1524)
				(type default)
			)
			(layer "F.SilkS")
		)
		(fp_line
			(start 0.508 -0.9398)
			(end -0.508 -0.9398)
			(stroke
				(width 0.1524)
				(type default)
			)
			(layer "F.SilkS")
		)
		(fp_rect
			(start -0.508 0.9398)
			(end 0.508 -0.9398)
			(stroke
				(width 0)
				(type default)
			)
			(fill no)
			(layer "F.CrtYd")
		)
		(fp_rect
			(start -0.508 0.9398)
			(end 0.508 -0.9398)
			(stroke
				(width 0)
				(type default)
			)
			(fill no)
			(layer "F.Fab")
		)
		(pad "1" smd custom
			(at 0 -0.4445)
			(size 0.1397 0.1397)
			(layers "F.Cu" "F.Mask" "F.Paste")
			(net "P3V3")
			(options
				(clearance outline)
				(anchor circle)
			)
			(primitives
				(gr_poly
					(pts
						(arc
							(start -0.1778 -0.2794)
							(mid -0.249642 -0.249642)
							(end -0.2794 -0.1778)
						)
						(arc
							(start -0.2794 0.1778)
							(mid -0.249642 0.249642)
							(end -0.1778 0.2794)
						)
						(arc
							(start 0.1778 0.2794)
							(mid 0.249642 0.249642)
							(end 0.2794 0.1778)
						)
						(arc
							(start 0.2794 -0.1778)
							(mid 0.249642 -0.249642)
							(end 0.1778 -0.2794)
						)
					)
					(width 0)
					(fill yes)
				)
			)
		)
		(pad "2" smd custom
			(at 0 0.4445)
			(size 0.1397 0.1397)
			(layers "F.Cu" "F.Mask" "F.Paste")
			(net "I2C_B_TMP1_A1")
			(options
				(clearance outline)
				(anchor circle)
			)
			(primitives
				(gr_poly
					(pts
						(arc
							(start -0.1778 -0.2794)
							(mid -0.249642 -0.249642)
							(end -0.2794 -0.1778)
						)
						(arc
							(start -0.2794 0.1778)
							(mid -0.249642 0.249642)
							(end -0.1778 0.2794)
						)
						(arc
							(start 0.1778 0.2794)
							(mid 0.249642 0.249642)
							(end 0.2794 0.1778)
						)
						(arc
							(start 0.2794 -0.1778)
							(mid 0.249642 -0.249642)
							(end 0.1778 -0.2794)
						)
					)
					(width 0)
					(fill yes)
				)
			)
		)
	)
	(footprint ""
		(layer "F.Cu")
		(at 30.51175 -101.91115 90)
		(property "Reference" "Q91"
			(at 0 0 90)
			(layer "F.SilkS")
			(hide yes)
			(effects
				(font
					(size 1.27 1.27)
				)
			)
		)
		(property "Value" "2N7002A-7-GP"
			(at 0.127 -8.9662 90)
			(unlocked yes)
			(layer "F.Fab")
			(hide yes)
			(effects
				(font
					(size 1.016 1.016)
					(thickness 0.1524)
				)
			)
		)
		(property "Device Type" "SOT23DGS2D4H48"
			(at 0.127 -10.4902 90)
			(unlocked yes)
			(layer "F.Fab")
			(hide yes)
			(effects
				(font
					(size 1.016 1.016)
					(thickness 0.1524)
				)
			)
		)
		(duplicate_pad_numbers_are_jumpers no)
		(fp_line
			(start 1.651 -1.778)
			(end -1.651 -1.778)
			(stroke
				(width 0.1524)
				(type default)
			)
			(layer "F.SilkS")
		)
		(fp_line
			(start -1.651 -1.778)
			(end -1.651 1.778)
			(stroke
				(width 0.1524)
				(type default)
			)
			(layer "F.SilkS")
		)
		(fp_line
			(start 1.651 1.778)
			(end 1.651 -1.778)
			(stroke
				(width 0.1524)
				(type default)
			)
			(layer "F.SilkS")
		)
		(fp_line
			(start -1.651 1.778)
			(end 1.651 1.778)
			(stroke
				(width 0.1524)
				(type default)
			)
			(layer "F.SilkS")
		)
		(fp_poly
			(pts
				(xy -1.778 1.8796) (xy -1.778 -1.8796) (xy 1.778 -1.8796) (xy 1.778 1.8796)
			)
			(stroke
				(width 0)
				(type default)
			)
			(fill no)
			(layer "F.CrtYd")
		)
		(fp_poly
			(pts
				(xy -1.778 1.8796) (xy -1.778 -1.8796) (xy 1.778 -1.8796) (xy 1.778 1.8796)
			)
			(stroke
				(width 0)
				(type default)
			)
			(fill no)
			(layer "F.Fab")
		)
		(pad "D" smd custom
			(at 0 -0.9525 90)
			(size 0.1905 0.1905)
			(layers "F.Cu" "F.Mask" "F.Paste")
			(net "P12V_MOST13_GATE_D")
			(options
				(clearance outline)
				(anchor circle)
			)
			(primitives
				(gr_poly
					(pts
						(arc
							(start -0.1778 0.5715)
							(mid -0.321484 0.511984)
							(end -0.381 0.3683)
						)
						(arc
							(start -0.381 -0.3683)
							(mid -0.321484 -0.511984)
							(end -0.1778 -0.5715)
						)
						(arc
							(start 0.1778 -0.5715)
							(mid 0.321484 -0.511984)
							(end 0.381 -0.3683)
						)
						(arc
							(start 0.381 0.3683)
							(mid 0.321484 0.511984)
							(end 0.1778 0.5715)
						)
					)
					(width 0)
					(fill yes)
				)
			)
		)
		(pad "G" smd custom
			(at -0.98425 0.9525 90)
			(size 0.1905 0.1905)
			(layers "F.Cu" "F.Mask" "F.Paste")
			(net "P12V_MOST13_GATE")
			(options
				(clearance outline)
				(anchor circle)
			)
			(primitives
				(gr_poly
					(pts
						(arc
							(start -0.1778 0.5715)
							(mid -0.321484 0.511984)
							(end -0.381 0.3683)
						)
						(arc
							(start -0.381 -0.3683)
							(mid -0.321484 -0.511984)
							(end -0.1778 -0.5715)
						)
						(arc
							(start 0.1778 -0.5715)
							(mid 0.321484 -0.511984)
							(end 0.381 -0.3683)
						)
						(arc
							(start 0.381 0.3683)
							(mid 0.321484 0.511984)
							(end 0.1778 0.5715)
						)
					)
					(width 0)
					(fill yes)
				)
			)
		)
		(pad "S" smd custom
			(at 0.98425 0.9525 90)
			(size 0.1905 0.1905)
			(layers "F.Cu" "F.Mask" "F.Paste")
			(net "GND")
			(options
				(clearance outline)
				(anchor circle)
			)
			(primitives
				(gr_poly
					(pts
						(arc
							(start -0.1778 0.5715)
							(mid -0.321484 0.511984)
							(end -0.381 0.3683)
						)
						(arc
							(start -0.381 -0.3683)
							(mid -0.321484 -0.511984)
							(end -0.1778 -0.5715)
						)
						(arc
							(start 0.1778 -0.5715)
							(mid 0.321484 -0.511984)
							(end 0.381 -0.3683)
						)
						(arc
							(start 0.381 0.3683)
							(mid 0.321484 0.511984)
							(end 0.1778 0.5715)
						)
					)
					(width 0)
					(fill yes)
				)
			)
		)
	)
	(footprint ""
		(layer "F.Cu")
		(at 25.4 -30.988 180)
		(property "Reference" "PC1234"
			(at 0 0 180)
			(layer "F.SilkS")
			(hide yes)
			(effects
				(font
					(size 1.27 1.27)
				)
			)
		)
		(property "Value" "SCD1U25V3KX-GP"
			(at 0 -2.8194 180)
			(unlocked yes)
			(layer "F.Fab")
			(hide yes)
			(effects
				(font
					(size 1.016 1.016)
					(thickness 0.1524)
				)
			)
		)
		(property "Device Type" "C603H36"
			(at 0 -4.3434 180)
			(unlocked yes)
			(layer "F.Fab")
			(hide yes)
			(effects
				(font
					(size 1.016 1.016)
					(thickness 0.1524)
				)
			)
		)
		(duplicate_pad_numbers_are_jumpers no)
		(fp_line
			(start 0.508 0)
			(end -0.508 0)
			(stroke
				(width 0.2032)
				(type default)
			)
			(layer "F.SilkS")
		)
		(fp_rect
			(start -0.5842 1.3335)
			(end 0.5842 -1.3335)
			(stroke
				(width 0)
				(type default)
			)
			(fill no)
			(layer "F.CrtYd")
		)
		(fp_rect
			(start -0.5842 1.3335)
			(end 0.5842 -1.3335)
			(stroke
				(width 0)
				(type default)
			)
			(fill no)
			(layer "F.Fab")
		)
		(pad "1" smd custom
			(at 0 -0.762 180)
			(size 0.2159 0.2159)
			(layers "F.Cu" "F.Mask" "F.Paste")
			(net "P3V3")
			(options
				(clearance outline)
				(anchor circle)
			)
			(primitives
				(gr_poly
					(pts
						(arc
							(start -0.3302 -0.4318)
							(mid -0.402042 -0.402042)
							(end -0.4318 -0.3302)
						)
						(arc
							(start -0.4318 0.3302)
							(mid -0.402042 0.402042)
							(end -0.3302 0.4318)
						)
						(arc
							(start 0.3302 0.4318)
							(mid 0.402042 0.402042)
							(end 0.4318 0.3302)
						)
						(arc
							(start 0.4318 -0.3302)
							(mid 0.402042 -0.402042)
							(end 0.3302 -0.4318)
						)
					)
					(width 0)
					(fill yes)
				)
			)
		)
		(pad "2" smd custom
			(at 0 0.762 180)
			(size 0.2159 0.2159)
			(layers "F.Cu" "F.Mask" "F.Paste")
			(net "GND")
			(options
				(clearance outline)
				(anchor circle)
			)
			(primitives
				(gr_poly
					(pts
						(arc
							(start -0.3302 -0.4318)
							(mid -0.402042 -0.402042)
							(end -0.4318 -0.3302)
						)
						(arc
							(start -0.4318 0.3302)
							(mid -0.402042 0.402042)
							(end -0.3302 0.4318)
						)
						(arc
							(start 0.3302 0.4318)
							(mid 0.402042 0.402042)
							(end 0.4318 0.3302)
						)
						(arc
							(start 0.4318 -0.3302)
							(mid 0.402042 -0.402042)
							(end 0.3302 -0.4318)
						)
					)
					(width 0)
					(fill yes)
				)
			)
		)
	)
	(footprint ""
		(layer "F.Cu")
		(at 22.352 -265.303 180)
		(property "Reference" "R9862"
			(at 0 0 180)
			(layer "F.SilkS")
			(hide yes)
			(effects
				(font
					(size 1.27 1.27)
				)
			)
		)
		(property "Value" "0R2J-2-GP"
			(at 0.064008 -3.993896 180)
			(unlocked yes)
			(layer "F.Fab")
			(hide yes)
			(effects
				(font
					(size 1.016 1.016)
					(thickness 0.1524)
				)
			)
		)
		(property "Device Type" "R402H16"
			(at 0.064008 -5.517896 180)
			(unlocked yes)
			(layer "F.Fab")
			(hide yes)
			(effects
				(font
					(size 1.016 1.016)
					(thickness 0.1524)
				)
			)
		)
		(duplicate_pad_numbers_are_jumpers no)
		(fp_line
			(start 0.508 -0.9398)
			(end -0.508 -0.9398)
			(stroke
				(width 0.1524)
				(type default)
			)
			(layer "F.SilkS")
		)
		(fp_line
			(start -0.508 -0.9398)
			(end -0.508 0.9398)
			(stroke
				(width 0.1524)
				(type default)
			)
			(layer "F.SilkS")
		)
		(fp_rect
			(start -0.508 0.9398)
			(end 0.508 -0.9398)
			(stroke
				(width 0)
				(type default)
			)
			(fill no)
			(layer "F.CrtYd")
		)
		(fp_rect
			(start -0.508 0.9398)
			(end 0.508 -0.9398)
			(stroke
				(width 0)
				(type default)
			)
			(fill no)
			(layer "F.Fab")
		)
		(pad "1" smd custom
			(at 0 -0.4445 180)
			(size 0.1397 0.1397)
			(layers "F.Cu" "F.Mask" "F.Paste")
			(net "ATTN_LED_DR12_R")
			(options
				(clearance outline)
				(anchor circle)
			)
			(primitives
				(gr_poly
					(pts
						(arc
							(start -0.1778 -0.2794)
							(mid -0.249642 -0.249642)
							(end -0.2794 -0.1778)
						)
						(arc
							(start -0.2794 0.1778)
							(mid -0.249642 0.249642)
							(end -0.1778 0.2794)
						)
						(arc
							(start 0.1778 0.2794)
							(mid 0.249642 0.249642)
							(end 0.2794 0.1778)
						)
						(arc
							(start 0.2794 -0.1778)
							(mid 0.249642 -0.249642)
							(end 0.1778 -0.2794)
						)
					)
					(width 0)
					(fill yes)
				)
			)
		)
		(pad "2" smd custom
			(at 0 0.4445 180)
			(size 0.1397 0.1397)
			(layers "F.Cu" "F.Mask" "F.Paste")
			(net "ATTN_LED_DR12_N")
			(options
				(clearance outline)
				(anchor circle)
			)
			(primitives
				(gr_poly
					(pts
						(arc
							(start -0.1778 -0.2794)
							(mid -0.249642 -0.249642)
							(end -0.2794 -0.1778)
						)
						(arc
							(start -0.2794 0.1778)
							(mid -0.249642 0.249642)
							(end -0.1778 0.2794)
						)
						(arc
							(start 0.1778 0.2794)
							(mid 0.249642 0.249642)
							(end 0.2794 0.1778)
						)
						(arc
							(start 0.2794 -0.1778)
							(mid 0.249642 -0.249642)
							(end 0.1778 -0.2794)
						)
					)
					(width 0)
					(fill yes)
				)
			)
		)
	)
	(footprint ""
		(layer "F.Cu")
		(at 99.06 -86.614 -90)
		(property "Reference" "R9589"
			(at 0 0 270)
			(layer "F.SilkS")
			(hide yes)
			(effects
				(font
					(size 1.27 1.27)
				)
			)
		)
		(property "Value" "4K7R2J-2-GP"
			(at 0.064008 -3.993896 270)
			(unlocked yes)
			(layer "F.Fab")
			(hide yes)
			(effects
				(font
					(size 1.016 1.016)
					(thickness 0.1524)
				)
			)
		)
		(property "Device Type" "R402H16"
			(at 0.064008 -5.517896 270)
			(unlocked yes)
			(layer "F.Fab")
			(hide yes)
			(effects
				(font
					(size 1.016 1.016)
					(thickness 0.1524)
				)
			)
		)
		(duplicate_pad_numbers_are_jumpers no)
		(fp_line
			(start -0.508 -0.9398)
			(end -0.508 0.9398)
			(stroke
				(width 0.1524)
				(type default)
			)
			(layer "F.SilkS")
		)
		(fp_line
			(start 0.508 -0.9398)
			(end -0.508 -0.9398)
			(stroke
				(width 0.1524)
				(type default)
			)
			(layer "F.SilkS")
		)
		(fp_rect
			(start -0.508 0.9398)
			(end 0.508 -0.9398)
			(stroke
				(width 0)
				(type default)
			)
			(fill no)
			(layer "F.CrtYd")
		)
		(fp_rect
			(start -0.508 0.9398)
			(end 0.508 -0.9398)
			(stroke
				(width 0)
				(type default)
			)
			(fill no)
			(layer "F.Fab")
		)
		(pad "1" smd custom
			(at 0 -0.4445 270)
			(size 0.1397 0.1397)
			(layers "F.Cu" "F.Mask" "F.Paste")
			(net "P3V3")
			(options
				(clearance outline)
				(anchor circle)
			)
			(primitives
				(gr_poly
					(pts
						(arc
							(start -0.1778 -0.2794)
							(mid -0.249642 -0.249642)
							(end -0.2794 -0.1778)
						)
						(arc
							(start -0.2794 0.1778)
							(mid -0.249642 0.249642)
							(end -0.1778 0.2794)
						)
						(arc
							(start 0.1778 0.2794)
							(mid 0.249642 0.249642)
							(end 0.2794 0.1778)
						)
						(arc
							(start 0.2794 -0.1778)
							(mid 0.249642 -0.249642)
							(end 0.1778 -0.2794)
						)
					)
					(width 0)
					(fill yes)
				)
			)
		)
		(pad "2" smd custom
			(at 0 0.4445 270)
			(size 0.1397 0.1397)
			(layers "F.Cu" "F.Mask" "F.Paste")
			(net "SSD14_CLK0_OE_N")
			(options
				(clearance outline)
				(anchor circle)
			)
			(primitives
				(gr_poly
					(pts
						(arc
							(start -0.1778 -0.2794)
							(mid -0.249642 -0.249642)
							(end -0.2794 -0.1778)
						)
						(arc
							(start -0.2794 0.1778)
							(mid -0.249642 0.249642)
							(end -0.1778 0.2794)
						)
						(arc
							(start 0.1778 0.2794)
							(mid 0.249642 0.249642)
							(end 0.2794 0.1778)
						)
						(arc
							(start 0.2794 -0.1778)
							(mid 0.249642 -0.249642)
							(end 0.1778 -0.2794)
						)
					)
					(width 0)
					(fill yes)
				)
			)
		)
	)
	(footprint ""
		(layer "F.Cu")
		(at 208.915 -439.42 90)
		(property "Reference" "PG4"
			(at 0 0 90)
			(layer "F.SilkS")
			(hide yes)
			(effects
				(font
					(size 1.27 1.27)
				)
			)
		)
		(property "Value" "GAP-CLOSE-PWR-4-GP"
			(at -2.4638 -0.5461 90)
			(unlocked yes)
			(layer "F.Fab")
			(hide yes)
			(effects
				(font
					(size 1.016 1.016)
					(thickness 0.1524)
				)
			)
		)
		(property "Device Type" "GAP-CLOSE-PWR-4"
			(at -2.4638 -2.0701 90)
			(unlocked yes)
			(layer "F.Fab")
			(hide yes)
			(effects
				(font
					(size 1.016 1.016)
					(thickness 0.1524)
				)
			)
		)
		(duplicate_pad_numbers_are_jumpers no)
		(fp_rect
			(start -0.2794 0.254)
			(end 0.2794 -0.254)
			(stroke
				(width 0)
				(type default)
			)
			(fill no)
			(layer "F.CrtYd")
		)
		(fp_rect
			(start -0.2794 0.254)
			(end 0.2794 -0.254)
			(stroke
				(width 0)
				(type default)
			)
			(fill no)
			(layer "F.Fab")
		)
		(pad "1" smd rect
			(at -0.0635 0 90)
			(size 0.1778 0.254)
			(layers "F.Cu" "F.Mask" "F.Paste")
			(net "P3V3_OUT")
		)
		(pad "2" smd rect
			(at 0.0635 0 90)
			(size 0.1778 0.254)
			(layers "F.Cu" "F.Mask" "F.Paste")
			(net "P3V3_CC")
		)
	)
	(footprint ""
		(layer "F.Cu")
		(at 22.14245 -198.95185 90)
		(property "Reference" "R9833"
			(at 0 0 90)
			(layer "F.SilkS")
			(hide yes)
			(effects
				(font
					(size 1.27 1.27)
				)
			)
		)
		(property "Value" "1KR2J-1-GP"
			(at 0.064008 -3.993896 90)
			(unlocked yes)
			(layer "F.Fab")
			(hide yes)
			(effects
				(font
					(size 1.016 1.016)
					(thickness 0.1524)
				)
			)
		)
		(property "Device Type" "R402H16"
			(at 0.064008 -5.517896 90)
			(unlocked yes)
			(layer "F.Fab")
			(hide yes)
			(effects
				(font
					(size 1.016 1.016)
					(thickness 0.1524)
				)
			)
		)
		(duplicate_pad_numbers_are_jumpers no)
		(fp_line
			(start 0.508 -0.9398)
			(end -0.508 -0.9398)
			(stroke
				(width 0.1524)
				(type default)
			)
			(layer "F.SilkS")
		)
		(fp_line
			(start -0.508 -0.9398)
			(end -0.508 0.9398)
			(stroke
				(width 0.1524)
				(type default)
			)
			(layer "F.SilkS")
		)
		(fp_rect
			(start -0.508 0.9398)
			(end 0.508 -0.9398)
			(stroke
				(width 0)
				(type default)
			)
			(fill no)
			(layer "F.CrtYd")
		)
		(fp_rect
			(start -0.508 0.9398)
			(end 0.508 -0.9398)
			(stroke
				(width 0)
				(type default)
			)
			(fill no)
			(layer "F.Fab")
		)
		(pad "1" smd custom
			(at 0 -0.4445 90)
			(size 0.1397 0.1397)
			(layers "F.Cu" "F.Mask" "F.Paste")
			(net "SSD8_PWREN")
			(options
				(clearance outline)
				(anchor circle)
			)
			(primitives
				(gr_poly
					(pts
						(arc
							(start -0.1778 -0.2794)
							(mid -0.249642 -0.249642)
							(end -0.2794 -0.1778)
						)
						(arc
							(start -0.2794 0.1778)
							(mid -0.249642 0.249642)
							(end -0.1778 0.2794)
						)
						(arc
							(start 0.1778 0.2794)
							(mid 0.249642 0.249642)
							(end 0.2794 0.1778)
						)
						(arc
							(start 0.2794 -0.1778)
							(mid 0.249642 -0.249642)
							(end 0.1778 -0.2794)
						)
					)
					(width 0)
					(fill yes)
				)
			)
		)
		(pad "2" smd custom
			(at 0 0.4445 90)
			(size 0.1397 0.1397)
			(layers "F.Cu" "F.Mask" "F.Paste")
			(net "SSD8_PWREN_R")
			(options
				(clearance outline)
				(anchor circle)
			)
			(primitives
				(gr_poly
					(pts
						(arc
							(start -0.1778 -0.2794)
							(mid -0.249642 -0.249642)
							(end -0.2794 -0.1778)
						)
						(arc
							(start -0.2794 0.1778)
							(mid -0.249642 0.249642)
							(end -0.1778 0.2794)
						)
						(arc
							(start 0.1778 0.2794)
							(mid 0.249642 0.249642)
							(end 0.2794 0.1778)
						)
						(arc
							(start 0.2794 -0.1778)
							(mid 0.249642 -0.249642)
							(end 0.1778 -0.2794)
						)
					)
					(width 0)
					(fill yes)
				)
			)
		)
	)
	(footprint ""
		(layer "F.Cu")
		(at 37.6936 -109.8804)
		(property "Reference" "R581"
			(at 0 0 0)
			(layer "F.SilkS")
			(hide yes)
			(effects
				(font
					(size 1.27 1.27)
				)
			)
		)
		(property "Value" "300KR2F-GP"
			(at 0.064008 -3.993896 0)
			(unlocked yes)
			(layer "F.Fab")
			(hide yes)
			(effects
				(font
					(size 1.016 1.016)
					(thickness 0.1524)
				)
			)
		)
		(property "Device Type" "R402H16"
			(at 0.064008 -5.517896 0)
			(unlocked yes)
			(layer "F.Fab")
			(hide yes)
			(effects
				(font
					(size 1.016 1.016)
					(thickness 0.1524)
				)
			)
		)
		(duplicate_pad_numbers_are_jumpers no)
		(fp_line
			(start -0.508 -0.9398)
			(end -0.508 0.9398)
			(stroke
				(width 0.1524)
				(type default)
			)
			(layer "F.SilkS")
		)
		(fp_line
			(start 0.508 -0.9398)
			(end -0.508 -0.9398)
			(stroke
				(width 0.1524)
				(type default)
			)
			(layer "F.SilkS")
		)
		(fp_rect
			(start -0.508 0.9398)
			(end 0.508 -0.9398)
			(stroke
				(width 0)
				(type default)
			)
			(fill no)
			(layer "F.CrtYd")
		)
		(fp_rect
			(start -0.508 0.9398)
			(end 0.508 -0.9398)
			(stroke
				(width 0)
				(type default)
			)
			(fill no)
			(layer "F.Fab")
		)
		(pad "1" smd custom
			(at 0 -0.4445)
			(size 0.1397 0.1397)
			(layers "F.Cu" "F.Mask" "F.Paste")
			(net "SW_SSD13_N")
			(options
				(clearance outline)
				(anchor circle)
			)
			(primitives
				(gr_poly
					(pts
						(arc
							(start -0.1778 -0.2794)
							(mid -0.249642 -0.249642)
							(end -0.2794 -0.1778)
						)
						(arc
							(start -0.2794 0.1778)
							(mid -0.249642 0.249642)
							(end -0.1778 0.2794)
						)
						(arc
							(start 0.1778 0.2794)
							(mid 0.249642 0.249642)
							(end 0.2794 0.1778)
						)
						(arc
							(start 0.2794 -0.1778)
							(mid 0.249642 -0.249642)
							(end 0.1778 -0.2794)
						)
					)
					(width 0)
					(fill yes)
				)
			)
		)
		(pad "2" smd custom
			(at 0 0.4445)
			(size 0.1397 0.1397)
			(layers "F.Cu" "F.Mask" "F.Paste")
			(net "P12V")
			(options
				(clearance outline)
				(anchor circle)
			)
			(primitives
				(gr_poly
					(pts
						(arc
							(start -0.1778 -0.2794)
							(mid -0.249642 -0.249642)
							(end -0.2794 -0.1778)
						)
						(arc
							(start -0.2794 0.1778)
							(mid -0.249642 0.249642)
							(end -0.1778 0.2794)
						)
						(arc
							(start 0.1778 0.2794)
							(mid 0.249642 0.249642)
							(end 0.2794 0.1778)
						)
						(arc
							(start 0.2794 -0.1778)
							(mid 0.249642 -0.249642)
							(end 0.1778 -0.2794)
						)
					)
					(width 0)
					(fill yes)
				)
			)
		)
	)
	(footprint ""
		(layer "F.Cu")
		(at 87.122 -436.499)
		(property "Reference" "C8893"
			(at 0 0 0)
			(layer "F.SilkS")
			(hide yes)
			(effects
				(font
					(size 1.27 1.27)
				)
			)
		)
		(property "Value" "SC1U10V2KX-7-GP"
			(at 1.1811 -2.7051 0)
			(unlocked yes)
			(layer "F.Fab")
			(hide yes)
			(effects
				(font
					(size 1.016 1.016)
					(thickness 0.1524)
				)
			)
		)
		(property "Device Type" "C402H22"
			(at 1.1811 -4.2291 0)
			(unlocked yes)
			(layer "F.Fab")
			(hide yes)
			(effects
				(font
					(size 1.016 1.016)
					(thickness 0.1524)
				)
			)
		)
		(duplicate_pad_numbers_are_jumpers no)
		(fp_rect
			(start -0.4318 0.9525)
			(end 0.4318 -0.9525)
			(stroke
				(width 0)
				(type default)
			)
			(fill no)
			(layer "F.CrtYd")
		)
		(fp_rect
			(start -0.4318 0.9525)
			(end 0.4318 -0.9525)
			(stroke
				(width 0)
				(type default)
			)
			(fill no)
			(layer "F.Fab")
		)
		(pad "1" smd custom
			(at 0 -0.4445)
			(size 0.1524 0.1524)
			(layers "F.Cu" "F.Mask" "F.Paste")
			(net "VDDA_1")
			(options
				(clearance outline)
				(anchor circle)
			)
			(primitives
				(gr_poly
					(pts
						(arc
							(start 0.3048 -0.2032)
							(mid 0.275042 -0.275042)
							(end 0.2032 -0.3048)
						)
						(arc
							(start -0.2032 -0.3048)
							(mid -0.275042 -0.275042)
							(end -0.3048 -0.2032)
						)
						(arc
							(start -0.3048 0.2032)
							(mid -0.275042 0.275042)
							(end -0.2032 0.3048)
						)
						(arc
							(start 0.2032 0.3048)
							(mid 0.275042 0.275042)
							(end 0.3048 0.2032)
						)
					)
					(width 0)
					(fill yes)
				)
			)
		)
		(pad "2" smd custom
			(at 0 0.4445)
			(size 0.1524 0.1524)
			(layers "F.Cu" "F.Mask" "F.Paste")
			(net "GND")
			(options
				(clearance outline)
				(anchor circle)
			)
			(primitives
				(gr_poly
					(pts
						(arc
							(start 0.3048 -0.2032)
							(mid 0.275042 -0.275042)
							(end 0.2032 -0.3048)
						)
						(arc
							(start -0.2032 -0.3048)
							(mid -0.275042 -0.275042)
							(end -0.3048 -0.2032)
						)
						(arc
							(start -0.3048 0.2032)
							(mid -0.275042 0.275042)
							(end -0.2032 0.3048)
						)
						(arc
							(start 0.2032 0.3048)
							(mid 0.275042 0.275042)
							(end 0.3048 0.2032)
						)
					)
					(width 0)
					(fill yes)
				)
			)
		)
	)
	(footprint ""
		(layer "F.Cu")
		(at 108.966 -434.848)
		(property "Reference" "R118"
			(at 0 0 0)
			(layer "F.SilkS")
			(hide yes)
			(effects
				(font
					(size 1.27 1.27)
				)
			)
		)
		(property "Value" "4K7R2J-2-GP"
			(at 0.064008 -3.993896 0)
			(unlocked yes)
			(layer "F.Fab")
			(hide yes)
			(effects
				(font
					(size 1.016 1.016)
					(thickness 0.1524)
				)
			)
		)
		(property "Device Type" "R402H16"
			(at 0.064008 -5.517896 0)
			(unlocked yes)
			(layer "F.Fab")
			(hide yes)
			(effects
				(font
					(size 1.016 1.016)
					(thickness 0.1524)
				)
			)
		)
		(duplicate_pad_numbers_are_jumpers no)
		(fp_line
			(start -0.508 -0.9398)
			(end -0.508 0.9398)
			(stroke
				(width 0.1524)
				(type default)
			)
			(layer "F.SilkS")
		)
		(fp_line
			(start 0.508 -0.9398)
			(end -0.508 -0.9398)
			(stroke
				(width 0.1524)
				(type default)
			)
			(layer "F.SilkS")
		)
		(fp_rect
			(start -0.508 0.9398)
			(end 0.508 -0.9398)
			(stroke
				(width 0)
				(type default)
			)
			(fill no)
			(layer "F.CrtYd")
		)
		(fp_rect
			(start -0.508 0.9398)
			(end 0.508 -0.9398)
			(stroke
				(width 0)
				(type default)
			)
			(fill no)
			(layer "F.Fab")
		)
		(pad "1" smd custom
			(at 0 -0.4445)
			(size 0.1397 0.1397)
			(layers "F.Cu" "F.Mask" "F.Paste")
			(net "P3V3")
			(options
				(clearance outline)
				(anchor circle)
			)
			(primitives
				(gr_poly
					(pts
						(arc
							(start -0.1778 -0.2794)
							(mid -0.249642 -0.249642)
							(end -0.2794 -0.1778)
						)
						(arc
							(start -0.2794 0.1778)
							(mid -0.249642 0.249642)
							(end -0.1778 0.2794)
						)
						(arc
							(start 0.1778 0.2794)
							(mid 0.249642 0.249642)
							(end 0.2794 0.1778)
						)
						(arc
							(start 0.2794 -0.1778)
							(mid 0.249642 -0.249642)
							(end 0.1778 -0.2794)
						)
					)
					(width 0)
					(fill yes)
				)
			)
		)
		(pad "2" smd custom
			(at 0 0.4445)
			(size 0.1397 0.1397)
			(layers "F.Cu" "F.Mask" "F.Paste")
			(net "SSD_PRSNT_NET0")
			(options
				(clearance outline)
				(anchor circle)
			)
			(primitives
				(gr_poly
					(pts
						(arc
							(start -0.1778 -0.2794)
							(mid -0.249642 -0.249642)
							(end -0.2794 -0.1778)
						)
						(arc
							(start -0.2794 0.1778)
							(mid -0.249642 0.249642)
							(end -0.1778 0.2794)
						)
						(arc
							(start 0.1778 0.2794)
							(mid 0.249642 0.249642)
							(end 0.2794 0.1778)
						)
						(arc
							(start 0.2794 -0.1778)
							(mid 0.249642 -0.249642)
							(end 0.1778 -0.2794)
						)
					)
					(width 0)
					(fill yes)
				)
			)
		)
	)
	(footprint ""
		(layer "F.Cu")
		(at 43.0784 -93.5482)
		(property "Reference" "R9242"
			(at 0 0 0)
			(layer "F.SilkS")
			(hide yes)
			(effects
				(font
					(size 1.27 1.27)
				)
			)
		)
		(property "Value" "2R2010F-GP"
			(at 0.0762 -4.5466 0)
			(unlocked yes)
			(layer "F.Fab")
			(hide yes)
			(effects
				(font
					(size 1.016 1.016)
					(thickness 0.1524)
				)
			)
		)
		(property "Device Type" "R2010H26"
			(at 0.0762 -6.1468 0)
			(unlocked yes)
			(layer "F.Fab")
			(hide yes)
			(effects
				(font
					(size 1.016 1.016)
					(thickness 0.1524)
				)
			)
		)
		(duplicate_pad_numbers_are_jumpers no)
		(fp_line
			(start -3.302 -1.651)
			(end -3.302 1.651)
			(stroke
				(width 0.1524)
				(type default)
			)
			(layer "F.SilkS")
		)
		(fp_line
			(start -3.302 1.651)
			(end 3.302 1.651)
			(stroke
				(width 0.1524)
				(type default)
			)
			(layer "F.SilkS")
		)
		(fp_line
			(start 3.302 -1.651)
			(end -3.302 -1.651)
			(stroke
				(width 0.1524)
				(type default)
			)
			(layer "F.SilkS")
		)
		(fp_line
			(start 3.302 1.651)
			(end 3.302 -1.651)
			(stroke
				(width 0.1524)
				(type default)
			)
			(layer "F.SilkS")
		)
		(fp_rect
			(start -3.3782 1.7272)
			(end 3.3782 -1.7272)
			(stroke
				(width 0)
				(type default)
			)
			(fill no)
			(layer "F.CrtYd")
		)
		(fp_poly
			(pts
				(xy 3.3782 -1.7272) (xy -3.3782 -1.7272) (xy -3.3782 1.7272) (xy 3.3782 1.7272)
			)
			(stroke
				(width 0)
				(type default)
			)
			(fill no)
			(layer "F.Fab")
		)
		(pad "1" smd rect
			(at -2.3495 0)
			(size 1.143 2.794)
			(layers "F.Cu" "F.Mask" "F.Paste")
			(net "P12V_SSD9")
		)
		(pad "2" smd rect
			(at 2.3495 0)
			(size 1.143 2.794)
			(layers "F.Cu" "F.Mask" "F.Paste")
			(net "12V_PRECH_SSD9")
		)
	)
	(footprint ""
		(layer "F.Cu")
		(at 8.053578 -272.298414 180)
		(property "Reference" "R584"
			(at 0 0 180)
			(layer "F.SilkS")
			(hide yes)
			(effects
				(font
					(size 1.27 1.27)
				)
			)
		)
		(property "Value" "2R2010J-1-GP"
			(at 0.254 -8.0772 180)
			(unlocked yes)
			(layer "F.Fab")
			(hide yes)
			(effects
				(font
					(size 1.016 1.016)
					(thickness 0.1524)
				)
			)
		)
		(property "Device Type" "R2010H28"
			(at 0.254 -9.6774 180)
			(unlocked yes)
			(layer "F.Fab")
			(hide yes)
			(effects
				(font
					(size 1.016 1.016)
					(thickness 0.1524)
				)
			)
		)
		(duplicate_pad_numbers_are_jumpers no)
		(fp_line
			(start 1.651 3.302)
			(end 1.651 -3.302)
			(stroke
				(width 0.1524)
				(type default)
			)
			(layer "F.SilkS")
		)
		(fp_line
			(start 1.651 -3.302)
			(end -1.651 -3.302)
			(stroke
				(width 0.1524)
				(type default)
			)
			(layer "F.SilkS")
		)
		(fp_line
			(start -1.651 3.302)
			(end 1.651 3.302)
			(stroke
				(width 0.1524)
				(type default)
			)
			(layer "F.SilkS")
		)
		(fp_line
			(start -1.651 -3.302)
			(end -1.651 3.302)
			(stroke
				(width 0.1524)
				(type default)
			)
			(layer "F.SilkS")
		)
		(fp_rect
			(start -1.7272 -3.3782)
			(end 1.7272 3.3782)
			(stroke
				(width 0)
				(type default)
			)
			(fill no)
			(layer "F.CrtYd")
		)
		(fp_poly
			(pts
				(xy 1.7272 3.3782) (xy 1.7272 -3.3782) (xy -1.7272 -3.3782) (xy -1.7272 3.3782)
			)
			(stroke
				(width 0)
				(type default)
			)
			(fill no)
			(layer "F.Fab")
		)
		(pad "1" smd rect
			(at 0 -2.3495 180)
			(size 2.794 1.143)
			(layers "F.Cu" "F.Mask" "F.Paste")
			(net "PCIE_MATED#_B")
		)
		(pad "2" smd rect
			(at 0 2.3495 180)
			(size 2.794 1.143)
			(layers "F.Cu" "F.Mask" "F.Paste")
			(net "GND")
		)
	)
	(footprint ""
		(layer "F.Cu")
		(at 22.247606 -162.109658 180)
		(property "Reference" "R9868"
			(at 0 0 180)
			(layer "F.SilkS")
			(hide yes)
			(effects
				(font
					(size 1.27 1.27)
				)
			)
		)
		(property "Value" "0R2J-2-GP"
			(at 0.064008 -3.993896 180)
			(unlocked yes)
			(layer "F.Fab")
			(hide yes)
			(effects
				(font
					(size 1.016 1.016)
					(thickness 0.1524)
				)
			)
		)
		(property "Device Type" "R402H16"
			(at 0.064008 -5.517896 180)
			(unlocked yes)
			(layer "F.Fab")
			(hide yes)
			(effects
				(font
					(size 1.016 1.016)
					(thickness 0.1524)
				)
			)
		)
		(duplicate_pad_numbers_are_jumpers no)
		(fp_line
			(start 0.508 -0.9398)
			(end -0.508 -0.9398)
			(stroke
				(width 0.1524)
				(type default)
			)
			(layer "F.SilkS")
		)
		(fp_line
			(start -0.508 -0.9398)
			(end -0.508 0.9398)
			(stroke
				(width 0.1524)
				(type default)
			)
			(layer "F.SilkS")
		)
		(fp_rect
			(start -0.508 0.9398)
			(end 0.508 -0.9398)
			(stroke
				(width 0)
				(type default)
			)
			(fill no)
			(layer "F.CrtYd")
		)
		(fp_rect
			(start -0.508 0.9398)
			(end 0.508 -0.9398)
			(stroke
				(width 0)
				(type default)
			)
			(fill no)
			(layer "F.Fab")
		)
		(pad "1" smd custom
			(at 0 -0.4445 180)
			(size 0.1397 0.1397)
			(layers "F.Cu" "F.Mask" "F.Paste")
			(net "ATTN_LED_DR13_R")
			(options
				(clearance outline)
				(anchor circle)
			)
			(primitives
				(gr_poly
					(pts
						(arc
							(start -0.1778 -0.2794)
							(mid -0.249642 -0.249642)
							(end -0.2794 -0.1778)
						)
						(arc
							(start -0.2794 0.1778)
							(mid -0.249642 0.249642)
							(end -0.1778 0.2794)
						)
						(arc
							(start 0.1778 0.2794)
							(mid 0.249642 0.249642)
							(end 0.2794 0.1778)
						)
						(arc
							(start 0.2794 -0.1778)
							(mid 0.249642 -0.249642)
							(end 0.1778 -0.2794)
						)
					)
					(width 0)
					(fill yes)
				)
			)
		)
		(pad "2" smd custom
			(at 0 0.4445 180)
			(size 0.1397 0.1397)
			(layers "F.Cu" "F.Mask" "F.Paste")
			(net "ATTN_LED_DR13_N")
			(options
				(clearance outline)
				(anchor circle)
			)
			(primitives
				(gr_poly
					(pts
						(arc
							(start -0.1778 -0.2794)
							(mid -0.249642 -0.249642)
							(end -0.2794 -0.1778)
						)
						(arc
							(start -0.2794 0.1778)
							(mid -0.249642 0.249642)
							(end -0.1778 0.2794)
						)
						(arc
							(start 0.1778 0.2794)
							(mid 0.249642 0.249642)
							(end 0.2794 0.1778)
						)
						(arc
							(start 0.2794 -0.1778)
							(mid 0.249642 -0.249642)
							(end 0.1778 -0.2794)
						)
					)
					(width 0)
					(fill yes)
				)
			)
		)
	)
	(footprint ""
		(layer "F.Cu")
		(at 90.297 -423.164)
		(property "Reference" "R9068"
			(at 0 0 0)
			(layer "F.SilkS")
			(hide yes)
			(effects
				(font
					(size 1.27 1.27)
				)
			)
		)
		(property "Value" "27R2F-GP"
			(at 0.064008 -3.993896 0)
			(unlocked yes)
			(layer "F.Fab")
			(hide yes)
			(effects
				(font
					(size 1.016 1.016)
					(thickness 0.1524)
				)
			)
		)
		(property "Device Type" "R402H16"
			(at 0.064008 -5.517896 0)
			(unlocked yes)
			(layer "F.Fab")
			(hide yes)
			(effects
				(font
					(size 1.016 1.016)
					(thickness 0.1524)
				)
			)
		)
		(duplicate_pad_numbers_are_jumpers no)
		(fp_line
			(start -0.508 -0.9398)
			(end -0.508 0.9398)
			(stroke
				(width 0.1524)
				(type default)
			)
			(layer "F.SilkS")
		)
		(fp_line
			(start 0.508 -0.9398)
			(end -0.508 -0.9398)
			(stroke
				(width 0.1524)
				(type default)
			)
			(layer "F.SilkS")
		)
		(fp_rect
			(start -0.508 0.9398)
			(end 0.508 -0.9398)
			(stroke
				(width 0)
				(type default)
			)
			(fill no)
			(layer "F.CrtYd")
		)
		(fp_rect
			(start -0.508 0.9398)
			(end 0.508 -0.9398)
			(stroke
				(width 0)
				(type default)
			)
			(fill no)
			(layer "F.Fab")
		)
		(pad "1" smd custom
			(at 0 -0.4445)
			(size 0.1397 0.1397)
			(layers "F.Cu" "F.Mask" "F.Paste")
			(net "PE_CLK_100M_DR10_1_R_P")
			(options
				(clearance outline)
				(anchor circle)
			)
			(primitives
				(gr_poly
					(pts
						(arc
							(start -0.1778 -0.2794)
							(mid -0.249642 -0.249642)
							(end -0.2794 -0.1778)
						)
						(arc
							(start -0.2794 0.1778)
							(mid -0.249642 0.249642)
							(end -0.1778 0.2794)
						)
						(arc
							(start 0.1778 0.2794)
							(mid 0.249642 0.249642)
							(end 0.2794 0.1778)
						)
						(arc
							(start 0.2794 -0.1778)
							(mid 0.249642 -0.249642)
							(end 0.1778 -0.2794)
						)
					)
					(width 0)
					(fill yes)
				)
			)
		)
		(pad "2" smd custom
			(at 0 0.4445)
			(size 0.1397 0.1397)
			(layers "F.Cu" "F.Mask" "F.Paste")
			(net "PE_CLK100M_DR10_1_P")
			(options
				(clearance outline)
				(anchor circle)
			)
			(primitives
				(gr_poly
					(pts
						(arc
							(start -0.1778 -0.2794)
							(mid -0.249642 -0.249642)
							(end -0.2794 -0.1778)
						)
						(arc
							(start -0.2794 0.1778)
							(mid -0.249642 0.249642)
							(end -0.1778 0.2794)
						)
						(arc
							(start 0.1778 0.2794)
							(mid 0.249642 0.249642)
							(end 0.2794 0.1778)
						)
						(arc
							(start 0.2794 -0.1778)
							(mid 0.249642 -0.249642)
							(end 0.1778 -0.2794)
						)
					)
					(width 0)
					(fill yes)
				)
			)
		)
	)
	(footprint ""
		(layer "F.Cu")
		(at 8.7376 -463.0928 90)
		(property "Reference" "PC1165"
			(at 0 0 90)
			(layer "F.SilkS")
			(hide yes)
			(effects
				(font
					(size 1.27 1.27)
				)
			)
		)
		(property "Value" "SCD01U50V2KX-1GP"
			(at 1.1811 -2.7051 90)
			(unlocked yes)
			(layer "F.Fab")
			(hide yes)
			(effects
				(font
					(size 1.016 1.016)
					(thickness 0.1524)
				)
			)
		)
		(property "Device Type" "C402H22"
			(at 1.1811 -4.2291 90)
			(unlocked yes)
			(layer "F.Fab")
			(hide yes)
			(effects
				(font
					(size 1.016 1.016)
					(thickness 0.1524)
				)
			)
		)
		(duplicate_pad_numbers_are_jumpers no)
		(fp_rect
			(start -0.4318 0.9525)
			(end 0.4318 -0.9525)
			(stroke
				(width 0)
				(type default)
			)
			(fill no)
			(layer "F.CrtYd")
		)
		(fp_rect
			(start -0.4318 0.9525)
			(end 0.4318 -0.9525)
			(stroke
				(width 0)
				(type default)
			)
			(fill no)
			(layer "F.Fab")
		)
		(pad "1" smd custom
			(at 0 -0.4445 90)
			(size 0.1524 0.1524)
			(layers "F.Cu" "F.Mask" "F.Paste")
			(net "P12V")
			(options
				(clearance outline)
				(anchor circle)
			)
			(primitives
				(gr_poly
					(pts
						(arc
							(start 0.3048 -0.2032)
							(mid 0.275042 -0.275042)
							(end 0.2032 -0.3048)
						)
						(arc
							(start -0.2032 -0.3048)
							(mid -0.275042 -0.275042)
							(end -0.3048 -0.2032)
						)
						(arc
							(start -0.3048 0.2032)
							(mid -0.275042 0.275042)
							(end -0.2032 0.3048)
						)
						(arc
							(start 0.2032 0.3048)
							(mid 0.275042 0.275042)
							(end 0.3048 0.2032)
						)
					)
					(width 0)
					(fill yes)
				)
			)
		)
		(pad "2" smd custom
			(at 0 0.4445 90)
			(size 0.1524 0.1524)
			(layers "F.Cu" "F.Mask" "F.Paste")
			(net "GND")
			(options
				(clearance outline)
				(anchor circle)
			)
			(primitives
				(gr_poly
					(pts
						(arc
							(start 0.3048 -0.2032)
							(mid 0.275042 -0.275042)
							(end 0.2032 -0.3048)
						)
						(arc
							(start -0.2032 -0.3048)
							(mid -0.275042 -0.275042)
							(end -0.3048 -0.2032)
						)
						(arc
							(start -0.3048 0.2032)
							(mid -0.275042 0.275042)
							(end -0.2032 0.3048)
						)
						(arc
							(start 0.2032 0.3048)
							(mid 0.275042 0.275042)
							(end 0.3048 0.2032)
						)
					)
					(width 0)
					(fill yes)
				)
			)
		)
	)
	(footprint ""
		(layer "F.Cu")
		(at 37.973 -205.74 180)
		(property "Reference" "R9772"
			(at 0 0 180)
			(layer "F.SilkS")
			(hide yes)
			(effects
				(font
					(size 1.27 1.27)
				)
			)
		)
		(property "Value" "4K7R2J-2-GP"
			(at 0.064008 -3.993896 180)
			(unlocked yes)
			(layer "F.Fab")
			(hide yes)
			(effects
				(font
					(size 1.016 1.016)
					(thickness 0.1524)
				)
			)
		)
		(property "Device Type" "R402H16"
			(at 0.064008 -5.517896 180)
			(unlocked yes)
			(layer "F.Fab")
			(hide yes)
			(effects
				(font
					(size 1.016 1.016)
					(thickness 0.1524)
				)
			)
		)
		(duplicate_pad_numbers_are_jumpers no)
		(fp_line
			(start 0.508 -0.9398)
			(end -0.508 -0.9398)
			(stroke
				(width 0.1524)
				(type default)
			)
			(layer "F.SilkS")
		)
		(fp_line
			(start -0.508 -0.9398)
			(end -0.508 0.9398)
			(stroke
				(width 0.1524)
				(type default)
			)
			(layer "F.SilkS")
		)
		(fp_rect
			(start -0.508 0.9398)
			(end 0.508 -0.9398)
			(stroke
				(width 0)
				(type default)
			)
			(fill no)
			(layer "F.CrtYd")
		)
		(fp_rect
			(start -0.508 0.9398)
			(end 0.508 -0.9398)
			(stroke
				(width 0)
				(type default)
			)
			(fill no)
			(layer "F.Fab")
		)
		(pad "1" smd custom
			(at 0 -0.4445 180)
			(size 0.1397 0.1397)
			(layers "F.Cu" "F.Mask" "F.Paste")
			(net "SSD12_PWREN")
			(options
				(clearance outline)
				(anchor circle)
			)
			(primitives
				(gr_poly
					(pts
						(arc
							(start -0.1778 -0.2794)
							(mid -0.249642 -0.249642)
							(end -0.2794 -0.1778)
						)
						(arc
							(start -0.2794 0.1778)
							(mid -0.249642 0.249642)
							(end -0.1778 0.2794)
						)
						(arc
							(start 0.1778 0.2794)
							(mid 0.249642 0.249642)
							(end 0.2794 0.1778)
						)
						(arc
							(start 0.2794 -0.1778)
							(mid 0.249642 -0.249642)
							(end 0.1778 -0.2794)
						)
					)
					(width 0)
					(fill yes)
				)
			)
		)
		(pad "2" smd custom
			(at 0 0.4445 180)
			(size 0.1397 0.1397)
			(layers "F.Cu" "F.Mask" "F.Paste")
			(net "GND")
			(options
				(clearance outline)
				(anchor circle)
			)
			(primitives
				(gr_poly
					(pts
						(arc
							(start -0.1778 -0.2794)
							(mid -0.249642 -0.249642)
							(end -0.2794 -0.1778)
						)
						(arc
							(start -0.2794 0.1778)
							(mid -0.249642 0.249642)
							(end -0.1778 0.2794)
						)
						(arc
							(start 0.1778 0.2794)
							(mid 0.249642 0.249642)
							(end 0.2794 0.1778)
						)
						(arc
							(start 0.2794 -0.1778)
							(mid 0.249642 -0.249642)
							(end 0.1778 -0.2794)
						)
					)
					(width 0)
					(fill yes)
				)
			)
		)
	)
	(footprint ""
		(layer "F.Cu")
		(at 17.9578 -499.1608 -90)
		(property "Reference" "Q51"
			(at 0 0 270)
			(layer "F.SilkS")
			(hide yes)
			(effects
				(font
					(size 1.27 1.27)
				)
			)
		)
		(property "Value" "2N7002A-7-GP"
			(at 0.127 -8.9662 270)
			(unlocked yes)
			(layer "F.Fab")
			(hide yes)
			(effects
				(font
					(size 1.016 1.016)
					(thickness 0.1524)
				)
			)
		)
		(property "Device Type" "SOT23DGS2D4H48"
			(at 0.127 -10.4902 270)
			(unlocked yes)
			(layer "F.Fab")
			(hide yes)
			(effects
				(font
					(size 1.016 1.016)
					(thickness 0.1524)
				)
			)
		)
		(duplicate_pad_numbers_are_jumpers no)
		(fp_line
			(start -1.651 1.778)
			(end 1.651 1.778)
			(stroke
				(width 0.1524)
				(type default)
			)
			(layer "F.SilkS")
		)
		(fp_line
			(start 1.651 1.778)
			(end 1.651 -1.778)
			(stroke
				(width 0.1524)
				(type default)
			)
			(layer "F.SilkS")
		)
		(fp_line
			(start -1.651 -1.778)
			(end -1.651 1.778)
			(stroke
				(width 0.1524)
				(type default)
			)
			(layer "F.SilkS")
		)
		(fp_line
			(start 1.651 -1.778)
			(end -1.651 -1.778)
			(stroke
				(width 0.1524)
				(type default)
			)
			(layer "F.SilkS")
		)
		(fp_poly
			(pts
				(xy -1.778 1.8796) (xy -1.778 -1.8796) (xy 1.778 -1.8796) (xy 1.778 1.8796)
			)
			(stroke
				(width 0)
				(type default)
			)
			(fill no)
			(layer "F.CrtYd")
		)
		(fp_poly
			(pts
				(xy -1.778 1.8796) (xy -1.778 -1.8796) (xy 1.778 -1.8796) (xy 1.778 1.8796)
			)
			(stroke
				(width 0)
				(type default)
			)
			(fill no)
			(layer "F.Fab")
		)
		(pad "D" smd custom
			(at 0 -0.9525 270)
			(size 0.1905 0.1905)
			(layers "F.Cu" "F.Mask" "F.Paste")
			(net "P12V_MOST5_GATE_D")
			(options
				(clearance outline)
				(anchor circle)
			)
			(primitives
				(gr_poly
					(pts
						(arc
							(start -0.1778 0.5715)
							(mid -0.321484 0.511984)
							(end -0.381 0.3683)
						)
						(arc
							(start -0.381 -0.3683)
							(mid -0.321484 -0.511984)
							(end -0.1778 -0.5715)
						)
						(arc
							(start 0.1778 -0.5715)
							(mid 0.321484 -0.511984)
							(end 0.381 -0.3683)
						)
						(arc
							(start 0.381 0.3683)
							(mid 0.321484 0.511984)
							(end 0.1778 0.5715)
						)
					)
					(width 0)
					(fill yes)
				)
			)
		)
		(pad "G" smd custom
			(at -0.98425 0.9525 270)
			(size 0.1905 0.1905)
			(layers "F.Cu" "F.Mask" "F.Paste")
			(net "P12V_MOST5_GATE")
			(options
				(clearance outline)
				(anchor circle)
			)
			(primitives
				(gr_poly
					(pts
						(arc
							(start -0.1778 0.5715)
							(mid -0.321484 0.511984)
							(end -0.381 0.3683)
						)
						(arc
							(start -0.381 -0.3683)
							(mid -0.321484 -0.511984)
							(end -0.1778 -0.5715)
						)
						(arc
							(start 0.1778 -0.5715)
							(mid 0.321484 -0.511984)
							(end 0.381 -0.3683)
						)
						(arc
							(start 0.381 0.3683)
							(mid 0.321484 0.511984)
							(end 0.1778 0.5715)
						)
					)
					(width 0)
					(fill yes)
				)
			)
		)
		(pad "S" smd custom
			(at 0.98425 0.9525 270)
			(size 0.1905 0.1905)
			(layers "F.Cu" "F.Mask" "F.Paste")
			(net "GND")
			(options
				(clearance outline)
				(anchor circle)
			)
			(primitives
				(gr_poly
					(pts
						(arc
							(start -0.1778 0.5715)
							(mid -0.321484 0.511984)
							(end -0.381 0.3683)
						)
						(arc
							(start -0.381 -0.3683)
							(mid -0.321484 -0.511984)
							(end -0.1778 -0.5715)
						)
						(arc
							(start 0.1778 -0.5715)
							(mid 0.321484 -0.511984)
							(end 0.381 -0.3683)
						)
						(arc
							(start 0.381 0.3683)
							(mid 0.321484 0.511984)
							(end 0.1778 0.5715)
						)
					)
					(width 0)
					(fill yes)
				)
			)
		)
	)
	(footprint ""
		(layer "F.Cu")
		(at 82.931 -214.122 -90)
		(property "Reference" "PR9063"
			(at 0 0 270)
			(layer "F.SilkS")
			(hide yes)
			(effects
				(font
					(size 1.27 1.27)
				)
			)
		)
		(property "Value" "1K4R2F-1-GP"
			(at 0.064008 -3.993896 270)
			(unlocked yes)
			(layer "F.Fab")
			(hide yes)
			(effects
				(font
					(size 1.016 1.016)
					(thickness 0.1524)
				)
			)
		)
		(property "Device Type" "R402H16"
			(at 0.064008 -5.517896 270)
			(unlocked yes)
			(layer "F.Fab")
			(hide yes)
			(effects
				(font
					(size 1.016 1.016)
					(thickness 0.1524)
				)
			)
		)
		(duplicate_pad_numbers_are_jumpers no)
		(fp_line
			(start -0.508 -0.9398)
			(end -0.508 0.9398)
			(stroke
				(width 0.1524)
				(type default)
			)
			(layer "F.SilkS")
		)
		(fp_line
			(start 0.508 -0.9398)
			(end -0.508 -0.9398)
			(stroke
				(width 0.1524)
				(type default)
			)
			(layer "F.SilkS")
		)
		(fp_rect
			(start -0.508 0.9398)
			(end 0.508 -0.9398)
			(stroke
				(width 0)
				(type default)
			)
			(fill no)
			(layer "F.CrtYd")
		)
		(fp_rect
			(start -0.508 0.9398)
			(end 0.508 -0.9398)
			(stroke
				(width 0)
				(type default)
			)
			(fill no)
			(layer "F.Fab")
		)
		(pad "1" smd custom
			(at 0 -0.4445 270)
			(size 0.1397 0.1397)
			(layers "F.Cu" "F.Mask" "F.Paste")
			(net "CLK_BUF_EU3_HIBW_BYPM_LOBW#")
			(options
				(clearance outline)
				(anchor circle)
			)
			(primitives
				(gr_poly
					(pts
						(arc
							(start -0.1778 -0.2794)
							(mid -0.249642 -0.249642)
							(end -0.2794 -0.1778)
						)
						(arc
							(start -0.2794 0.1778)
							(mid -0.249642 0.249642)
							(end -0.1778 0.2794)
						)
						(arc
							(start 0.1778 0.2794)
							(mid 0.249642 0.249642)
							(end 0.2794 0.1778)
						)
						(arc
							(start 0.2794 -0.1778)
							(mid 0.249642 -0.249642)
							(end 0.1778 -0.2794)
						)
					)
					(width 0)
					(fill yes)
				)
			)
		)
		(pad "2" smd custom
			(at 0 0.4445 270)
			(size 0.1397 0.1397)
			(layers "F.Cu" "F.Mask" "F.Paste")
			(net "GND")
			(options
				(clearance outline)
				(anchor circle)
			)
			(primitives
				(gr_poly
					(pts
						(arc
							(start -0.1778 -0.2794)
							(mid -0.249642 -0.249642)
							(end -0.2794 -0.1778)
						)
						(arc
							(start -0.2794 0.1778)
							(mid -0.249642 0.249642)
							(end -0.1778 0.2794)
						)
						(arc
							(start 0.1778 0.2794)
							(mid 0.249642 0.249642)
							(end 0.2794 0.1778)
						)
						(arc
							(start 0.2794 -0.1778)
							(mid 0.249642 -0.249642)
							(end 0.1778 -0.2794)
						)
					)
					(width 0)
					(fill yes)
				)
			)
		)
	)
	(footprint ""
		(layer "F.Cu")
		(at 21.5138 -295.6306)
		(property "Reference" "D25"
			(at 0 0 0)
			(layer "F.SilkS")
			(hide yes)
			(effects
				(font
					(size 1.27 1.27)
				)
			)
		)
		(property "Value" "RB551V30-1-GP"
			(at 0 -6.7818 0)
			(unlocked yes)
			(layer "F.Fab")
			(hide yes)
			(effects
				(font
					(size 1.016 1.016)
					(thickness 0.1524)
				)
			)
		)
		(property "Device Type" "SOD323AKH44"
			(at 0 -8.6868 0)
			(unlocked yes)
			(layer "F.Fab")
			(hide yes)
			(effects
				(font
					(size 1.016 1.016)
					(thickness 0.1524)
				)
			)
		)
		(duplicate_pad_numbers_are_jumpers no)
		(fp_line
			(start -0.889 -1.9304)
			(end 0.889 -1.9304)
			(stroke
				(width 0.1524)
				(type default)
			)
			(layer "F.SilkS")
		)
		(fp_line
			(start -0.889 2.159)
			(end -0.889 -1.9304)
			(stroke
				(width 0.1524)
				(type default)
			)
			(layer "F.SilkS")
		)
		(fp_line
			(start 0.762 2.0574)
			(end -0.762 2.0574)
			(stroke
				(width 0.508)
				(type default)
			)
			(layer "F.SilkS")
		)
		(fp_line
			(start 0.889 -1.9304)
			(end 0.889 2.159)
			(stroke
				(width 0.1524)
				(type default)
			)
			(layer "F.SilkS")
		)
		(fp_line
			(start 0.889 2.159)
			(end -0.889 2.159)
			(stroke
				(width 0.1524)
				(type default)
			)
			(layer "F.SilkS")
		)
		(fp_rect
			(start -1.016 2.3114)
			(end 1.016 -2.0066)
			(stroke
				(width 0)
				(type default)
			)
			(fill no)
			(layer "F.CrtYd")
		)
		(fp_poly
			(pts
				(xy -1.016 -2.0066) (xy 1.016 -2.0066) (xy 1.016 2.3114) (xy -1.016 2.3114)
			)
			(stroke
				(width 0)
				(type default)
			)
			(fill no)
			(layer "F.Fab")
		)
		(pad "A" smd rect
			(at 0 -1.143)
			(size 0.5588 1.016)
			(layers "F.Cu" "F.Mask" "F.Paste")
			(net "SW_SSD7_R")
		)
		(pad "K" smd rect
			(at 0 1.143)
			(size 0.5588 1.016)
			(layers "F.Cu" "F.Mask" "F.Paste")
			(net "SW_SSD7_N")
		)
	)
	(footprint ""
		(layer "F.Cu")
		(at 76.2 -361.061 -90)
		(property "Reference" "EU17"
			(at 0 0 270)
			(layer "F.SilkS")
			(hide yes)
			(effects
				(font
					(size 1.27 1.27)
				)
			)
		)
		(property "Value" "PCA9547BS-GP"
			(at 4.064 -5.5372 270)
			(unlocked yes)
			(layer "F.Fab")
			(hide yes)
			(effects
				(font
					(size 1.016 1.016)
					(thickness 0.1524)
				)
			)
		)
		(property "Device Type" "QFN24-G2D25H40"
			(at 4.064 -7.0612 270)
			(unlocked yes)
			(layer "F.Fab")
			(hide yes)
			(effects
				(font
					(size 1.016 1.016)
					(thickness 0.1524)
				)
			)
		)
		(duplicate_pad_numbers_are_jumpers no)
		(fp_line
			(start -0.254 3.302)
			(end -0.254 2.794)
			(stroke
				(width 0.1524)
				(type default)
			)
			(layer "F.SilkS")
		)
		(fp_line
			(start -3.0226 3.0226)
			(end -1.7526 3.0226)
			(stroke
				(width 0.1524)
				(type default)
			)
			(layer "F.SilkS")
		)
		(fp_line
			(start 1.7526 3.0226)
			(end 3.0226 3.0226)
			(stroke
				(width 0.1524)
				(type default)
			)
			(layer "F.SilkS")
		)
		(fp_line
			(start 3.0226 3.0226)
			(end 3.0226 1.7526)
			(stroke
				(width 0.1524)
				(type default)
			)
			(layer "F.SilkS")
		)
		(fp_line
			(start -3.0226 1.7526)
			(end -3.0226 3.0226)
			(stroke
				(width 0.1524)
				(type default)
			)
			(layer "F.SilkS")
		)
		(fp_line
			(start 2.8194 0.762)
			(end 3.5814 0.762)
			(stroke
				(width 0.1524)
				(type default)
			)
			(layer "F.SilkS")
		)
		(fp_line
			(start -3.5306 0.254)
			(end -2.7686 0.254)
			(stroke
				(width 0.1524)
				(type default)
			)
			(layer "F.SilkS")
		)
		(fp_line
			(start -3.0226 -1.7526)
			(end -3.0226 -3.0226)
			(stroke
				(width 0.1524)
				(type default)
			)
			(layer "F.SilkS")
		)
		(fp_line
			(start -0.7366 -2.794)
			(end -0.7366 -3.302)
			(stroke
				(width 0.1524)
				(type default)
			)
			(layer "F.SilkS")
		)
		(fp_line
			(start -3.0226 -3.0226)
			(end -1.7526 -3.0226)
			(stroke
				(width 0.1524)
				(type default)
			)
			(layer "F.SilkS")
		)
		(fp_poly
			(pts
				(xy 1.7526 -3.0226) (xy 3.0226 -1.7526) (xy 3.0226 -3.0226)
			)
			(stroke
				(width 0)
				(type default)
			)
			(fill yes)
			(layer "F.SilkS")
		)
		(fp_rect
			(start -2.0066 2.0066)
			(end 2.0066 -2.0066)
			(stroke
				(width 0)
				(type default)
			)
			(fill no)
			(layer "F.CrtYd")
		)
		(fp_poly
			(pts
				(xy -2.0066 -2.0066) (xy -2.0066 -3.0226) (xy -3.0226 -3.0226) (xy -3.0226 3.0226) (xy 3.0226 3.0226)
				(xy 3.0226 -3.0226) (xy -2.00152 -3.0226) (xy -2.00152 -2.0066) (xy 2.0066 -2.0066) (xy 2.0066 2.0066)
				(xy -2.0066 2.0066)
			)
			(stroke
				(width 0)
				(type default)
			)
			(fill no)
			(layer "F.CrtYd")
		)
		(fp_rect
			(start -3.0226 3.0226)
			(end 3.0226 -3.0226)
			(stroke
				(width 0)
				(type default)
			)
			(fill no)
			(layer "F.Fab")
		)
		(pad "1" smd rect
			(at 1.249934 -2.0574 270)
			(size 0.3048 0.9144)
			(layers "F.Cu" "F.Mask" "F.Paste")
			(net "SDA_DR2")
		)
		(pad "2" smd rect
			(at 0.750062 -1.9812 270)
			(size 0.3048 1.0668)
			(layers "F.Cu" "F.Mask" "F.Paste")
			(net "SCL_DR2")
		)
		(pad "3" smd rect
			(at 0.249936 -1.9812 270)
			(size 0.3048 1.0668)
			(layers "F.Cu" "F.Mask" "F.Paste")
			(net "SDA_DR1")
		)
		(pad "4" smd rect
			(at -0.249936 -1.9812 270)
			(size 0.3048 1.0668)
			(layers "F.Cu" "F.Mask" "F.Paste")
			(net "SCL_DR1")
		)
		(pad "5" smd rect
			(at -0.750062 -1.9812 270)
			(size 0.3048 1.0668)
			(layers "F.Cu" "F.Mask" "F.Paste")
			(net "SDA_DR0")
		)
		(pad "6" smd rect
			(at -1.249934 -2.0574 270)
			(size 0.3048 0.9144)
			(layers "F.Cu" "F.Mask" "F.Paste")
			(net "SCL_DR0")
		)
		(pad "7" smd rect
			(at -2.0574 -1.249934 270)
			(size 0.9144 0.3048)
			(layers "F.Cu" "F.Mask" "F.Paste")
			(net "SDA_DR5")
		)
		(pad "8" smd rect
			(at -1.9812 -0.750062 270)
			(size 1.0668 0.3048)
			(layers "F.Cu" "F.Mask" "F.Paste")
			(net "SCL_DR5")
		)
		(pad "9" smd rect
			(at -1.9812 -0.249936 270)
			(size 1.0668 0.3048)
			(layers "F.Cu" "F.Mask" "F.Paste")
			(net "GND")
		)
		(pad "10" smd rect
			(at -1.9812 0.249936 270)
			(size 1.0668 0.3048)
			(layers "F.Cu" "F.Mask" "F.Paste")
			(net "SDA_DR10")
		)
		(pad "11" smd rect
			(at -1.9812 0.750062 270)
			(size 1.0668 0.3048)
			(layers "F.Cu" "F.Mask" "F.Paste")
			(net "SCL_DR10")
		)
		(pad "12" smd rect
			(at -2.0574 1.249934 270)
			(size 0.9144 0.3048)
			(layers "F.Cu" "F.Mask" "F.Paste")
			(net "SDA_DR6")
		)
		(pad "13" smd rect
			(at -1.249934 2.0574 270)
			(size 0.3048 0.9144)
			(layers "F.Cu" "F.Mask" "F.Paste")
			(net "SCL_DR6")
		)
		(pad "14" smd rect
			(at -0.750062 1.9812 270)
			(size 0.3048 1.0668)
			(layers "F.Cu" "F.Mask" "F.Paste")
			(net "SDA_DR11")
		)
		(pad "15" smd rect
			(at -0.249936 1.9812 270)
			(size 0.3048 1.0668)
			(layers "F.Cu" "F.Mask" "F.Paste")
			(net "SCL_DR11")
		)
		(pad "16" smd rect
			(at 0.249936 1.9812 270)
			(size 0.3048 1.0668)
			(layers "F.Cu" "F.Mask" "F.Paste")
			(net "SDA_DR7")
		)
		(pad "17" smd rect
			(at 0.750062 1.9812 270)
			(size 0.3048 1.0668)
			(layers "F.Cu" "F.Mask" "F.Paste")
			(net "SCL_DR7")
		)
		(pad "18" smd rect
			(at 1.249934 2.0574 270)
			(size 0.3048 0.9144)
			(layers "F.Cu" "F.Mask" "F.Paste")
			(net "I2C_SW_EU17_ADDRESS_A2")
		)
		(pad "19" smd rect
			(at 2.0574 1.249934 270)
			(size 0.9144 0.3048)
			(layers "F.Cu" "F.Mask" "F.Paste")
			(net "I2C8_SCL_R_SW_EU17")
		)
		(pad "20" smd rect
			(at 1.9812 0.750062 270)
			(size 1.0668 0.3048)
			(layers "F.Cu" "F.Mask" "F.Paste")
			(net "I2C8_SDA_R_SW_EU17")
		)
		(pad "21" smd rect
			(at 1.9812 0.249936 270)
			(size 1.0668 0.3048)
			(layers "F.Cu" "F.Mask" "F.Paste")
			(net "P3V3")
		)
		(pad "22" smd rect
			(at 1.9812 -0.249936 270)
			(size 1.0668 0.3048)
			(layers "F.Cu" "F.Mask" "F.Paste")
			(net "I2C_SW_EU17_ADDRESS_A0")
		)
		(pad "23" smd rect
			(at 1.9812 -0.750062 270)
			(size 1.0668 0.3048)
			(layers "F.Cu" "F.Mask" "F.Paste")
			(net "I2C_SW_EU17_ADDRESS_A1")
		)
		(pad "24" smd rect
			(at 2.0574 -1.249934 270)
			(size 0.9144 0.3048)
			(layers "F.Cu" "F.Mask" "F.Paste")
			(net "I2C_MUX_RESET_R_EU17")
		)
		(pad "25" smd rect
			(at 0 0 270)
			(size 2.2606 2.2606)
			(layers "F.Cu" "F.Mask" "F.Paste")
			(net "GND")
		)
	)
	(footprint ""
		(layer "F.Cu")
		(at 48.387 -7.0104 90)
		(property "Reference" "Q97"
			(at 0 0 90)
			(layer "F.SilkS")
			(hide yes)
			(effects
				(font
					(size 1.27 1.27)
				)
			)
		)
		(property "Value" "2N7002A-7-GP"
			(at 0.127 -8.9662 90)
			(unlocked yes)
			(layer "F.Fab")
			(hide yes)
			(effects
				(font
					(size 1.016 1.016)
					(thickness 0.1524)
				)
			)
		)
		(property "Device Type" "SOT23DGS2D4H48"
			(at 0.127 -10.4902 90)
			(unlocked yes)
			(layer "F.Fab")
			(hide yes)
			(effects
				(font
					(size 1.016 1.016)
					(thickness 0.1524)
				)
			)
		)
		(duplicate_pad_numbers_are_jumpers no)
		(fp_line
			(start 1.651 -1.778)
			(end -1.651 -1.778)
			(stroke
				(width 0.1524)
				(type default)
			)
			(layer "F.SilkS")
		)
		(fp_line
			(start -1.651 -1.778)
			(end -1.651 1.778)
			(stroke
				(width 0.1524)
				(type default)
			)
			(layer "F.SilkS")
		)
		(fp_line
			(start 1.651 1.778)
			(end 1.651 -1.778)
			(stroke
				(width 0.1524)
				(type default)
			)
			(layer "F.SilkS")
		)
		(fp_line
			(start -1.651 1.778)
			(end 1.651 1.778)
			(stroke
				(width 0.1524)
				(type default)
			)
			(layer "F.SilkS")
		)
		(fp_poly
			(pts
				(xy -1.778 1.8796) (xy -1.778 -1.8796) (xy 1.778 -1.8796) (xy 1.778 1.8796)
			)
			(stroke
				(width 0)
				(type default)
			)
			(fill no)
			(layer "F.CrtYd")
		)
		(fp_poly
			(pts
				(xy -1.778 1.8796) (xy -1.778 -1.8796) (xy 1.778 -1.8796) (xy 1.778 1.8796)
			)
			(stroke
				(width 0)
				(type default)
			)
			(fill no)
			(layer "F.Fab")
		)
		(pad "D" smd custom
			(at 0 -0.9525 90)
			(size 0.1905 0.1905)
			(layers "F.Cu" "F.Mask" "F.Paste")
			(net "P12V_MOST14_GATE")
			(options
				(clearance outline)
				(anchor circle)
			)
			(primitives
				(gr_poly
					(pts
						(arc
							(start -0.1778 0.5715)
							(mid -0.321484 0.511984)
							(end -0.381 0.3683)
						)
						(arc
							(start -0.381 -0.3683)
							(mid -0.321484 -0.511984)
							(end -0.1778 -0.5715)
						)
						(arc
							(start 0.1778 -0.5715)
							(mid 0.321484 -0.511984)
							(end 0.381 -0.3683)
						)
						(arc
							(start 0.381 0.3683)
							(mid 0.321484 0.511984)
							(end 0.1778 0.5715)
						)
					)
					(width 0)
					(fill yes)
				)
			)
		)
		(pad "G" smd custom
			(at -0.98425 0.9525 90)
			(size 0.1905 0.1905)
			(layers "F.Cu" "F.Mask" "F.Paste")
			(net "SSD14_PWREN_R")
			(options
				(clearance outline)
				(anchor circle)
			)
			(primitives
				(gr_poly
					(pts
						(arc
							(start -0.1778 0.5715)
							(mid -0.321484 0.511984)
							(end -0.381 0.3683)
						)
						(arc
							(start -0.381 -0.3683)
							(mid -0.321484 -0.511984)
							(end -0.1778 -0.5715)
						)
						(arc
							(start 0.1778 -0.5715)
							(mid 0.321484 -0.511984)
							(end 0.381 -0.3683)
						)
						(arc
							(start 0.381 0.3683)
							(mid 0.321484 0.511984)
							(end 0.1778 0.5715)
						)
					)
					(width 0)
					(fill yes)
				)
			)
		)
		(pad "S" smd custom
			(at 0.98425 0.9525 90)
			(size 0.1905 0.1905)
			(layers "F.Cu" "F.Mask" "F.Paste")
			(net "GND")
			(options
				(clearance outline)
				(anchor circle)
			)
			(primitives
				(gr_poly
					(pts
						(arc
							(start -0.1778 0.5715)
							(mid -0.321484 0.511984)
							(end -0.381 0.3683)
						)
						(arc
							(start -0.381 -0.3683)
							(mid -0.321484 -0.511984)
							(end -0.1778 -0.5715)
						)
						(arc
							(start 0.1778 -0.5715)
							(mid 0.321484 -0.511984)
							(end 0.381 -0.3683)
						)
						(arc
							(start 0.381 0.3683)
							(mid 0.321484 0.511984)
							(end 0.1778 0.5715)
						)
					)
					(width 0)
					(fill yes)
				)
			)
		)
	)
	(footprint ""
		(layer "F.Cu")
		(at 30.988 -374.65)
		(property "Reference" "R340"
			(at 0 0 0)
			(layer "F.SilkS")
			(hide yes)
			(effects
				(font
					(size 1.27 1.27)
				)
			)
		)
		(property "Value" "4K7R2F-GP"
			(at 0.064008 -3.993896 0)
			(unlocked yes)
			(layer "F.Fab")
			(hide yes)
			(effects
				(font
					(size 1.016 1.016)
					(thickness 0.1524)
				)
			)
		)
		(property "Device Type" "R402H16"
			(at 0.064008 -5.517896 0)
			(unlocked yes)
			(layer "F.Fab")
			(hide yes)
			(effects
				(font
					(size 1.016 1.016)
					(thickness 0.1524)
				)
			)
		)
		(duplicate_pad_numbers_are_jumpers no)
		(fp_line
			(start -0.508 -0.9398)
			(end -0.508 0.9398)
			(stroke
				(width 0.1524)
				(type default)
			)
			(layer "F.SilkS")
		)
		(fp_line
			(start 0.508 -0.9398)
			(end -0.508 -0.9398)
			(stroke
				(width 0.1524)
				(type default)
			)
			(layer "F.SilkS")
		)
		(fp_rect
			(start -0.508 0.9398)
			(end 0.508 -0.9398)
			(stroke
				(width 0)
				(type default)
			)
			(fill no)
			(layer "F.CrtYd")
		)
		(fp_rect
			(start -0.508 0.9398)
			(end 0.508 -0.9398)
			(stroke
				(width 0)
				(type default)
			)
			(fill no)
			(layer "F.Fab")
		)
		(pad "1" smd custom
			(at 0 -0.4445)
			(size 0.1397 0.1397)
			(layers "F.Cu" "F.Mask" "F.Paste")
			(net "I2C_B_TMP4_A1")
			(options
				(clearance outline)
				(anchor circle)
			)
			(primitives
				(gr_poly
					(pts
						(arc
							(start -0.1778 -0.2794)
							(mid -0.249642 -0.249642)
							(end -0.2794 -0.1778)
						)
						(arc
							(start -0.2794 0.1778)
							(mid -0.249642 0.249642)
							(end -0.1778 0.2794)
						)
						(arc
							(start 0.1778 0.2794)
							(mid 0.249642 0.249642)
							(end 0.2794 0.1778)
						)
						(arc
							(start 0.2794 -0.1778)
							(mid 0.249642 -0.249642)
							(end 0.1778 -0.2794)
						)
					)
					(width 0)
					(fill yes)
				)
			)
		)
		(pad "2" smd custom
			(at 0 0.4445)
			(size 0.1397 0.1397)
			(layers "F.Cu" "F.Mask" "F.Paste")
			(net "GND")
			(options
				(clearance outline)
				(anchor circle)
			)
			(primitives
				(gr_poly
					(pts
						(arc
							(start -0.1778 -0.2794)
							(mid -0.249642 -0.249642)
							(end -0.2794 -0.1778)
						)
						(arc
							(start -0.2794 0.1778)
							(mid -0.249642 0.249642)
							(end -0.1778 0.2794)
						)
						(arc
							(start 0.1778 0.2794)
							(mid 0.249642 0.249642)
							(end 0.2794 0.1778)
						)
						(arc
							(start 0.2794 -0.1778)
							(mid 0.249642 -0.249642)
							(end 0.1778 -0.2794)
						)
					)
					(width 0)
					(fill yes)
				)
			)
		)
	)
	(footprint ""
		(layer "F.Cu")
		(at 29.7688 -294.9956 -90)
		(property "Reference" "U16"
			(at 0 0 270)
			(layer "F.SilkS")
			(hide yes)
			(effects
				(font
					(size 1.27 1.27)
				)
			)
		)
		(property "Value" "P2003EVG-GP"
			(at 0 -11.1252 270)
			(unlocked yes)
			(layer "F.Fab")
			(hide yes)
			(effects
				(font
					(size 1.016 1.016)
					(thickness 0.1524)
				)
			)
		)
		(property "Device Type" "SOIC8H79"
			(at 0 -12.6492 270)
			(unlocked yes)
			(layer "F.Fab")
			(hide yes)
			(effects
				(font
					(size 1.016 1.016)
					(thickness 0.1524)
				)
			)
		)
		(duplicate_pad_numbers_are_jumpers no)
		(fp_line
			(start -2.6162 3.429)
			(end -2.6162 1.4732)
			(stroke
				(width 0.4064)
				(type default)
			)
			(layer "F.SilkS")
		)
		(fp_line
			(start -2.7432 1.4224)
			(end 2.1336 1.4224)
			(stroke
				(width 0.1524)
				(type default)
			)
			(layer "F.SilkS")
		)
		(fp_line
			(start 2.1336 1.4224)
			(end 2.1336 -1.4224)
			(stroke
				(width 0.1524)
				(type default)
			)
			(layer "F.SilkS")
		)
		(fp_line
			(start -2.2352 0)
			(end -2.7432 0.508)
			(stroke
				(width 0.1524)
				(type default)
			)
			(layer "F.SilkS")
		)
		(fp_line
			(start -2.7432 -0.508)
			(end -2.2352 0)
			(stroke
				(width 0.1524)
				(type default)
			)
			(layer "F.SilkS")
		)
		(fp_line
			(start -2.7432 -1.4224)
			(end -2.7432 1.4224)
			(stroke
				(width 0.1524)
				(type default)
			)
			(layer "F.SilkS")
		)
		(fp_line
			(start 2.1336 -1.4224)
			(end -2.7432 -1.4224)
			(stroke
				(width 0.1524)
				(type default)
			)
			(layer "F.SilkS")
		)
		(fp_poly
			(pts
				(xy 2.2098 -1.4224) (xy 2.2098 1.4224) (xy -2.2225 1.4224) (xy -2.2225 -1.4224)
			)
			(stroke
				(width 0)
				(type default)
			)
			(fill yes)
			(layer "F.SilkS")
		)
		(fp_rect
			(start -2.4511 2.9972)
			(end 2.4511 -2.9972)
			(stroke
				(width 0)
				(type default)
			)
			(fill no)
			(layer "F.CrtYd")
		)
		(fp_poly
			(pts
				(xy -2.8194 3.6322) (xy -2.8194 -3.6322) (xy 2.8194 -3.6322) (xy 2.8194 -2.2987) (xy 2.4511 -2.2987)
				(xy 2.4511 -2.9972) (xy -2.4511 -2.9972) (xy -2.4511 2.9972) (xy 2.4511 2.9972) (xy 2.4511 -2.286)
				(xy 2.8194 -2.286) (xy 2.8194 3.6322)
			)
			(stroke
				(width 0)
				(type default)
			)
			(fill no)
			(layer "F.CrtYd")
		)
		(fp_rect
			(start -2.8194 3.6322)
			(end 2.8194 -3.6322)
			(stroke
				(width 0)
				(type default)
			)
			(fill no)
			(layer "F.Fab")
		)
		(pad "1" smd rect
			(at -1.905 2.54 270)
			(size 0.635 1.651)
			(layers "F.Cu" "F.Mask" "F.Paste")
			(net "P12V")
		)
		(pad "2" smd rect
			(at -0.635 2.54 270)
			(size 0.635 1.651)
			(layers "F.Cu" "F.Mask" "F.Paste")
			(net "P12V")
		)
		(pad "3" smd rect
			(at 0.635 2.54 270)
			(size 0.635 1.651)
			(layers "F.Cu" "F.Mask" "F.Paste")
			(net "P12V")
		)
		(pad "4" smd rect
			(at 1.905 2.54 270)
			(size 0.635 1.651)
			(layers "F.Cu" "F.Mask" "F.Paste")
			(net "SW_SSD7_N")
		)
		(pad "5" smd rect
			(at 1.905 -2.54 270)
			(size 0.635 1.651)
			(layers "F.Cu" "F.Mask" "F.Paste")
			(net "P12V_SSD7")
		)
		(pad "6" smd rect
			(at 0.635 -2.54 270)
			(size 0.635 1.651)
			(layers "F.Cu" "F.Mask" "F.Paste")
			(net "P12V_SSD7")
		)
		(pad "7" smd rect
			(at -0.635 -2.54 270)
			(size 0.635 1.651)
			(layers "F.Cu" "F.Mask" "F.Paste")
			(net "P12V_SSD7")
		)
		(pad "8" smd rect
			(at -1.905 -2.54 270)
			(size 0.635 1.651)
			(layers "F.Cu" "F.Mask" "F.Paste")
			(net "P12V_SSD7")
		)
	)
	(footprint ""
		(layer "F.Cu")
		(at 41.150032 -376.670062 90)
		(property "Reference" "J6"
			(at 0 0 90)
			(layer "F.SilkS")
			(hide yes)
			(effects
				(font
					(size 1.27 1.27)
				)
			)
		)
		(property "Value" "PCISLT68-14-GP-U1"
			(at -22.225 12.7508 90)
			(unlocked yes)
			(layer "F.Fab")
			(hide yes)
			(effects
				(font
					(size 1.016 1.016)
					(thickness 0.1524)
				)
			)
		)
		(property "Device Type" "SD-78827-0001"
			(at -22.225 11.2268 90)
			(unlocked yes)
			(layer "F.Fab")
			(hide yes)
			(effects
				(font
					(size 1.016 1.016)
					(thickness 0.1524)
				)
			)
		)
		(duplicate_pad_numbers_are_jumpers no)
		(fp_line
			(start 20.4724 -3.4036)
			(end 20.4724 0.0254)
			(stroke
				(width 0.1524)
				(type default)
			)
			(layer "F.SilkS")
		)
		(fp_line
			(start -20.4724 -3.4036)
			(end 20.4724 -3.4036)
			(stroke
				(width 0.1524)
				(type default)
			)
			(layer "F.SilkS")
		)
		(fp_line
			(start 23.749 0.0254)
			(end 23.749 4.6736)
			(stroke
				(width 0.1524)
				(type default)
			)
			(layer "F.SilkS")
		)
		(fp_line
			(start 20.4724 0.0254)
			(end 23.749 0.0254)
			(stroke
				(width 0.1524)
				(type default)
			)
			(layer "F.SilkS")
		)
		(fp_line
			(start -20.4724 0.0254)
			(end -20.4724 -3.4036)
			(stroke
				(width 0.1524)
				(type default)
			)
			(layer "F.SilkS")
		)
		(fp_line
			(start -23.749 0.0254)
			(end -20.4724 0.0254)
			(stroke
				(width 0.1524)
				(type default)
			)
			(layer "F.SilkS")
		)
		(fp_line
			(start 23.117556 1.803908)
			(end 23.117556 2.896108)
			(stroke
				(width 0.3048)
				(type default)
			)
			(layer "F.SilkS")
		)
		(fp_line
			(start -20.882356 1.803908)
			(end -20.882356 2.896108)
			(stroke
				(width 0.3048)
				(type default)
			)
			(layer "F.SilkS")
		)
		(fp_line
			(start 20.882356 2.896108)
			(end 20.882356 1.803908)
			(stroke
				(width 0.3048)
				(type default)
			)
			(layer "F.SilkS")
		)
		(fp_line
			(start -23.117556 2.896108)
			(end -23.117556 1.803908)
			(stroke
				(width 0.3048)
				(type default)
			)
			(layer "F.SilkS")
		)
		(fp_line
			(start 23.749 4.6736)
			(end 20.4724 4.6736)
			(stroke
				(width 0.1524)
				(type default)
			)
			(layer "F.SilkS")
		)
		(fp_line
			(start 20.4724 4.6736)
			(end 20.4724 12.0142)
			(stroke
				(width 0.1524)
				(type default)
			)
			(layer "F.SilkS")
		)
		(fp_line
			(start -20.4724 4.6736)
			(end -23.749 4.6736)
			(stroke
				(width 0.1524)
				(type default)
			)
			(layer "F.SilkS")
		)
		(fp_line
			(start -23.749 4.6736)
			(end -23.749 0.0254)
			(stroke
				(width 0.1524)
				(type default)
			)
			(layer "F.SilkS")
		)
		(fp_line
			(start 17.8435 10.3124)
			(end -17.8435 10.3124)
			(stroke
				(width 0.1524)
				(type default)
			)
			(layer "F.SilkS")
		)
		(fp_line
			(start -17.8435 10.3124)
			(end -17.8435 12.0142)
			(stroke
				(width 0.1524)
				(type default)
			)
			(layer "F.SilkS")
		)
		(fp_line
			(start 20.4724 12.0142)
			(end 17.8435 12.0142)
			(stroke
				(width 0.1524)
				(type default)
			)
			(layer "F.SilkS")
		)
		(fp_line
			(start 17.8435 12.0142)
			(end 17.8435 10.3124)
			(stroke
				(width 0.1524)
				(type default)
			)
			(layer "F.SilkS")
		)
		(fp_line
			(start -17.8435 12.0142)
			(end -20.4724 12.0142)
			(stroke
				(width 0.1524)
				(type default)
			)
			(layer "F.SilkS")
		)
		(fp_line
			(start -20.4724 12.0142)
			(end -20.4724 4.6736)
			(stroke
				(width 0.1524)
				(type default)
			)
			(layer "F.SilkS")
		)
		(fp_arc
			(start 20.882356 1.803908)
			(mid 21.999956 0.686308)
			(end 23.117556 1.803908)
			(stroke
				(width 0.3048)
				(type default)
			)
			(layer "F.SilkS")
		)
		(fp_arc
			(start -23.117556 1.803908)
			(mid -21.999956 0.686308)
			(end -20.882356 1.803908)
			(stroke
				(width 0.3048)
				(type default)
			)
			(layer "F.SilkS")
		)
		(fp_arc
			(start 23.117556 2.896108)
			(mid 21.999956 4.013708)
			(end 20.882356 2.896108)
			(stroke
				(width 0.3048)
				(type default)
			)
			(layer "F.SilkS")
		)
		(fp_arc
			(start -20.882356 2.896108)
			(mid -21.999956 4.013708)
			(end -23.117556 2.896108)
			(stroke
				(width 0.3048)
				(type default)
			)
			(layer "F.SilkS")
		)
		(fp_poly
			(pts
				(xy -20.2184 11.7602) (xy -20.2184 4.4196) (xy -23.495 4.4196) (xy -23.495 0.2794) (xy -20.2184 0.2794)
				(xy -20.2184 -3.1496) (xy 20.2184 -3.1496) (xy 20.2184 0.2794) (xy 23.495 0.2794) (xy 23.495 4.4196)
				(xy 20.2184 4.4196) (xy 20.2184 11.7602) (xy 18.0975 11.7602) (xy 18.0975 10.0584) (xy -18.0975 10.0584)
				(xy -18.0975 11.7602)
			)
			(stroke
				(width 0)
				(type default)
			)
			(fill no)
			(layer "F.CrtYd")
		)
		(fp_poly
			(pts
				(xy -21.2471 16.256) (xy -21.2471 4.9276) (xy -24.003 4.9276) (xy -24.003 -0.2286) (xy -20.7264 -0.2286)
				(xy -20.7264 -3.6576) (xy 20.7264 -3.6576) (xy 20.7264 -0.2286) (xy 24.003 -0.2286) (xy 24.003 -0.00635)
				(xy 20.2184 -0.00635) (xy 20.2184 -3.1496) (xy -20.2184 -3.1496) (xy -20.2184 0.2794) (xy -23.495 0.2794)
				(xy -23.495 4.4196) (xy -20.2184 4.4196) (xy -20.2184 11.7602) (xy -18.0975 11.7602) (xy -18.0975 10.0584)
				(xy 18.0975 10.0584) (xy 18.0975 11.7602) (xy 20.2184 11.7602) (xy 20.2184 4.4196) (xy 23.495 4.4196)
				(xy 23.495 0.2794) (xy 20.2184 0.2794) (xy 20.2184 0.00635) (xy 24.003 0.00635) (xy 24.003 4.9276)
				(xy 21.2471 4.9276) (xy 21.2471 16.256)
			)
			(stroke
				(width 0)
				(type default)
			)
			(fill no)
			(layer "F.CrtYd")
		)
		(fp_poly
			(pts
				(xy -21.2471 16.256) (xy -21.2471 4.9276) (xy -24.003 4.9276) (xy -24.003 -0.2286) (xy -20.7264 -0.2286)
				(xy -20.7264 -3.6576) (xy 20.7264 -3.6576) (xy 20.7264 -0.2286) (xy 24.003 -0.2286) (xy 24.003 4.9276)
				(xy 21.2471 4.9276) (xy 21.2471 16.256)
			)
			(stroke
				(width 0)
				(type default)
			)
			(fill no)
			(layer "F.Fab")
		)
		(pad "" np_thru_hole circle
			(at -18.999962 0 90)
			(size 0.254 0.254)
			(drill 1.8542)
			(layers "*.Cu" "*.Mask")
			(clearance 1.1557)
			(thermal_gap 1.1557)
		)
		(pad "" np_thru_hole circle
			(at 18.999962 0 90)
			(size 0.254 0.254)
			(drill 1.8542)
			(layers "*.Cu" "*.Mask")
			(clearance 1.1557)
			(thermal_gap 1.1557)
		)
		(pad "E1" smd rect
			(at -7.079996 1.240028 90)
			(size 0.508 2.0066)
			(layers "F.Cu" "F.Mask" "F.Paste")
			(net "PE_CLK100M_DR6_2_P")
		)
		(pad "E2" smd rect
			(at -6.279896 1.240028 90)
			(size 0.508 2.0066)
			(layers "F.Cu" "F.Mask" "F.Paste")
			(net "PE_CLK100M_DR6_2_N")
		)
		(pad "E3" smd rect
			(at -5.48005 1.240028 90)
			(size 0.508 2.0066)
			(layers "F.Cu" "F.Mask" "F.Paste")
			(net "P3V3")
		)
		(pad "E4" smd rect
			(at -4.67995 1.240028 90)
			(size 0.508 2.0066)
			(layers "F.Cu" "F.Mask" "F.Paste")
			(net "SSD6_PERST_N")
		)
		(pad "E5" smd rect
			(at -3.880104 1.240028 90)
			(size 0.508 2.0066)
			(layers "F.Cu" "F.Mask" "F.Paste")
			(net "SSD6_PERST_N")
		)
		(pad "E6" smd rect
			(at -3.080004 1.240028 90)
			(size 0.508 2.0066)
			(layers "F.Cu" "F.Mask" "F.Paste")
			(net "Net_1125")
		)
		(pad "E7" smd rect
			(at -15.48003 -1.949958 90)
			(size 0.508 2.0066)
			(layers "F.Cu" "F.Mask" "F.Paste")
			(net "PE_CLK100M_DR6_1_P")
		)
		(pad "E8" smd rect
			(at -14.67993 -1.949958 90)
			(size 0.508 2.0066)
			(layers "F.Cu" "F.Mask" "F.Paste")
			(net "PE_CLK100M_DR6_1_N")
		)
		(pad "E9" smd rect
			(at -13.880084 -1.949958 90)
			(size 0.508 2.0066)
			(layers "F.Cu" "F.Mask" "F.Paste")
			(net "GND")
		)
		(pad "E10" smd rect
			(at -13.079984 -1.949958 90)
			(size 0.508 2.0066)
			(layers "F.Cu" "F.Mask" "F.Paste")
			(net "PE_TX1_DR6_N")
		)
		(pad "E11" smd rect
			(at -12.279884 -1.949958 90)
			(size 0.508 2.0066)
			(layers "F.Cu" "F.Mask" "F.Paste")
			(net "PE_TX1_DR6_P")
		)
		(pad "E12" smd rect
			(at -11.480038 -1.949958 90)
			(size 0.508 2.0066)
			(layers "F.Cu" "F.Mask" "F.Paste")
			(net "GND")
		)
		(pad "E13" smd rect
			(at -10.679938 -1.949958 90)
			(size 0.508 2.0066)
			(layers "F.Cu" "F.Mask" "F.Paste")
			(net "PE_RX1_DR6_N")
		)
		(pad "E14" smd rect
			(at -9.880092 -1.949958 90)
			(size 0.508 2.0066)
			(layers "F.Cu" "F.Mask" "F.Paste")
			(net "PE_RX1_DR6_P")
		)
		(pad "E15" smd rect
			(at -9.079992 -1.949958 90)
			(size 0.508 2.0066)
			(layers "F.Cu" "F.Mask" "F.Paste")
			(net "GND")
		)
		(pad "E16" smd rect
			(at -8.279892 -1.949958 90)
			(size 0.508 2.0066)
			(layers "F.Cu" "F.Mask" "F.Paste")
			(net "Net_1132")
		)
		(pad "E17" smd rect
			(at 9.320022 -1.949958 90)
			(size 0.508 2.0066)
			(layers "F.Cu" "F.Mask" "F.Paste")
			(net "PE_TX4_DR6_N")
		)
		(pad "E18" smd rect
			(at 10.120122 -1.949958 90)
			(size 0.508 2.0066)
			(layers "F.Cu" "F.Mask" "F.Paste")
			(net "PE_TX4_DR6_P")
		)
		(pad "E19" smd rect
			(at 10.919968 -1.949958 90)
			(size 0.508 2.0066)
			(layers "F.Cu" "F.Mask" "F.Paste")
			(net "GND")
		)
		(pad "E20" smd rect
			(at 11.720068 -1.949958 90)
			(size 0.508 2.0066)
			(layers "F.Cu" "F.Mask" "F.Paste")
			(net "PE_RX4_DR6_N")
		)
		(pad "E21" smd rect
			(at 12.519914 -1.949958 90)
			(size 0.508 2.0066)
			(layers "F.Cu" "F.Mask" "F.Paste")
			(net "PE_RX4_DR6_P")
		)
		(pad "E22" smd rect
			(at 13.320014 -1.949958 90)
			(size 0.508 2.0066)
			(layers "F.Cu" "F.Mask" "F.Paste")
			(net "GND")
		)
		(pad "E23" smd rect
			(at 14.120114 -1.949958 90)
			(size 0.508 2.0066)
			(layers "F.Cu" "F.Mask" "F.Paste")
			(net "SCL_DR6_R")
		)
		(pad "E24" smd rect
			(at 14.91996 -1.949958 90)
			(size 0.508 2.0066)
			(layers "F.Cu" "F.Mask" "F.Paste")
			(net "SDA_DR6_R")
		)
		(pad "E25" smd rect
			(at 15.72006 -1.949958 90)
			(size 0.508 2.0066)
			(layers "F.Cu" "F.Mask" "F.Paste")
			(net "DUALPORTEN#6")
		)
		(pad "P1" smd rect
			(at -1.905 0.824992 90)
			(size 0.6604 2.0574)
			(layers "F.Cu" "F.Mask" "F.Paste")
			(net "Net_1128")
		)
		(pad "P2" smd rect
			(at -0.635 0.824992 90)
			(size 0.6604 2.0574)
			(layers "F.Cu" "F.Mask" "F.Paste")
			(net "Net_1127")
		)
		(pad "P3" smd rect
			(at 0.635 0.824992 90)
			(size 0.6604 2.0574)
			(layers "F.Cu" "F.Mask" "F.Paste")
			(net "Net_1126")
		)
		(pad "P4" smd rect
			(at 1.905 0.824992 90)
			(size 0.6604 2.0574)
			(layers "F.Cu" "F.Mask" "F.Paste")
			(net "SSD6_CLK0_OE_N")
		)
		(pad "P5" smd rect
			(at 3.175 0.824992 90)
			(size 0.6604 2.0574)
			(layers "F.Cu" "F.Mask" "F.Paste")
			(net "GND")
		)
		(pad "P6" smd rect
			(at 4.445 0.824992 90)
			(size 0.6604 2.0574)
			(layers "F.Cu" "F.Mask" "F.Paste")
			(net "GND")
		)
		(pad "P7" smd rect
			(at 5.715 0.824992 90)
			(size 0.6604 2.0574)
			(layers "F.Cu" "F.Mask" "F.Paste")
			(net "Net_100")
		)
		(pad "P8" smd rect
			(at 6.985 0.824992 90)
			(size 0.6604 2.0574)
			(layers "F.Cu" "F.Mask" "F.Paste")
			(net "Net_73")
		)
		(pad "P9" smd rect
			(at 8.255 0.824992 90)
			(size 0.6604 2.0574)
			(layers "F.Cu" "F.Mask" "F.Paste")
			(net "Net_87")
		)
		(pad "P10" smd rect
			(at 9.525 0.824992 90)
			(size 0.6604 2.0574)
			(layers "F.Cu" "F.Mask" "F.Paste")
			(net "SSD_PRSNT_NET6")
		)
		(pad "P11" smd rect
			(at 10.795 0.824992 90)
			(size 0.6604 2.0574)
			(layers "F.Cu" "F.Mask" "F.Paste")
			(net "SSD_ACT_DR6")
		)
		(pad "P12" smd rect
			(at 12.065 0.824992 90)
			(size 0.6604 2.0574)
			(layers "F.Cu" "F.Mask" "F.Paste")
			(net "GND")
		)
		(pad "P13" smd rect
			(at 13.335 0.824992 90)
			(size 0.6604 2.0574)
			(layers "F.Cu" "F.Mask" "F.Paste")
			(net "12V_PRECH_SSD6")
		)
		(pad "P14" smd rect
			(at 14.605 0.824992 90)
			(size 0.6604 2.0574)
			(layers "F.Cu" "F.Mask" "F.Paste")
			(net "P12V_SSD6")
		)
		(pad "P15" smd rect
			(at 15.875 0.824992 90)
			(size 0.6604 2.0574)
			(layers "F.Cu" "F.Mask" "F.Paste")
			(net "P12V_SSD6")
		)
		(pad "PTH1" thru_hole oval
			(at -21.999956 2.350008 90)
			(size 1.524 2.6162)
			(drill oval 0.8128 1.905)
			(layers "*.Cu" "*.Mask")
			(remove_unused_layers no)
			(net "Net_1137")
			(clearance 0.1524)
			(thermal_gap 0.1524)
		)
		(pad "PTH2" thru_hole oval
			(at 21.999956 2.350008 90)
			(size 1.524 2.6162)
			(drill oval 0.8128 1.905)
			(layers "*.Cu" "*.Mask")
			(remove_unused_layers no)
			(net "Net_1121")
			(clearance 0.1524)
			(thermal_gap 0.1524)
		)
		(pad "S1" smd rect
			(at -15.875 0.824992 90)
			(size 0.6604 2.0574)
			(layers "F.Cu" "F.Mask" "F.Paste")
			(net "GND")
		)
		(pad "S2" smd rect
			(at -14.605 0.824992 90)
			(size 0.6604 2.0574)
			(layers "F.Cu" "F.Mask" "F.Paste")
			(net "Net_1136")
		)
		(pad "S3" smd rect
			(at -13.335 0.824992 90)
			(size 0.6604 2.0574)
			(layers "F.Cu" "F.Mask" "F.Paste")
			(net "Net_1135")
		)
		(pad "S4" smd rect
			(at -12.065 0.824992 90)
			(size 0.6604 2.0574)
			(layers "F.Cu" "F.Mask" "F.Paste")
			(net "GND")
		)
		(pad "S5" smd rect
			(at -10.795 0.824992 90)
			(size 0.6604 2.0574)
			(layers "F.Cu" "F.Mask" "F.Paste")
			(net "Net_1134")
		)
		(pad "S6" smd rect
			(at -9.525 0.824992 90)
			(size 0.6604 2.0574)
			(layers "F.Cu" "F.Mask" "F.Paste")
			(net "Net_1133")
		)
		(pad "S7" smd rect
			(at -8.255 0.824992 90)
			(size 0.6604 2.0574)
			(layers "F.Cu" "F.Mask" "F.Paste")
			(net "GND")
		)
		(pad "S8" smd rect
			(at -7.480046 -1.949958 90)
			(size 0.508 2.0066)
			(layers "F.Cu" "F.Mask" "F.Paste")
			(net "GND")
		)
		(pad "S9" smd rect
			(at -6.679946 -1.949958 90)
			(size 0.508 2.0066)
			(layers "F.Cu" "F.Mask" "F.Paste")
			(net "Net_1131")
		)
		(pad "S10" smd rect
			(at -5.8801 -1.949958 90)
			(size 0.508 2.0066)
			(layers "F.Cu" "F.Mask" "F.Paste")
			(net "Net_1130")
		)
		(pad "S11" smd rect
			(at -5.08 -1.949958 90)
			(size 0.508 2.0066)
			(layers "F.Cu" "F.Mask" "F.Paste")
			(net "GND")
		)
		(pad "S12" smd rect
			(at -4.2799 -1.949958 90)
			(size 0.508 2.0066)
			(layers "F.Cu" "F.Mask" "F.Paste")
			(net "Net_1129")
		)
		(pad "S13" smd rect
			(at -3.480054 -1.949958 90)
			(size 0.508 2.0066)
			(layers "F.Cu" "F.Mask" "F.Paste")
			(net "Net_1124")
		)
		(pad "S14" smd rect
			(at -2.679954 -1.949958 90)
			(size 0.508 2.0066)
			(layers "F.Cu" "F.Mask" "F.Paste")
			(net "GND")
		)
		(pad "S15" smd rect
			(at -1.880108 -1.949958 90)
			(size 0.508 2.0066)
			(layers "F.Cu" "F.Mask" "F.Paste")
			(net "Net_1123")
		)
		(pad "S16" smd rect
			(at -1.080008 -1.949958 90)
			(size 0.508 2.0066)
			(layers "F.Cu" "F.Mask" "F.Paste")
			(net "GND")
		)
		(pad "S17" smd rect
			(at -0.279908 -1.949958 90)
			(size 0.508 2.0066)
			(layers "F.Cu" "F.Mask" "F.Paste")
			(net "PE_TX2_DR6_N")
		)
		(pad "S18" smd rect
			(at 0.519938 -1.949958 90)
			(size 0.508 2.0066)
			(layers "F.Cu" "F.Mask" "F.Paste")
			(net "PE_TX2_DR6_P")
		)
		(pad "S19" smd rect
			(at 1.320038 -1.949958 90)
			(size 0.508 2.0066)
			(layers "F.Cu" "F.Mask" "F.Paste")
			(net "GND")
		)
		(pad "S20" smd rect
			(at 2.119884 -1.949958 90)
			(size 0.508 2.0066)
			(layers "F.Cu" "F.Mask" "F.Paste")
			(net "PE_RX2_DR6_N")
		)
		(pad "S21" smd rect
			(at 2.919984 -1.949958 90)
			(size 0.508 2.0066)
			(layers "F.Cu" "F.Mask" "F.Paste")
			(net "PE_RX2_DR6_P")
		)
		(pad "S22" smd rect
			(at 3.720084 -1.949958 90)
			(size 0.508 2.0066)
			(layers "F.Cu" "F.Mask" "F.Paste")
			(net "GND")
		)
		(pad "S23" smd rect
			(at 4.51993 -1.949958 90)
			(size 0.508 2.0066)
			(layers "F.Cu" "F.Mask" "F.Paste")
			(net "PE_TX3_DR6_N")
		)
		(pad "S24" smd rect
			(at 5.32003 -1.949958 90)
			(size 0.508 2.0066)
			(layers "F.Cu" "F.Mask" "F.Paste")
			(net "PE_TX3_DR6_P")
		)
		(pad "S25" smd rect
			(at 6.119876 -1.949958 90)
			(size 0.508 2.0066)
			(layers "F.Cu" "F.Mask" "F.Paste")
			(net "GND")
		)
		(pad "S26" smd rect
			(at 6.919976 -1.949958 90)
			(size 0.508 2.0066)
			(layers "F.Cu" "F.Mask" "F.Paste")
			(net "PE_RX3_DR6_N")
		)
		(pad "S27" smd rect
			(at 7.720076 -1.949958 90)
			(size 0.508 2.0066)
			(layers "F.Cu" "F.Mask" "F.Paste")
			(net "PE_RX3_DR6_P")
		)
		(pad "S28" smd rect
			(at 8.519922 -1.949958 90)
			(size 0.508 2.0066)
			(layers "F.Cu" "F.Mask" "F.Paste")
			(net "GND")
		)
		(zone
			(layers "F.Cu" "B.Cu" "In1.Cu" "In2.Cu" "In3.Cu" "In4.Cu" "In5.Cu" "In6.Cu")
			(hatch none 0.5)
			(connect_pads
				(clearance 0)
			)
			(min_thickness 0.25)
			(keepout
				(tracks not_allowed)
				(vias allowed)
				(pads allowed)
				(copperpour not_allowed)
				(footprints allowed)
			)
			(placement
				(enabled no)
				(sheetname "")
			)
			(fill
				(thermal_gap 0.5)
				(thermal_bridge_width 0.5)
				(island_removal_mode 0)
			)
			(polygon
				(pts
					(arc
						(start 42.381932 -395.670024)
						(mid 39.918132 -395.670024)
						(end 42.381932 -395.670024)
					)
				)
			)
		)
		(zone
			(layers "F.Cu" "B.Cu" "In1.Cu" "In2.Cu" "In3.Cu" "In4.Cu" "In5.Cu" "In6.Cu")
			(hatch none 0.5)
			(connect_pads
				(clearance 0)
			)
			(min_thickness 0.25)
			(keepout
				(tracks not_allowed)
				(vias allowed)
				(pads allowed)
				(copperpour not_allowed)
				(footprints allowed)
			)
			(placement
				(enabled no)
				(sheetname "")
			)
			(fill
				(thermal_gap 0.5)
				(thermal_bridge_width 0.5)
				(island_removal_mode 0)
			)
			(polygon
				(pts
					(arc
						(start 42.381932 -357.6701)
						(mid 39.918132 -357.6701)
						(end 42.381932 -357.6701)
					)
				)
			)
		)
	)
	(footprint ""
		(layer "F.Cu")
		(at 36.6776 -109.8804 180)
		(property "Reference" "C395"
			(at 0 0 180)
			(layer "F.SilkS")
			(hide yes)
			(effects
				(font
					(size 1.27 1.27)
				)
			)
		)
		(property "Value" "SCD1U25V2KX-2-GP"
			(at 1.1811 -2.7051 180)
			(unlocked yes)
			(layer "F.Fab")
			(hide yes)
			(effects
				(font
					(size 1.016 1.016)
					(thickness 0.1524)
				)
			)
		)
		(property "Device Type" "C402H22"
			(at 1.1811 -4.2291 180)
			(unlocked yes)
			(layer "F.Fab")
			(hide yes)
			(effects
				(font
					(size 1.016 1.016)
					(thickness 0.1524)
				)
			)
		)
		(duplicate_pad_numbers_are_jumpers no)
		(fp_rect
			(start -0.4318 0.9525)
			(end 0.4318 -0.9525)
			(stroke
				(width 0)
				(type default)
			)
			(fill no)
			(layer "F.CrtYd")
		)
		(fp_rect
			(start -0.4318 0.9525)
			(end 0.4318 -0.9525)
			(stroke
				(width 0)
				(type default)
			)
			(fill no)
			(layer "F.Fab")
		)
		(pad "1" smd custom
			(at 0 -0.4445 180)
			(size 0.1524 0.1524)
			(layers "F.Cu" "F.Mask" "F.Paste")
			(net "P12V")
			(options
				(clearance outline)
				(anchor circle)
			)
			(primitives
				(gr_poly
					(pts
						(arc
							(start 0.3048 -0.2032)
							(mid 0.275042 -0.275042)
							(end 0.2032 -0.3048)
						)
						(arc
							(start -0.2032 -0.3048)
							(mid -0.275042 -0.275042)
							(end -0.3048 -0.2032)
						)
						(arc
							(start -0.3048 0.2032)
							(mid -0.275042 0.275042)
							(end -0.2032 0.3048)
						)
						(arc
							(start 0.2032 0.3048)
							(mid 0.275042 0.275042)
							(end 0.3048 0.2032)
						)
					)
					(width 0)
					(fill yes)
				)
			)
		)
		(pad "2" smd custom
			(at 0 0.4445 180)
			(size 0.1524 0.1524)
			(layers "F.Cu" "F.Mask" "F.Paste")
			(net "SW_SSD13_N")
			(options
				(clearance outline)
				(anchor circle)
			)
			(primitives
				(gr_poly
					(pts
						(arc
							(start 0.3048 -0.2032)
							(mid 0.275042 -0.275042)
							(end 0.2032 -0.3048)
						)
						(arc
							(start -0.2032 -0.3048)
							(mid -0.275042 -0.275042)
							(end -0.3048 -0.2032)
						)
						(arc
							(start -0.3048 0.2032)
							(mid -0.275042 0.275042)
							(end -0.2032 0.3048)
						)
						(arc
							(start 0.2032 0.3048)
							(mid 0.275042 0.275042)
							(end 0.3048 0.2032)
						)
					)
					(width 0)
					(fill yes)
				)
			)
		)
	)
	(footprint ""
		(layer "F.Cu")
		(at 29.845 -320.167 90)
		(property "Reference" "R412"
			(at 0 0 90)
			(layer "F.SilkS")
			(hide yes)
			(effects
				(font
					(size 1.27 1.27)
				)
			)
		)
		(property "Value" "0R2J-2-GP"
			(at 0.064008 -3.993896 90)
			(unlocked yes)
			(layer "F.Fab")
			(hide yes)
			(effects
				(font
					(size 1.016 1.016)
					(thickness 0.1524)
				)
			)
		)
		(property "Device Type" "R402H16"
			(at 0.064008 -5.517896 90)
			(unlocked yes)
			(layer "F.Fab")
			(hide yes)
			(effects
				(font
					(size 1.016 1.016)
					(thickness 0.1524)
				)
			)
		)
		(duplicate_pad_numbers_are_jumpers no)
		(fp_line
			(start 0.508 -0.9398)
			(end -0.508 -0.9398)
			(stroke
				(width 0.1524)
				(type default)
			)
			(layer "F.SilkS")
		)
		(fp_line
			(start -0.508 -0.9398)
			(end -0.508 0.9398)
			(stroke
				(width 0.1524)
				(type default)
			)
			(layer "F.SilkS")
		)
		(fp_rect
			(start -0.508 0.9398)
			(end 0.508 -0.9398)
			(stroke
				(width 0)
				(type default)
			)
			(fill no)
			(layer "F.CrtYd")
		)
		(fp_rect
			(start -0.508 0.9398)
			(end 0.508 -0.9398)
			(stroke
				(width 0)
				(type default)
			)
			(fill no)
			(layer "F.Fab")
		)
		(pad "1" smd custom
			(at 0 -0.4445 90)
			(size 0.1397 0.1397)
			(layers "F.Cu" "F.Mask" "F.Paste")
			(net "SDA_DR11_R")
			(options
				(clearance outline)
				(anchor circle)
			)
			(primitives
				(gr_poly
					(pts
						(arc
							(start -0.1778 -0.2794)
							(mid -0.249642 -0.249642)
							(end -0.2794 -0.1778)
						)
						(arc
							(start -0.2794 0.1778)
							(mid -0.249642 0.249642)
							(end -0.1778 0.2794)
						)
						(arc
							(start 0.1778 0.2794)
							(mid 0.249642 0.249642)
							(end 0.2794 0.1778)
						)
						(arc
							(start 0.2794 -0.1778)
							(mid 0.249642 -0.249642)
							(end 0.1778 -0.2794)
						)
					)
					(width 0)
					(fill yes)
				)
			)
		)
		(pad "2" smd custom
			(at 0 0.4445 90)
			(size 0.1397 0.1397)
			(layers "F.Cu" "F.Mask" "F.Paste")
			(net "SDA_DR11")
			(options
				(clearance outline)
				(anchor circle)
			)
			(primitives
				(gr_poly
					(pts
						(arc
							(start -0.1778 -0.2794)
							(mid -0.249642 -0.249642)
							(end -0.2794 -0.1778)
						)
						(arc
							(start -0.2794 0.1778)
							(mid -0.249642 0.249642)
							(end -0.1778 0.2794)
						)
						(arc
							(start 0.1778 0.2794)
							(mid 0.249642 0.249642)
							(end 0.2794 0.1778)
						)
						(arc
							(start 0.2794 -0.1778)
							(mid 0.249642 -0.249642)
							(end 0.1778 -0.2794)
						)
					)
					(width 0)
					(fill yes)
				)
			)
		)
	)
	(footprint ""
		(layer "F.Cu")
		(at 28.67025 -402.53285 -90)
		(property "Reference" "Q56"
			(at 0 0 270)
			(layer "F.SilkS")
			(hide yes)
			(effects
				(font
					(size 1.27 1.27)
				)
			)
		)
		(property "Value" "2N7002A-7-GP"
			(at 0.127 -8.9662 270)
			(unlocked yes)
			(layer "F.Fab")
			(hide yes)
			(effects
				(font
					(size 1.016 1.016)
					(thickness 0.1524)
				)
			)
		)
		(property "Device Type" "SOT23DGS2D4H48"
			(at 0.127 -10.4902 270)
			(unlocked yes)
			(layer "F.Fab")
			(hide yes)
			(effects
				(font
					(size 1.016 1.016)
					(thickness 0.1524)
				)
			)
		)
		(duplicate_pad_numbers_are_jumpers no)
		(fp_line
			(start -1.651 1.778)
			(end 1.651 1.778)
			(stroke
				(width 0.1524)
				(type default)
			)
			(layer "F.SilkS")
		)
		(fp_line
			(start 1.651 1.778)
			(end 1.651 -1.778)
			(stroke
				(width 0.1524)
				(type default)
			)
			(layer "F.SilkS")
		)
		(fp_line
			(start -1.651 -1.778)
			(end -1.651 1.778)
			(stroke
				(width 0.1524)
				(type default)
			)
			(layer "F.SilkS")
		)
		(fp_line
			(start 1.651 -1.778)
			(end -1.651 -1.778)
			(stroke
				(width 0.1524)
				(type default)
			)
			(layer "F.SilkS")
		)
		(fp_poly
			(pts
				(xy -1.778 1.8796) (xy -1.778 -1.8796) (xy 1.778 -1.8796) (xy 1.778 1.8796)
			)
			(stroke
				(width 0)
				(type default)
			)
			(fill no)
			(layer "F.CrtYd")
		)
		(fp_poly
			(pts
				(xy -1.778 1.8796) (xy -1.778 -1.8796) (xy 1.778 -1.8796) (xy 1.778 1.8796)
			)
			(stroke
				(width 0)
				(type default)
			)
			(fill no)
			(layer "F.Fab")
		)
		(pad "D" smd custom
			(at 0 -0.9525 270)
			(size 0.1905 0.1905)
			(layers "F.Cu" "F.Mask" "F.Paste")
			(net "P12V_MOST6_GATE_D")
			(options
				(clearance outline)
				(anchor circle)
			)
			(primitives
				(gr_poly
					(pts
						(arc
							(start -0.1778 0.5715)
							(mid -0.321484 0.511984)
							(end -0.381 0.3683)
						)
						(arc
							(start -0.381 -0.3683)
							(mid -0.321484 -0.511984)
							(end -0.1778 -0.5715)
						)
						(arc
							(start 0.1778 -0.5715)
							(mid 0.321484 -0.511984)
							(end 0.381 -0.3683)
						)
						(arc
							(start 0.381 0.3683)
							(mid 0.321484 0.511984)
							(end 0.1778 0.5715)
						)
					)
					(width 0)
					(fill yes)
				)
			)
		)
		(pad "G" smd custom
			(at -0.98425 0.9525 270)
			(size 0.1905 0.1905)
			(layers "F.Cu" "F.Mask" "F.Paste")
			(net "P12V_MOST6_GATE")
			(options
				(clearance outline)
				(anchor circle)
			)
			(primitives
				(gr_poly
					(pts
						(arc
							(start -0.1778 0.5715)
							(mid -0.321484 0.511984)
							(end -0.381 0.3683)
						)
						(arc
							(start -0.381 -0.3683)
							(mid -0.321484 -0.511984)
							(end -0.1778 -0.5715)
						)
						(arc
							(start 0.1778 -0.5715)
							(mid 0.321484 -0.511984)
							(end 0.381 -0.3683)
						)
						(arc
							(start 0.381 0.3683)
							(mid 0.321484 0.511984)
							(end 0.1778 0.5715)
						)
					)
					(width 0)
					(fill yes)
				)
			)
		)
		(pad "S" smd custom
			(at 0.98425 0.9525 270)
			(size 0.1905 0.1905)
			(layers "F.Cu" "F.Mask" "F.Paste")
			(net "GND")
			(options
				(clearance outline)
				(anchor circle)
			)
			(primitives
				(gr_poly
					(pts
						(arc
							(start -0.1778 0.5715)
							(mid -0.321484 0.511984)
							(end -0.381 0.3683)
						)
						(arc
							(start -0.381 -0.3683)
							(mid -0.321484 -0.511984)
							(end -0.1778 -0.5715)
						)
						(arc
							(start 0.1778 -0.5715)
							(mid 0.321484 -0.511984)
							(end 0.381 -0.3683)
						)
						(arc
							(start 0.381 0.3683)
							(mid 0.321484 0.511984)
							(end 0.1778 0.5715)
						)
					)
					(width 0)
					(fill yes)
				)
			)
		)
	)
	(footprint ""
		(layer "F.Cu")
		(at 212.725 -454.66)
		(property "Reference" "R323"
			(at 0 0 0)
			(layer "F.SilkS")
			(hide yes)
			(effects
				(font
					(size 1.27 1.27)
				)
			)
		)
		(property "Value" "4K7R2J-2-GP"
			(at 0.064008 -3.993896 0)
			(unlocked yes)
			(layer "F.Fab")
			(hide yes)
			(effects
				(font
					(size 1.016 1.016)
					(thickness 0.1524)
				)
			)
		)
		(property "Device Type" "R402H16"
			(at 0.064008 -5.517896 0)
			(unlocked yes)
			(layer "F.Fab")
			(hide yes)
			(effects
				(font
					(size 1.016 1.016)
					(thickness 0.1524)
				)
			)
		)
		(duplicate_pad_numbers_are_jumpers no)
		(fp_line
			(start -0.508 -0.9398)
			(end -0.508 0.9398)
			(stroke
				(width 0.1524)
				(type default)
			)
			(layer "F.SilkS")
		)
		(fp_line
			(start 0.508 -0.9398)
			(end -0.508 -0.9398)
			(stroke
				(width 0.1524)
				(type default)
			)
			(layer "F.SilkS")
		)
		(fp_rect
			(start -0.508 0.9398)
			(end 0.508 -0.9398)
			(stroke
				(width 0)
				(type default)
			)
			(fill no)
			(layer "F.CrtYd")
		)
		(fp_rect
			(start -0.508 0.9398)
			(end 0.508 -0.9398)
			(stroke
				(width 0)
				(type default)
			)
			(fill no)
			(layer "F.Fab")
		)
		(pad "1" smd custom
			(at 0 -0.4445)
			(size 0.1397 0.1397)
			(layers "F.Cu" "F.Mask" "F.Paste")
			(net "I2C_B_TMP2_A2")
			(options
				(clearance outline)
				(anchor circle)
			)
			(primitives
				(gr_poly
					(pts
						(arc
							(start -0.1778 -0.2794)
							(mid -0.249642 -0.249642)
							(end -0.2794 -0.1778)
						)
						(arc
							(start -0.2794 0.1778)
							(mid -0.249642 0.249642)
							(end -0.1778 0.2794)
						)
						(arc
							(start 0.1778 0.2794)
							(mid 0.249642 0.249642)
							(end 0.2794 0.1778)
						)
						(arc
							(start 0.2794 -0.1778)
							(mid 0.249642 -0.249642)
							(end 0.1778 -0.2794)
						)
					)
					(width 0)
					(fill yes)
				)
			)
		)
		(pad "2" smd custom
			(at 0 0.4445)
			(size 0.1397 0.1397)
			(layers "F.Cu" "F.Mask" "F.Paste")
			(net "GND")
			(options
				(clearance outline)
				(anchor circle)
			)
			(primitives
				(gr_poly
					(pts
						(arc
							(start -0.1778 -0.2794)
							(mid -0.249642 -0.249642)
							(end -0.2794 -0.1778)
						)
						(arc
							(start -0.2794 0.1778)
							(mid -0.249642 0.249642)
							(end -0.1778 0.2794)
						)
						(arc
							(start 0.1778 0.2794)
							(mid 0.249642 0.249642)
							(end 0.2794 0.1778)
						)
						(arc
							(start 0.2794 -0.1778)
							(mid 0.249642 -0.249642)
							(end 0.1778 -0.2794)
						)
					)
					(width 0)
					(fill yes)
				)
			)
		)
	)
	(footprint ""
		(layer "F.Cu")
		(at 195.386706 -498.222778)
		(property "Reference" "R9760"
			(at 0 0 0)
			(layer "F.SilkS")
			(hide yes)
			(effects
				(font
					(size 1.27 1.27)
				)
			)
		)
		(property "Value" "4K7R2J-2-GP"
			(at 0.064008 -3.993896 0)
			(unlocked yes)
			(layer "F.Fab")
			(hide yes)
			(effects
				(font
					(size 1.016 1.016)
					(thickness 0.1524)
				)
			)
		)
		(property "Device Type" "R402H16"
			(at 0.064008 -5.517896 0)
			(unlocked yes)
			(layer "F.Fab")
			(hide yes)
			(effects
				(font
					(size 1.016 1.016)
					(thickness 0.1524)
				)
			)
		)
		(duplicate_pad_numbers_are_jumpers no)
		(fp_line
			(start -0.508 -0.9398)
			(end -0.508 0.9398)
			(stroke
				(width 0.1524)
				(type default)
			)
			(layer "F.SilkS")
		)
		(fp_line
			(start 0.508 -0.9398)
			(end -0.508 -0.9398)
			(stroke
				(width 0.1524)
				(type default)
			)
			(layer "F.SilkS")
		)
		(fp_rect
			(start -0.508 0.9398)
			(end 0.508 -0.9398)
			(stroke
				(width 0)
				(type default)
			)
			(fill no)
			(layer "F.CrtYd")
		)
		(fp_rect
			(start -0.508 0.9398)
			(end 0.508 -0.9398)
			(stroke
				(width 0)
				(type default)
			)
			(fill no)
			(layer "F.Fab")
		)
		(pad "1" smd custom
			(at 0 -0.4445)
			(size 0.1397 0.1397)
			(layers "F.Cu" "F.Mask" "F.Paste")
			(net "SSD0_PWREN")
			(options
				(clearance outline)
				(anchor circle)
			)
			(primitives
				(gr_poly
					(pts
						(arc
							(start -0.1778 -0.2794)
							(mid -0.249642 -0.249642)
							(end -0.2794 -0.1778)
						)
						(arc
							(start -0.2794 0.1778)
							(mid -0.249642 0.249642)
							(end -0.1778 0.2794)
						)
						(arc
							(start 0.1778 0.2794)
							(mid 0.249642 0.249642)
							(end 0.2794 0.1778)
						)
						(arc
							(start 0.2794 -0.1778)
							(mid 0.249642 -0.249642)
							(end 0.1778 -0.2794)
						)
					)
					(width 0)
					(fill yes)
				)
			)
		)
		(pad "2" smd custom
			(at 0 0.4445)
			(size 0.1397 0.1397)
			(layers "F.Cu" "F.Mask" "F.Paste")
			(net "GND")
			(options
				(clearance outline)
				(anchor circle)
			)
			(primitives
				(gr_poly
					(pts
						(arc
							(start -0.1778 -0.2794)
							(mid -0.249642 -0.249642)
							(end -0.2794 -0.1778)
						)
						(arc
							(start -0.2794 0.1778)
							(mid -0.249642 0.249642)
							(end -0.1778 0.2794)
						)
						(arc
							(start 0.1778 0.2794)
							(mid 0.249642 0.249642)
							(end 0.2794 0.1778)
						)
						(arc
							(start 0.2794 -0.1778)
							(mid 0.249642 -0.249642)
							(end 0.1778 -0.2794)
						)
					)
					(width 0)
					(fill yes)
				)
			)
		)
	)
	(footprint ""
		(layer "F.Cu")
		(at 228.510592 -37.834062 180)
		(property "Reference" "SR1130"
			(at 0 0 180)
			(layer "F.SilkS")
			(hide yes)
			(effects
				(font
					(size 1.27 1.27)
				)
			)
		)
		(property "Value" "4K7R2J-2-GP"
			(at 0.064008 -3.993896 180)
			(unlocked yes)
			(layer "F.Fab")
			(hide yes)
			(effects
				(font
					(size 1.016 1.016)
					(thickness 0.1524)
				)
			)
		)
		(property "Device Type" "R402H16"
			(at 0.064008 -5.517896 180)
			(unlocked yes)
			(layer "F.Fab")
			(hide yes)
			(effects
				(font
					(size 1.016 1.016)
					(thickness 0.1524)
				)
			)
		)
		(duplicate_pad_numbers_are_jumpers no)
		(fp_line
			(start 0.508 -0.9398)
			(end -0.508 -0.9398)
			(stroke
				(width 0.1524)
				(type default)
			)
			(layer "F.SilkS")
		)
		(fp_line
			(start -0.508 -0.9398)
			(end -0.508 0.9398)
			(stroke
				(width 0.1524)
				(type default)
			)
			(layer "F.SilkS")
		)
		(fp_rect
			(start -0.508 0.9398)
			(end 0.508 -0.9398)
			(stroke
				(width 0)
				(type default)
			)
			(fill no)
			(layer "F.CrtYd")
		)
		(fp_rect
			(start -0.508 0.9398)
			(end 0.508 -0.9398)
			(stroke
				(width 0)
				(type default)
			)
			(fill no)
			(layer "F.Fab")
		)
		(pad "1" smd custom
			(at 0 -0.4445 180)
			(size 0.1397 0.1397)
			(layers "F.Cu" "F.Mask" "F.Paste")
			(net "P3V3")
			(options
				(clearance outline)
				(anchor circle)
			)
			(primitives
				(gr_poly
					(pts
						(arc
							(start -0.1778 -0.2794)
							(mid -0.249642 -0.249642)
							(end -0.2794 -0.1778)
						)
						(arc
							(start -0.2794 0.1778)
							(mid -0.249642 0.249642)
							(end -0.1778 0.2794)
						)
						(arc
							(start 0.1778 0.2794)
							(mid 0.249642 0.249642)
							(end 0.2794 0.1778)
						)
						(arc
							(start 0.2794 -0.1778)
							(mid 0.249642 -0.249642)
							(end 0.1778 -0.2794)
						)
					)
					(width 0)
					(fill yes)
				)
			)
		)
		(pad "2" smd custom
			(at 0 0.4445 180)
			(size 0.1397 0.1397)
			(layers "F.Cu" "F.Mask" "F.Paste")
			(net "SSD_ACT_DR4")
			(options
				(clearance outline)
				(anchor circle)
			)
			(primitives
				(gr_poly
					(pts
						(arc
							(start -0.1778 -0.2794)
							(mid -0.249642 -0.249642)
							(end -0.2794 -0.1778)
						)
						(arc
							(start -0.2794 0.1778)
							(mid -0.249642 0.249642)
							(end -0.1778 0.2794)
						)
						(arc
							(start 0.1778 0.2794)
							(mid 0.249642 0.249642)
							(end 0.2794 0.1778)
						)
						(arc
							(start 0.2794 -0.1778)
							(mid 0.249642 -0.249642)
							(end 0.1778 -0.2794)
						)
					)
					(width 0)
					(fill yes)
				)
			)
		)
	)
	(footprint ""
		(layer "F.Cu")
		(at 96.774 -113.665 -90)
		(property "Reference" "C9370"
			(at 0 0 270)
			(layer "F.SilkS")
			(hide yes)
			(effects
				(font
					(size 1.27 1.27)
				)
			)
		)
		(property "Value" "SC1KP50V2KX-1GP"
			(at 1.1811 -2.7051 270)
			(unlocked yes)
			(layer "F.Fab")
			(hide yes)
			(effects
				(font
					(size 1.016 1.016)
					(thickness 0.1524)
				)
			)
		)
		(property "Device Type" "C402H22"
			(at 1.1811 -4.2291 270)
			(unlocked yes)
			(layer "F.Fab")
			(hide yes)
			(effects
				(font
					(size 1.016 1.016)
					(thickness 0.1524)
				)
			)
		)
		(duplicate_pad_numbers_are_jumpers no)
		(fp_rect
			(start -0.4318 0.9525)
			(end 0.4318 -0.9525)
			(stroke
				(width 0)
				(type default)
			)
			(fill no)
			(layer "F.CrtYd")
		)
		(fp_rect
			(start -0.4318 0.9525)
			(end 0.4318 -0.9525)
			(stroke
				(width 0)
				(type default)
			)
			(fill no)
			(layer "F.Fab")
		)
		(pad "1" smd custom
			(at 0 -0.4445 270)
			(size 0.1524 0.1524)
			(layers "F.Cu" "F.Mask" "F.Paste")
			(net "SSD8_CLK0_OE_R_N")
			(options
				(clearance outline)
				(anchor circle)
			)
			(primitives
				(gr_poly
					(pts
						(arc
							(start 0.3048 -0.2032)
							(mid 0.275042 -0.275042)
							(end 0.2032 -0.3048)
						)
						(arc
							(start -0.2032 -0.3048)
							(mid -0.275042 -0.275042)
							(end -0.3048 -0.2032)
						)
						(arc
							(start -0.3048 0.2032)
							(mid -0.275042 0.275042)
							(end -0.2032 0.3048)
						)
						(arc
							(start 0.2032 0.3048)
							(mid 0.275042 0.275042)
							(end 0.3048 0.2032)
						)
					)
					(width 0)
					(fill yes)
				)
			)
		)
		(pad "2" smd custom
			(at 0 0.4445 270)
			(size 0.1524 0.1524)
			(layers "F.Cu" "F.Mask" "F.Paste")
			(net "GND")
			(options
				(clearance outline)
				(anchor circle)
			)
			(primitives
				(gr_poly
					(pts
						(arc
							(start 0.3048 -0.2032)
							(mid 0.275042 -0.275042)
							(end 0.2032 -0.3048)
						)
						(arc
							(start -0.2032 -0.3048)
							(mid -0.275042 -0.275042)
							(end -0.3048 -0.2032)
						)
						(arc
							(start -0.3048 0.2032)
							(mid -0.275042 0.275042)
							(end -0.2032 0.3048)
						)
						(arc
							(start 0.2032 0.3048)
							(mid 0.275042 0.275042)
							(end 0.3048 0.2032)
						)
					)
					(width 0)
					(fill yes)
				)
			)
		)
	)
	(footprint ""
		(layer "F.Cu")
		(at 31.8262 -112.4712 180)
		(property "Reference" "SR1117"
			(at 0 0 180)
			(layer "F.SilkS")
			(hide yes)
			(effects
				(font
					(size 1.27 1.27)
				)
			)
		)
		(property "Value" "4K7R2F-GP"
			(at 0.064008 -3.993896 180)
			(unlocked yes)
			(layer "F.Fab")
			(hide yes)
			(effects
				(font
					(size 1.016 1.016)
					(thickness 0.1524)
				)
			)
		)
		(property "Device Type" "R402H16"
			(at 0.064008 -5.517896 180)
			(unlocked yes)
			(layer "F.Fab")
			(hide yes)
			(effects
				(font
					(size 1.016 1.016)
					(thickness 0.1524)
				)
			)
		)
		(duplicate_pad_numbers_are_jumpers no)
		(fp_line
			(start 0.508 -0.9398)
			(end -0.508 -0.9398)
			(stroke
				(width 0.1524)
				(type default)
			)
			(layer "F.SilkS")
		)
		(fp_line
			(start -0.508 -0.9398)
			(end -0.508 0.9398)
			(stroke
				(width 0.1524)
				(type default)
			)
			(layer "F.SilkS")
		)
		(fp_rect
			(start -0.508 0.9398)
			(end 0.508 -0.9398)
			(stroke
				(width 0)
				(type default)
			)
			(fill no)
			(layer "F.CrtYd")
		)
		(fp_rect
			(start -0.508 0.9398)
			(end 0.508 -0.9398)
			(stroke
				(width 0)
				(type default)
			)
			(fill no)
			(layer "F.Fab")
		)
		(pad "1" smd custom
			(at 0 -0.4445 180)
			(size 0.1397 0.1397)
			(layers "F.Cu" "F.Mask" "F.Paste")
			(net "P3V3")
			(options
				(clearance outline)
				(anchor circle)
			)
			(primitives
				(gr_poly
					(pts
						(arc
							(start -0.1778 -0.2794)
							(mid -0.249642 -0.249642)
							(end -0.2794 -0.1778)
						)
						(arc
							(start -0.2794 0.1778)
							(mid -0.249642 0.249642)
							(end -0.1778 0.2794)
						)
						(arc
							(start 0.1778 0.2794)
							(mid 0.249642 0.249642)
							(end 0.2794 0.1778)
						)
						(arc
							(start 0.2794 -0.1778)
							(mid 0.249642 -0.249642)
							(end 0.1778 -0.2794)
						)
					)
					(width 0)
					(fill yes)
				)
			)
		)
		(pad "2" smd custom
			(at 0 0.4445 180)
			(size 0.1397 0.1397)
			(layers "F.Cu" "F.Mask" "F.Paste")
			(net "DUALPORTEN#13")
			(options
				(clearance outline)
				(anchor circle)
			)
			(primitives
				(gr_poly
					(pts
						(arc
							(start -0.1778 -0.2794)
							(mid -0.249642 -0.249642)
							(end -0.2794 -0.1778)
						)
						(arc
							(start -0.2794 0.1778)
							(mid -0.249642 0.249642)
							(end -0.1778 0.2794)
						)
						(arc
							(start 0.1778 0.2794)
							(mid 0.249642 0.249642)
							(end 0.2794 0.1778)
						)
						(arc
							(start 0.2794 -0.1778)
							(mid 0.249642 -0.249642)
							(end 0.1778 -0.2794)
						)
					)
					(width 0)
					(fill yes)
				)
			)
		)
	)
	(footprint ""
		(layer "F.Cu")
		(at 51.181 -14.859 180)
		(property "Reference" "R582"
			(at 0 0 180)
			(layer "F.SilkS")
			(hide yes)
			(effects
				(font
					(size 1.27 1.27)
				)
			)
		)
		(property "Value" "200KR2F-L-GP"
			(at 0.064008 -3.993896 180)
			(unlocked yes)
			(layer "F.Fab")
			(hide yes)
			(effects
				(font
					(size 1.016 1.016)
					(thickness 0.1524)
				)
			)
		)
		(property "Device Type" "R402H16"
			(at 0.064008 -5.517896 180)
			(unlocked yes)
			(layer "F.Fab")
			(hide yes)
			(effects
				(font
					(size 1.016 1.016)
					(thickness 0.1524)
				)
			)
		)
		(duplicate_pad_numbers_are_jumpers no)
		(fp_line
			(start 0.508 -0.9398)
			(end -0.508 -0.9398)
			(stroke
				(width 0.1524)
				(type default)
			)
			(layer "F.SilkS")
		)
		(fp_line
			(start -0.508 -0.9398)
			(end -0.508 0.9398)
			(stroke
				(width 0.1524)
				(type default)
			)
			(layer "F.SilkS")
		)
		(fp_rect
			(start -0.508 0.9398)
			(end 0.508 -0.9398)
			(stroke
				(width 0)
				(type default)
			)
			(fill no)
			(layer "F.CrtYd")
		)
		(fp_rect
			(start -0.508 0.9398)
			(end 0.508 -0.9398)
			(stroke
				(width 0)
				(type default)
			)
			(fill no)
			(layer "F.Fab")
		)
		(pad "1" smd custom
			(at 0 -0.4445 180)
			(size 0.1397 0.1397)
			(layers "F.Cu" "F.Mask" "F.Paste")
			(net "SW_SSD14_R")
			(options
				(clearance outline)
				(anchor circle)
			)
			(primitives
				(gr_poly
					(pts
						(arc
							(start -0.1778 -0.2794)
							(mid -0.249642 -0.249642)
							(end -0.2794 -0.1778)
						)
						(arc
							(start -0.2794 0.1778)
							(mid -0.249642 0.249642)
							(end -0.1778 0.2794)
						)
						(arc
							(start 0.1778 0.2794)
							(mid 0.249642 0.249642)
							(end 0.2794 0.1778)
						)
						(arc
							(start 0.2794 -0.1778)
							(mid 0.249642 -0.249642)
							(end 0.1778 -0.2794)
						)
					)
					(width 0)
					(fill yes)
				)
			)
		)
		(pad "2" smd custom
			(at 0 0.4445 180)
			(size 0.1397 0.1397)
			(layers "F.Cu" "F.Mask" "F.Paste")
			(net "SW_SSD14_N")
			(options
				(clearance outline)
				(anchor circle)
			)
			(primitives
				(gr_poly
					(pts
						(arc
							(start -0.1778 -0.2794)
							(mid -0.249642 -0.249642)
							(end -0.2794 -0.1778)
						)
						(arc
							(start -0.2794 0.1778)
							(mid -0.249642 0.249642)
							(end -0.1778 0.2794)
						)
						(arc
							(start 0.1778 0.2794)
							(mid 0.249642 0.249642)
							(end 0.2794 0.1778)
						)
						(arc
							(start 0.2794 -0.1778)
							(mid 0.249642 -0.249642)
							(end 0.1778 -0.2794)
						)
					)
					(width 0)
					(fill yes)
				)
			)
		)
	)
	(footprint ""
		(layer "F.Cu")
		(at 70.739 -151.638 90)
		(property "Reference" "SR970"
			(at 0 0 90)
			(layer "F.SilkS")
			(hide yes)
			(effects
				(font
					(size 1.27 1.27)
				)
			)
		)
		(property "Value" "2KR2F-3-GP"
			(at 0.064008 -3.993896 90)
			(unlocked yes)
			(layer "F.Fab")
			(hide yes)
			(effects
				(font
					(size 1.016 1.016)
					(thickness 0.1524)
				)
			)
		)
		(property "Device Type" "R402H16"
			(at 0.064008 -5.517896 90)
			(unlocked yes)
			(layer "F.Fab")
			(hide yes)
			(effects
				(font
					(size 1.016 1.016)
					(thickness 0.1524)
				)
			)
		)
		(duplicate_pad_numbers_are_jumpers no)
		(fp_line
			(start 0.508 -0.9398)
			(end -0.508 -0.9398)
			(stroke
				(width 0.1524)
				(type default)
			)
			(layer "F.SilkS")
		)
		(fp_line
			(start -0.508 -0.9398)
			(end -0.508 0.9398)
			(stroke
				(width 0.1524)
				(type default)
			)
			(layer "F.SilkS")
		)
		(fp_rect
			(start -0.508 0.9398)
			(end 0.508 -0.9398)
			(stroke
				(width 0)
				(type default)
			)
			(fill no)
			(layer "F.CrtYd")
		)
		(fp_rect
			(start -0.508 0.9398)
			(end 0.508 -0.9398)
			(stroke
				(width 0)
				(type default)
			)
			(fill no)
			(layer "F.Fab")
		)
		(pad "1" smd custom
			(at 0 -0.4445 90)
			(size 0.1397 0.1397)
			(layers "F.Cu" "F.Mask" "F.Paste")
			(net "P3V3")
			(options
				(clearance outline)
				(anchor circle)
			)
			(primitives
				(gr_poly
					(pts
						(arc
							(start -0.1778 -0.2794)
							(mid -0.249642 -0.249642)
							(end -0.2794 -0.1778)
						)
						(arc
							(start -0.2794 0.1778)
							(mid -0.249642 0.249642)
							(end -0.1778 0.2794)
						)
						(arc
							(start 0.1778 0.2794)
							(mid 0.249642 0.249642)
							(end 0.2794 0.1778)
						)
						(arc
							(start 0.2794 -0.1778)
							(mid 0.249642 -0.249642)
							(end 0.1778 -0.2794)
						)
					)
					(width 0)
					(fill yes)
				)
			)
		)
		(pad "2" smd custom
			(at 0 0.4445 90)
			(size 0.1397 0.1397)
			(layers "F.Cu" "F.Mask" "F.Paste")
			(net "SDA_DR8")
			(options
				(clearance outline)
				(anchor circle)
			)
			(primitives
				(gr_poly
					(pts
						(arc
							(start -0.1778 -0.2794)
							(mid -0.249642 -0.249642)
							(end -0.2794 -0.1778)
						)
						(arc
							(start -0.2794 0.1778)
							(mid -0.249642 0.249642)
							(end -0.1778 0.2794)
						)
						(arc
							(start 0.1778 0.2794)
							(mid 0.249642 0.249642)
							(end 0.2794 0.1778)
						)
						(arc
							(start 0.2794 -0.1778)
							(mid 0.249642 -0.249642)
							(end 0.1778 -0.2794)
						)
					)
					(width 0)
					(fill yes)
				)
			)
		)
	)
	(footprint ""
		(layer "F.Cu")
		(at 227.4316 -451.3326 90)
		(property "Reference" "R9928"
			(at 0 0 90)
			(layer "F.SilkS")
			(hide yes)
			(effects
				(font
					(size 1.27 1.27)
				)
			)
		)
		(property "Value" "4K7R2J-2-GP"
			(at 0.064008 -3.993896 90)
			(unlocked yes)
			(layer "F.Fab")
			(hide yes)
			(effects
				(font
					(size 1.016 1.016)
					(thickness 0.1524)
				)
			)
		)
		(property "Device Type" "R402H16"
			(at 0.064008 -5.517896 90)
			(unlocked yes)
			(layer "F.Fab")
			(hide yes)
			(effects
				(font
					(size 1.016 1.016)
					(thickness 0.1524)
				)
			)
		)
		(duplicate_pad_numbers_are_jumpers no)
		(fp_line
			(start 0.508 -0.9398)
			(end -0.508 -0.9398)
			(stroke
				(width 0.1524)
				(type default)
			)
			(layer "F.SilkS")
		)
		(fp_line
			(start -0.508 -0.9398)
			(end -0.508 0.9398)
			(stroke
				(width 0.1524)
				(type default)
			)
			(layer "F.SilkS")
		)
		(fp_rect
			(start -0.508 0.9398)
			(end 0.508 -0.9398)
			(stroke
				(width 0)
				(type default)
			)
			(fill no)
			(layer "F.CrtYd")
		)
		(fp_rect
			(start -0.508 0.9398)
			(end 0.508 -0.9398)
			(stroke
				(width 0)
				(type default)
			)
			(fill no)
			(layer "F.Fab")
		)
		(pad "1" smd custom
			(at 0 -0.4445 90)
			(size 0.1397 0.1397)
			(layers "F.Cu" "F.Mask" "F.Paste")
			(net "P3V3")
			(options
				(clearance outline)
				(anchor circle)
			)
			(primitives
				(gr_poly
					(pts
						(arc
							(start -0.1778 -0.2794)
							(mid -0.249642 -0.249642)
							(end -0.2794 -0.1778)
						)
						(arc
							(start -0.2794 0.1778)
							(mid -0.249642 0.249642)
							(end -0.1778 0.2794)
						)
						(arc
							(start 0.1778 0.2794)
							(mid 0.249642 0.249642)
							(end 0.2794 0.1778)
						)
						(arc
							(start 0.2794 -0.1778)
							(mid 0.249642 -0.249642)
							(end 0.1778 -0.2794)
						)
					)
					(width 0)
					(fill yes)
				)
			)
		)
		(pad "2" smd custom
			(at 0 0.4445 90)
			(size 0.1397 0.1397)
			(layers "F.Cu" "F.Mask" "F.Paste")
			(net "SSD_ACT_DR0_MOS_N")
			(options
				(clearance outline)
				(anchor circle)
			)
			(primitives
				(gr_poly
					(pts
						(arc
							(start -0.1778 -0.2794)
							(mid -0.249642 -0.249642)
							(end -0.2794 -0.1778)
						)
						(arc
							(start -0.2794 0.1778)
							(mid -0.249642 0.249642)
							(end -0.1778 0.2794)
						)
						(arc
							(start 0.1778 0.2794)
							(mid 0.249642 0.249642)
							(end 0.2794 0.1778)
						)
						(arc
							(start 0.2794 -0.1778)
							(mid 0.249642 -0.249642)
							(end 0.1778 -0.2794)
						)
					)
					(width 0)
					(fill yes)
				)
			)
		)
	)
	(footprint ""
		(layer "F.Cu")
		(at 83.185 -154.686 90)
		(property "Reference" "PR9059"
			(at 0 0 90)
			(layer "F.SilkS")
			(hide yes)
			(effects
				(font
					(size 1.27 1.27)
				)
			)
		)
		(property "Value" "0R2J-2-GP"
			(at 0.064008 -3.993896 90)
			(unlocked yes)
			(layer "F.Fab")
			(hide yes)
			(effects
				(font
					(size 1.016 1.016)
					(thickness 0.1524)
				)
			)
		)
		(property "Device Type" "R402H16"
			(at 0.064008 -5.517896 90)
			(unlocked yes)
			(layer "F.Fab")
			(hide yes)
			(effects
				(font
					(size 1.016 1.016)
					(thickness 0.1524)
				)
			)
		)
		(duplicate_pad_numbers_are_jumpers no)
		(fp_line
			(start 0.508 -0.9398)
			(end -0.508 -0.9398)
			(stroke
				(width 0.1524)
				(type default)
			)
			(layer "F.SilkS")
		)
		(fp_line
			(start -0.508 -0.9398)
			(end -0.508 0.9398)
			(stroke
				(width 0.1524)
				(type default)
			)
			(layer "F.SilkS")
		)
		(fp_rect
			(start -0.508 0.9398)
			(end 0.508 -0.9398)
			(stroke
				(width 0)
				(type default)
			)
			(fill no)
			(layer "F.CrtYd")
		)
		(fp_rect
			(start -0.508 0.9398)
			(end 0.508 -0.9398)
			(stroke
				(width 0)
				(type default)
			)
			(fill no)
			(layer "F.Fab")
		)
		(pad "1" smd custom
			(at 0 -0.4445 90)
			(size 0.1397 0.1397)
			(layers "F.Cu" "F.Mask" "F.Paste")
			(net "I2C_MUX_RESET_PEB")
			(options
				(clearance outline)
				(anchor circle)
			)
			(primitives
				(gr_poly
					(pts
						(arc
							(start -0.1778 -0.2794)
							(mid -0.249642 -0.249642)
							(end -0.2794 -0.1778)
						)
						(arc
							(start -0.2794 0.1778)
							(mid -0.249642 0.249642)
							(end -0.1778 0.2794)
						)
						(arc
							(start 0.1778 0.2794)
							(mid 0.249642 0.249642)
							(end 0.2794 0.1778)
						)
						(arc
							(start 0.2794 -0.1778)
							(mid 0.249642 -0.249642)
							(end 0.1778 -0.2794)
						)
					)
					(width 0)
					(fill yes)
				)
			)
		)
		(pad "2" smd custom
			(at 0 0.4445 90)
			(size 0.1397 0.1397)
			(layers "F.Cu" "F.Mask" "F.Paste")
			(net "I2C_MUX_RESET")
			(options
				(clearance outline)
				(anchor circle)
			)
			(primitives
				(gr_poly
					(pts
						(arc
							(start -0.1778 -0.2794)
							(mid -0.249642 -0.249642)
							(end -0.2794 -0.1778)
						)
						(arc
							(start -0.2794 0.1778)
							(mid -0.249642 0.249642)
							(end -0.1778 0.2794)
						)
						(arc
							(start 0.1778 0.2794)
							(mid 0.249642 0.249642)
							(end 0.2794 0.1778)
						)
						(arc
							(start 0.2794 -0.1778)
							(mid 0.249642 -0.249642)
							(end 0.1778 -0.2794)
						)
					)
					(width 0)
					(fill yes)
				)
			)
		)
	)
	(footprint ""
		(layer "F.Cu")
		(at 49.276 -42.418 -90)
		(property "Reference" "R9493"
			(at 0 0 270)
			(layer "F.SilkS")
			(hide yes)
			(effects
				(font
					(size 1.27 1.27)
				)
			)
		)
		(property "Value" "330R2F-GP"
			(at 0.064008 -3.993896 270)
			(unlocked yes)
			(layer "F.Fab")
			(hide yes)
			(effects
				(font
					(size 1.016 1.016)
					(thickness 0.1524)
				)
			)
		)
		(property "Device Type" "R402H16"
			(at 0.064008 -5.517896 270)
			(unlocked yes)
			(layer "F.Fab")
			(hide yes)
			(effects
				(font
					(size 1.016 1.016)
					(thickness 0.1524)
				)
			)
		)
		(duplicate_pad_numbers_are_jumpers no)
		(fp_line
			(start -0.508 -0.9398)
			(end -0.508 0.9398)
			(stroke
				(width 0.1524)
				(type default)
			)
			(layer "F.SilkS")
		)
		(fp_line
			(start 0.508 -0.9398)
			(end -0.508 -0.9398)
			(stroke
				(width 0.1524)
				(type default)
			)
			(layer "F.SilkS")
		)
		(fp_rect
			(start -0.508 0.9398)
			(end 0.508 -0.9398)
			(stroke
				(width 0)
				(type default)
			)
			(fill no)
			(layer "F.CrtYd")
		)
		(fp_rect
			(start -0.508 0.9398)
			(end 0.508 -0.9398)
			(stroke
				(width 0)
				(type default)
			)
			(fill no)
			(layer "F.Fab")
		)
		(pad "1" smd custom
			(at 0 -0.4445 270)
			(size 0.1397 0.1397)
			(layers "F.Cu" "F.Mask" "F.Paste")
			(net "P3V3")
			(options
				(clearance outline)
				(anchor circle)
			)
			(primitives
				(gr_poly
					(pts
						(arc
							(start -0.1778 -0.2794)
							(mid -0.249642 -0.249642)
							(end -0.2794 -0.1778)
						)
						(arc
							(start -0.2794 0.1778)
							(mid -0.249642 0.249642)
							(end -0.1778 0.2794)
						)
						(arc
							(start 0.1778 0.2794)
							(mid 0.249642 0.249642)
							(end 0.2794 0.1778)
						)
						(arc
							(start 0.2794 -0.1778)
							(mid 0.249642 -0.249642)
							(end 0.1778 -0.2794)
						)
					)
					(width 0)
					(fill yes)
				)
			)
		)
		(pad "2" smd custom
			(at 0 0.4445 270)
			(size 0.1397 0.1397)
			(layers "F.Cu" "F.Mask" "F.Paste")
			(net "DRV_ATTN_9")
			(options
				(clearance outline)
				(anchor circle)
			)
			(primitives
				(gr_poly
					(pts
						(arc
							(start -0.1778 -0.2794)
							(mid -0.249642 -0.249642)
							(end -0.2794 -0.1778)
						)
						(arc
							(start -0.2794 0.1778)
							(mid -0.249642 0.249642)
							(end -0.1778 0.2794)
						)
						(arc
							(start 0.1778 0.2794)
							(mid 0.249642 0.249642)
							(end 0.2794 0.1778)
						)
						(arc
							(start 0.2794 -0.1778)
							(mid 0.249642 -0.249642)
							(end 0.1778 -0.2794)
						)
					)
					(width 0)
					(fill yes)
				)
			)
		)
	)
	(footprint ""
		(layer "F.Cu")
		(at 36.576 -165.354 180)
		(property "Reference" "PC1219"
			(at 0 0 180)
			(layer "F.SilkS")
			(hide yes)
			(effects
				(font
					(size 1.27 1.27)
				)
			)
		)
		(property "Value" "SCD1U25V3KX-GP"
			(at 0 -2.8194 180)
			(unlocked yes)
			(layer "F.Fab")
			(hide yes)
			(effects
				(font
					(size 1.016 1.016)
					(thickness 0.1524)
				)
			)
		)
		(property "Device Type" "C603H36"
			(at 0 -4.3434 180)
			(unlocked yes)
			(layer "F.Fab")
			(hide yes)
			(effects
				(font
					(size 1.016 1.016)
					(thickness 0.1524)
				)
			)
		)
		(duplicate_pad_numbers_are_jumpers no)
		(fp_line
			(start 0.508 0)
			(end -0.508 0)
			(stroke
				(width 0.2032)
				(type default)
			)
			(layer "F.SilkS")
		)
		(fp_rect
			(start -0.5842 1.3335)
			(end 0.5842 -1.3335)
			(stroke
				(width 0)
				(type default)
			)
			(fill no)
			(layer "F.CrtYd")
		)
		(fp_rect
			(start -0.5842 1.3335)
			(end 0.5842 -1.3335)
			(stroke
				(width 0)
				(type default)
			)
			(fill no)
			(layer "F.Fab")
		)
		(pad "1" smd custom
			(at 0 -0.762 180)
			(size 0.2159 0.2159)
			(layers "F.Cu" "F.Mask" "F.Paste")
			(net "P3V3")
			(options
				(clearance outline)
				(anchor circle)
			)
			(primitives
				(gr_poly
					(pts
						(arc
							(start -0.3302 -0.4318)
							(mid -0.402042 -0.402042)
							(end -0.4318 -0.3302)
						)
						(arc
							(start -0.4318 0.3302)
							(mid -0.402042 0.402042)
							(end -0.3302 0.4318)
						)
						(arc
							(start 0.3302 0.4318)
							(mid 0.402042 0.402042)
							(end 0.4318 0.3302)
						)
						(arc
							(start 0.4318 -0.3302)
							(mid 0.402042 -0.402042)
							(end 0.3302 -0.4318)
						)
					)
					(width 0)
					(fill yes)
				)
			)
		)
		(pad "2" smd custom
			(at 0 0.762 180)
			(size 0.2159 0.2159)
			(layers "F.Cu" "F.Mask" "F.Paste")
			(net "GND")
			(options
				(clearance outline)
				(anchor circle)
			)
			(primitives
				(gr_poly
					(pts
						(arc
							(start -0.3302 -0.4318)
							(mid -0.402042 -0.402042)
							(end -0.4318 -0.3302)
						)
						(arc
							(start -0.4318 0.3302)
							(mid -0.402042 0.402042)
							(end -0.3302 0.4318)
						)
						(arc
							(start 0.3302 0.4318)
							(mid 0.402042 0.402042)
							(end 0.4318 0.3302)
						)
						(arc
							(start 0.4318 -0.3302)
							(mid 0.402042 -0.402042)
							(end 0.3302 -0.4318)
						)
					)
					(width 0)
					(fill yes)
				)
			)
		)
	)
	(footprint ""
		(layer "F.Cu")
		(at 215.7984 -494.0808 90)
		(property "Reference" "SR1091"
			(at 0 0 90)
			(layer "F.SilkS")
			(hide yes)
			(effects
				(font
					(size 1.27 1.27)
				)
			)
		)
		(property "Value" "4K7R2F-GP"
			(at 0.064008 -3.993896 90)
			(unlocked yes)
			(layer "F.Fab")
			(hide yes)
			(effects
				(font
					(size 1.016 1.016)
					(thickness 0.1524)
				)
			)
		)
		(property "Device Type" "R402H16"
			(at 0.064008 -5.517896 90)
			(unlocked yes)
			(layer "F.Fab")
			(hide yes)
			(effects
				(font
					(size 1.016 1.016)
					(thickness 0.1524)
				)
			)
		)
		(duplicate_pad_numbers_are_jumpers no)
		(fp_line
			(start 0.508 -0.9398)
			(end -0.508 -0.9398)
			(stroke
				(width 0.1524)
				(type default)
			)
			(layer "F.SilkS")
		)
		(fp_line
			(start -0.508 -0.9398)
			(end -0.508 0.9398)
			(stroke
				(width 0.1524)
				(type default)
			)
			(layer "F.SilkS")
		)
		(fp_rect
			(start -0.508 0.9398)
			(end 0.508 -0.9398)
			(stroke
				(width 0)
				(type default)
			)
			(fill no)
			(layer "F.CrtYd")
		)
		(fp_rect
			(start -0.508 0.9398)
			(end 0.508 -0.9398)
			(stroke
				(width 0)
				(type default)
			)
			(fill no)
			(layer "F.Fab")
		)
		(pad "1" smd custom
			(at 0 -0.4445 90)
			(size 0.1397 0.1397)
			(layers "F.Cu" "F.Mask" "F.Paste")
			(net "P3V3")
			(options
				(clearance outline)
				(anchor circle)
			)
			(primitives
				(gr_poly
					(pts
						(arc
							(start -0.1778 -0.2794)
							(mid -0.249642 -0.249642)
							(end -0.2794 -0.1778)
						)
						(arc
							(start -0.2794 0.1778)
							(mid -0.249642 0.249642)
							(end -0.1778 0.2794)
						)
						(arc
							(start 0.1778 0.2794)
							(mid 0.249642 0.249642)
							(end 0.2794 0.1778)
						)
						(arc
							(start 0.2794 -0.1778)
							(mid 0.249642 -0.249642)
							(end 0.1778 -0.2794)
						)
					)
					(width 0)
					(fill yes)
				)
			)
		)
		(pad "2" smd custom
			(at 0 0.4445 90)
			(size 0.1397 0.1397)
			(layers "F.Cu" "F.Mask" "F.Paste")
			(net "DUALPORTEN#0")
			(options
				(clearance outline)
				(anchor circle)
			)
			(primitives
				(gr_poly
					(pts
						(arc
							(start -0.1778 -0.2794)
							(mid -0.249642 -0.249642)
							(end -0.2794 -0.1778)
						)
						(arc
							(start -0.2794 0.1778)
							(mid -0.249642 0.249642)
							(end -0.1778 0.2794)
						)
						(arc
							(start 0.1778 0.2794)
							(mid 0.249642 0.249642)
							(end 0.2794 0.1778)
						)
						(arc
							(start 0.2794 -0.1778)
							(mid 0.249642 -0.249642)
							(end 0.1778 -0.2794)
						)
					)
					(width 0)
					(fill yes)
				)
			)
		)
	)
	(footprint ""
		(layer "F.Cu")
		(at 17.018 -267.843)
		(property "Reference" "Q88"
			(at 0 0 0)
			(layer "F.SilkS")
			(hide yes)
			(effects
				(font
					(size 1.27 1.27)
				)
			)
		)
		(property "Value" "2N7002A-7-GP"
			(at 0.127 -8.9662 0)
			(unlocked yes)
			(layer "F.Fab")
			(hide yes)
			(effects
				(font
					(size 1.016 1.016)
					(thickness 0.1524)
				)
			)
		)
		(property "Device Type" "SOT23DGS2D4H48"
			(at 0.127 -10.4902 0)
			(unlocked yes)
			(layer "F.Fab")
			(hide yes)
			(effects
				(font
					(size 1.016 1.016)
					(thickness 0.1524)
				)
			)
		)
		(duplicate_pad_numbers_are_jumpers no)
		(fp_line
			(start -1.651 -1.778)
			(end -1.651 1.778)
			(stroke
				(width 0.1524)
				(type default)
			)
			(layer "F.SilkS")
		)
		(fp_line
			(start -1.651 1.778)
			(end 1.651 1.778)
			(stroke
				(width 0.1524)
				(type default)
			)
			(layer "F.SilkS")
		)
		(fp_line
			(start 1.651 -1.778)
			(end -1.651 -1.778)
			(stroke
				(width 0.1524)
				(type default)
			)
			(layer "F.SilkS")
		)
		(fp_line
			(start 1.651 1.778)
			(end 1.651 -1.778)
			(stroke
				(width 0.1524)
				(type default)
			)
			(layer "F.SilkS")
		)
		(fp_poly
			(pts
				(xy -1.778 1.8796) (xy -1.778 -1.8796) (xy 1.778 -1.8796) (xy 1.778 1.8796)
			)
			(stroke
				(width 0)
				(type default)
			)
			(fill no)
			(layer "F.CrtYd")
		)
		(fp_poly
			(pts
				(xy -1.778 1.8796) (xy -1.778 -1.8796) (xy 1.778 -1.8796) (xy 1.778 1.8796)
			)
			(stroke
				(width 0)
				(type default)
			)
			(fill no)
			(layer "F.Fab")
		)
		(pad "D" smd custom
			(at 0 -0.9525)
			(size 0.1905 0.1905)
			(layers "F.Cu" "F.Mask" "F.Paste")
			(net "SSD_ACT_DR12_MOS_N")
			(options
				(clearance outline)
				(anchor circle)
			)
			(primitives
				(gr_poly
					(pts
						(arc
							(start -0.1778 0.5715)
							(mid -0.321484 0.511984)
							(end -0.381 0.3683)
						)
						(arc
							(start -0.381 -0.3683)
							(mid -0.321484 -0.511984)
							(end -0.1778 -0.5715)
						)
						(arc
							(start 0.1778 -0.5715)
							(mid 0.321484 -0.511984)
							(end 0.381 -0.3683)
						)
						(arc
							(start 0.381 0.3683)
							(mid 0.321484 0.511984)
							(end 0.1778 0.5715)
						)
					)
					(width 0)
					(fill yes)
				)
			)
		)
		(pad "G" smd custom
			(at -0.98425 0.9525)
			(size 0.1905 0.1905)
			(layers "F.Cu" "F.Mask" "F.Paste")
			(net "ATTN_LED_DR12_AND_R")
			(options
				(clearance outline)
				(anchor circle)
			)
			(primitives
				(gr_poly
					(pts
						(arc
							(start -0.1778 0.5715)
							(mid -0.321484 0.511984)
							(end -0.381 0.3683)
						)
						(arc
							(start -0.381 -0.3683)
							(mid -0.321484 -0.511984)
							(end -0.1778 -0.5715)
						)
						(arc
							(start 0.1778 -0.5715)
							(mid 0.321484 -0.511984)
							(end 0.381 -0.3683)
						)
						(arc
							(start 0.381 0.3683)
							(mid 0.321484 0.511984)
							(end 0.1778 0.5715)
						)
					)
					(width 0)
					(fill yes)
				)
			)
		)
		(pad "S" smd custom
			(at 0.98425 0.9525)
			(size 0.1905 0.1905)
			(layers "F.Cu" "F.Mask" "F.Paste")
			(net "SSD_ACT_DR12_R")
			(options
				(clearance outline)
				(anchor circle)
			)
			(primitives
				(gr_poly
					(pts
						(arc
							(start -0.1778 0.5715)
							(mid -0.321484 0.511984)
							(end -0.381 0.3683)
						)
						(arc
							(start -0.381 -0.3683)
							(mid -0.321484 -0.511984)
							(end -0.1778 -0.5715)
						)
						(arc
							(start 0.1778 -0.5715)
							(mid 0.321484 -0.511984)
							(end 0.381 -0.3683)
						)
						(arc
							(start 0.381 0.3683)
							(mid 0.321484 0.511984)
							(end 0.1778 0.5715)
						)
					)
					(width 0)
					(fill yes)
				)
			)
		)
	)
	(footprint ""
		(layer "F.Cu")
		(at 43.434 -7.0104 90)
		(property "Reference" "Q96"
			(at 0 0 90)
			(layer "F.SilkS")
			(hide yes)
			(effects
				(font
					(size 1.27 1.27)
				)
			)
		)
		(property "Value" "2N7002A-7-GP"
			(at 0.127 -8.9662 90)
			(unlocked yes)
			(layer "F.Fab")
			(hide yes)
			(effects
				(font
					(size 1.016 1.016)
					(thickness 0.1524)
				)
			)
		)
		(property "Device Type" "SOT23DGS2D4H48"
			(at 0.127 -10.4902 90)
			(unlocked yes)
			(layer "F.Fab")
			(hide yes)
			(effects
				(font
					(size 1.016 1.016)
					(thickness 0.1524)
				)
			)
		)
		(duplicate_pad_numbers_are_jumpers no)
		(fp_line
			(start 1.651 -1.778)
			(end -1.651 -1.778)
			(stroke
				(width 0.1524)
				(type default)
			)
			(layer "F.SilkS")
		)
		(fp_line
			(start -1.651 -1.778)
			(end -1.651 1.778)
			(stroke
				(width 0.1524)
				(type default)
			)
			(layer "F.SilkS")
		)
		(fp_line
			(start 1.651 1.778)
			(end 1.651 -1.778)
			(stroke
				(width 0.1524)
				(type default)
			)
			(layer "F.SilkS")
		)
		(fp_line
			(start -1.651 1.778)
			(end 1.651 1.778)
			(stroke
				(width 0.1524)
				(type default)
			)
			(layer "F.SilkS")
		)
		(fp_poly
			(pts
				(xy -1.778 1.8796) (xy -1.778 -1.8796) (xy 1.778 -1.8796) (xy 1.778 1.8796)
			)
			(stroke
				(width 0)
				(type default)
			)
			(fill no)
			(layer "F.CrtYd")
		)
		(fp_poly
			(pts
				(xy -1.778 1.8796) (xy -1.778 -1.8796) (xy 1.778 -1.8796) (xy 1.778 1.8796)
			)
			(stroke
				(width 0)
				(type default)
			)
			(fill no)
			(layer "F.Fab")
		)
		(pad "D" smd custom
			(at 0 -0.9525 90)
			(size 0.1905 0.1905)
			(layers "F.Cu" "F.Mask" "F.Paste")
			(net "P12V_MOST14_GATE_D")
			(options
				(clearance outline)
				(anchor circle)
			)
			(primitives
				(gr_poly
					(pts
						(arc
							(start -0.1778 0.5715)
							(mid -0.321484 0.511984)
							(end -0.381 0.3683)
						)
						(arc
							(start -0.381 -0.3683)
							(mid -0.321484 -0.511984)
							(end -0.1778 -0.5715)
						)
						(arc
							(start 0.1778 -0.5715)
							(mid 0.321484 -0.511984)
							(end 0.381 -0.3683)
						)
						(arc
							(start 0.381 0.3683)
							(mid 0.321484 0.511984)
							(end 0.1778 0.5715)
						)
					)
					(width 0)
					(fill yes)
				)
			)
		)
		(pad "G" smd custom
			(at -0.98425 0.9525 90)
			(size 0.1905 0.1905)
			(layers "F.Cu" "F.Mask" "F.Paste")
			(net "P12V_MOST14_GATE")
			(options
				(clearance outline)
				(anchor circle)
			)
			(primitives
				(gr_poly
					(pts
						(arc
							(start -0.1778 0.5715)
							(mid -0.321484 0.511984)
							(end -0.381 0.3683)
						)
						(arc
							(start -0.381 -0.3683)
							(mid -0.321484 -0.511984)
							(end -0.1778 -0.5715)
						)
						(arc
							(start 0.1778 -0.5715)
							(mid 0.321484 -0.511984)
							(end 0.381 -0.3683)
						)
						(arc
							(start 0.381 0.3683)
							(mid 0.321484 0.511984)
							(end 0.1778 0.5715)
						)
					)
					(width 0)
					(fill yes)
				)
			)
		)
		(pad "S" smd custom
			(at 0.98425 0.9525 90)
			(size 0.1905 0.1905)
			(layers "F.Cu" "F.Mask" "F.Paste")
			(net "GND")
			(options
				(clearance outline)
				(anchor circle)
			)
			(primitives
				(gr_poly
					(pts
						(arc
							(start -0.1778 0.5715)
							(mid -0.321484 0.511984)
							(end -0.381 0.3683)
						)
						(arc
							(start -0.381 -0.3683)
							(mid -0.321484 -0.511984)
							(end -0.1778 -0.5715)
						)
						(arc
							(start 0.1778 -0.5715)
							(mid 0.321484 -0.511984)
							(end 0.381 -0.3683)
						)
						(arc
							(start 0.381 0.3683)
							(mid 0.321484 0.511984)
							(end 0.1778 0.5715)
						)
					)
					(width 0)
					(fill yes)
				)
			)
		)
	)
	(footprint ""
		(layer "F.Cu")
		(at 32.131 -390.525 -90)
		(property "Reference" "R399"
			(at 0 0 270)
			(layer "F.SilkS")
			(hide yes)
			(effects
				(font
					(size 1.27 1.27)
				)
			)
		)
		(property "Value" "0R2J-2-GP"
			(at 0.064008 -3.993896 270)
			(unlocked yes)
			(layer "F.Fab")
			(hide yes)
			(effects
				(font
					(size 1.016 1.016)
					(thickness 0.1524)
				)
			)
		)
		(property "Device Type" "R402H16"
			(at 0.064008 -5.517896 270)
			(unlocked yes)
			(layer "F.Fab")
			(hide yes)
			(effects
				(font
					(size 1.016 1.016)
					(thickness 0.1524)
				)
			)
		)
		(duplicate_pad_numbers_are_jumpers no)
		(fp_line
			(start -0.508 -0.9398)
			(end -0.508 0.9398)
			(stroke
				(width 0.1524)
				(type default)
			)
			(layer "F.SilkS")
		)
		(fp_line
			(start 0.508 -0.9398)
			(end -0.508 -0.9398)
			(stroke
				(width 0.1524)
				(type default)
			)
			(layer "F.SilkS")
		)
		(fp_rect
			(start -0.508 0.9398)
			(end 0.508 -0.9398)
			(stroke
				(width 0)
				(type default)
			)
			(fill no)
			(layer "F.CrtYd")
		)
		(fp_rect
			(start -0.508 0.9398)
			(end 0.508 -0.9398)
			(stroke
				(width 0)
				(type default)
			)
			(fill no)
			(layer "F.Fab")
		)
		(pad "1" smd custom
			(at 0 -0.4445 270)
			(size 0.1397 0.1397)
			(layers "F.Cu" "F.Mask" "F.Paste")
			(net "SCL_DR6_R")
			(options
				(clearance outline)
				(anchor circle)
			)
			(primitives
				(gr_poly
					(pts
						(arc
							(start -0.1778 -0.2794)
							(mid -0.249642 -0.249642)
							(end -0.2794 -0.1778)
						)
						(arc
							(start -0.2794 0.1778)
							(mid -0.249642 0.249642)
							(end -0.1778 0.2794)
						)
						(arc
							(start 0.1778 0.2794)
							(mid 0.249642 0.249642)
							(end 0.2794 0.1778)
						)
						(arc
							(start 0.2794 -0.1778)
							(mid 0.249642 -0.249642)
							(end 0.1778 -0.2794)
						)
					)
					(width 0)
					(fill yes)
				)
			)
		)
		(pad "2" smd custom
			(at 0 0.4445 270)
			(size 0.1397 0.1397)
			(layers "F.Cu" "F.Mask" "F.Paste")
			(net "SCL_DR6")
			(options
				(clearance outline)
				(anchor circle)
			)
			(primitives
				(gr_poly
					(pts
						(arc
							(start -0.1778 -0.2794)
							(mid -0.249642 -0.249642)
							(end -0.2794 -0.1778)
						)
						(arc
							(start -0.2794 0.1778)
							(mid -0.249642 0.249642)
							(end -0.1778 0.2794)
						)
						(arc
							(start 0.1778 0.2794)
							(mid 0.249642 0.249642)
							(end 0.2794 0.1778)
						)
						(arc
							(start 0.2794 -0.1778)
							(mid 0.249642 -0.249642)
							(end 0.1778 -0.2794)
						)
					)
					(width 0)
					(fill yes)
				)
			)
		)
	)
	(footprint ""
		(layer "F.Cu")
		(at 87.122 -106.299)
		(property "Reference" "C8931"
			(at 0 0 0)
			(layer "F.SilkS")
			(hide yes)
			(effects
				(font
					(size 1.27 1.27)
				)
			)
		)
		(property "Value" "SC1U10V2KX-7-GP"
			(at 1.1811 -2.7051 0)
			(unlocked yes)
			(layer "F.Fab")
			(hide yes)
			(effects
				(font
					(size 1.016 1.016)
					(thickness 0.1524)
				)
			)
		)
		(property "Device Type" "C402H22"
			(at 1.1811 -4.2291 0)
			(unlocked yes)
			(layer "F.Fab")
			(hide yes)
			(effects
				(font
					(size 1.016 1.016)
					(thickness 0.1524)
				)
			)
		)
		(duplicate_pad_numbers_are_jumpers no)
		(fp_rect
			(start -0.4318 0.9525)
			(end 0.4318 -0.9525)
			(stroke
				(width 0)
				(type default)
			)
			(fill no)
			(layer "F.CrtYd")
		)
		(fp_poly
			(pts
				(xy -0.4318 0.9525) (xy 0.4318 0.9525) (xy 0.4318 -0.9525) (xy -0.4318 -0.9525)
			)
			(stroke
				(width 0)
				(type default)
			)
			(fill no)
			(layer "F.Fab")
		)
		(pad "1" smd custom
			(at 0 -0.4445)
			(size 0.1524 0.1524)
			(layers "F.Cu" "F.Mask" "F.Paste")
			(net "VDDA_4")
			(options
				(clearance outline)
				(anchor circle)
			)
			(primitives
				(gr_poly
					(pts
						(arc
							(start 0.3048 -0.2032)
							(mid 0.275042 -0.275042)
							(end 0.2032 -0.3048)
						)
						(arc
							(start -0.2032 -0.3048)
							(mid -0.275042 -0.275042)
							(end -0.3048 -0.2032)
						)
						(arc
							(start -0.3048 0.2032)
							(mid -0.275042 0.275042)
							(end -0.2032 0.3048)
						)
						(arc
							(start 0.2032 0.3048)
							(mid 0.275042 0.275042)
							(end 0.3048 0.2032)
						)
					)
					(width 0)
					(fill yes)
				)
			)
		)
		(pad "2" smd custom
			(at 0 0.4445)
			(size 0.1524 0.1524)
			(layers "F.Cu" "F.Mask" "F.Paste")
			(net "GND")
			(options
				(clearance outline)
				(anchor circle)
			)
			(primitives
				(gr_poly
					(pts
						(arc
							(start 0.3048 -0.2032)
							(mid 0.275042 -0.275042)
							(end 0.2032 -0.3048)
						)
						(arc
							(start -0.2032 -0.3048)
							(mid -0.275042 -0.275042)
							(end -0.3048 -0.2032)
						)
						(arc
							(start -0.3048 0.2032)
							(mid -0.275042 0.275042)
							(end -0.2032 0.3048)
						)
						(arc
							(start 0.2032 0.3048)
							(mid 0.275042 0.275042)
							(end 0.3048 0.2032)
						)
					)
					(width 0)
					(fill yes)
				)
			)
		)
	)
	(footprint ""
		(layer "F.Cu")
		(at 30.099 -499.0084 180)
		(property "Reference" "PC1207"
			(at 0 0 180)
			(layer "F.SilkS")
			(hide yes)
			(effects
				(font
					(size 1.27 1.27)
				)
			)
		)
		(property "Value" "SCD1U50V3KX-GP"
			(at 0 -2.8194 180)
			(unlocked yes)
			(layer "F.Fab")
			(hide yes)
			(effects
				(font
					(size 1.016 1.016)
					(thickness 0.1524)
				)
			)
		)
		(property "Device Type" "C603H36"
			(at 0 -4.3434 180)
			(unlocked yes)
			(layer "F.Fab")
			(hide yes)
			(effects
				(font
					(size 1.016 1.016)
					(thickness 0.1524)
				)
			)
		)
		(duplicate_pad_numbers_are_jumpers no)
		(fp_line
			(start 0.508 0)
			(end -0.508 0)
			(stroke
				(width 0.2032)
				(type default)
			)
			(layer "F.SilkS")
		)
		(fp_rect
			(start -0.5842 1.3335)
			(end 0.5842 -1.3335)
			(stroke
				(width 0)
				(type default)
			)
			(fill no)
			(layer "F.CrtYd")
		)
		(fp_rect
			(start -0.5842 1.3335)
			(end 0.5842 -1.3335)
			(stroke
				(width 0)
				(type default)
			)
			(fill no)
			(layer "F.Fab")
		)
		(pad "1" smd custom
			(at 0 -0.762 180)
			(size 0.2159 0.2159)
			(layers "F.Cu" "F.Mask" "F.Paste")
			(net "P12V_SSD5")
			(options
				(clearance outline)
				(anchor circle)
			)
			(primitives
				(gr_poly
					(pts
						(arc
							(start -0.3302 -0.4318)
							(mid -0.402042 -0.402042)
							(end -0.4318 -0.3302)
						)
						(arc
							(start -0.4318 0.3302)
							(mid -0.402042 0.402042)
							(end -0.3302 0.4318)
						)
						(arc
							(start 0.3302 0.4318)
							(mid 0.402042 0.402042)
							(end 0.4318 0.3302)
						)
						(arc
							(start 0.4318 -0.3302)
							(mid 0.402042 -0.402042)
							(end 0.3302 -0.4318)
						)
					)
					(width 0)
					(fill yes)
				)
			)
		)
		(pad "2" smd custom
			(at 0 0.762 180)
			(size 0.2159 0.2159)
			(layers "F.Cu" "F.Mask" "F.Paste")
			(net "GND")
			(options
				(clearance outline)
				(anchor circle)
			)
			(primitives
				(gr_poly
					(pts
						(arc
							(start -0.3302 -0.4318)
							(mid -0.402042 -0.402042)
							(end -0.4318 -0.3302)
						)
						(arc
							(start -0.4318 0.3302)
							(mid -0.402042 0.402042)
							(end -0.3302 0.4318)
						)
						(arc
							(start 0.3302 0.4318)
							(mid 0.402042 0.402042)
							(end 0.4318 0.3302)
						)
						(arc
							(start 0.4318 -0.3302)
							(mid 0.402042 -0.402042)
							(end 0.3302 -0.4318)
						)
					)
					(width 0)
					(fill yes)
				)
			)
		)
	)
	(footprint ""
		(layer "F.Cu")
		(at 17.653 -491.363)
		(property "Reference" "C387"
			(at 0 0 0)
			(layer "F.SilkS")
			(hide yes)
			(effects
				(font
					(size 1.27 1.27)
				)
			)
		)
		(property "Value" "SCD1U25V2KX-2-GP"
			(at 1.1811 -2.7051 0)
			(unlocked yes)
			(layer "F.Fab")
			(hide yes)
			(effects
				(font
					(size 1.016 1.016)
					(thickness 0.1524)
				)
			)
		)
		(property "Device Type" "C402H22"
			(at 1.1811 -4.2291 0)
			(unlocked yes)
			(layer "F.Fab")
			(hide yes)
			(effects
				(font
					(size 1.016 1.016)
					(thickness 0.1524)
				)
			)
		)
		(duplicate_pad_numbers_are_jumpers no)
		(fp_rect
			(start -0.4318 0.9525)
			(end 0.4318 -0.9525)
			(stroke
				(width 0)
				(type default)
			)
			(fill no)
			(layer "F.CrtYd")
		)
		(fp_rect
			(start -0.4318 0.9525)
			(end 0.4318 -0.9525)
			(stroke
				(width 0)
				(type default)
			)
			(fill no)
			(layer "F.Fab")
		)
		(pad "1" smd custom
			(at 0 -0.4445)
			(size 0.1524 0.1524)
			(layers "F.Cu" "F.Mask" "F.Paste")
			(net "P12V")
			(options
				(clearance outline)
				(anchor circle)
			)
			(primitives
				(gr_poly
					(pts
						(arc
							(start 0.3048 -0.2032)
							(mid 0.275042 -0.275042)
							(end 0.2032 -0.3048)
						)
						(arc
							(start -0.2032 -0.3048)
							(mid -0.275042 -0.275042)
							(end -0.3048 -0.2032)
						)
						(arc
							(start -0.3048 0.2032)
							(mid -0.275042 0.275042)
							(end -0.2032 0.3048)
						)
						(arc
							(start 0.2032 0.3048)
							(mid 0.275042 0.275042)
							(end 0.3048 0.2032)
						)
					)
					(width 0)
					(fill yes)
				)
			)
		)
		(pad "2" smd custom
			(at 0 0.4445)
			(size 0.1524 0.1524)
			(layers "F.Cu" "F.Mask" "F.Paste")
			(net "SW_SSD5_N")
			(options
				(clearance outline)
				(anchor circle)
			)
			(primitives
				(gr_poly
					(pts
						(arc
							(start 0.3048 -0.2032)
							(mid 0.275042 -0.275042)
							(end 0.2032 -0.3048)
						)
						(arc
							(start -0.2032 -0.3048)
							(mid -0.275042 -0.275042)
							(end -0.3048 -0.2032)
						)
						(arc
							(start -0.3048 0.2032)
							(mid -0.275042 0.275042)
							(end -0.2032 0.3048)
						)
						(arc
							(start 0.2032 0.3048)
							(mid 0.275042 0.275042)
							(end 0.3048 0.2032)
						)
					)
					(width 0)
					(fill yes)
				)
			)
		)
	)
	(footprint ""
		(layer "F.Cu")
		(at 95.504 -424.688)
		(property "Reference" "C8837"
			(at 0 0 0)
			(layer "F.SilkS")
			(hide yes)
			(effects
				(font
					(size 1.27 1.27)
				)
			)
		)
		(property "Value" "SCD1U16V2KX-3GP"
			(at 1.1811 -2.7051 0)
			(unlocked yes)
			(layer "F.Fab")
			(hide yes)
			(effects
				(font
					(size 1.016 1.016)
					(thickness 0.1524)
				)
			)
		)
		(property "Device Type" "C402H22"
			(at 1.1811 -4.2291 0)
			(unlocked yes)
			(layer "F.Fab")
			(hide yes)
			(effects
				(font
					(size 1.016 1.016)
					(thickness 0.1524)
				)
			)
		)
		(duplicate_pad_numbers_are_jumpers no)
		(fp_rect
			(start -0.4318 0.9525)
			(end 0.4318 -0.9525)
			(stroke
				(width 0)
				(type default)
			)
			(fill no)
			(layer "F.CrtYd")
		)
		(fp_rect
			(start -0.4318 0.9525)
			(end 0.4318 -0.9525)
			(stroke
				(width 0)
				(type default)
			)
			(fill no)
			(layer "F.Fab")
		)
		(pad "1" smd custom
			(at 0 -0.4445)
			(size 0.1524 0.1524)
			(layers "F.Cu" "F.Mask" "F.Paste")
			(net "VDD_IO_1")
			(options
				(clearance outline)
				(anchor circle)
			)
			(primitives
				(gr_poly
					(pts
						(arc
							(start 0.3048 -0.2032)
							(mid 0.275042 -0.275042)
							(end 0.2032 -0.3048)
						)
						(arc
							(start -0.2032 -0.3048)
							(mid -0.275042 -0.275042)
							(end -0.3048 -0.2032)
						)
						(arc
							(start -0.3048 0.2032)
							(mid -0.275042 0.275042)
							(end -0.2032 0.3048)
						)
						(arc
							(start 0.2032 0.3048)
							(mid 0.275042 0.275042)
							(end 0.3048 0.2032)
						)
					)
					(width 0)
					(fill yes)
				)
			)
		)
		(pad "2" smd custom
			(at 0 0.4445)
			(size 0.1524 0.1524)
			(layers "F.Cu" "F.Mask" "F.Paste")
			(net "GND")
			(options
				(clearance outline)
				(anchor circle)
			)
			(primitives
				(gr_poly
					(pts
						(arc
							(start 0.3048 -0.2032)
							(mid 0.275042 -0.275042)
							(end 0.2032 -0.3048)
						)
						(arc
							(start -0.2032 -0.3048)
							(mid -0.275042 -0.275042)
							(end -0.3048 -0.2032)
						)
						(arc
							(start -0.3048 0.2032)
							(mid -0.275042 0.275042)
							(end -0.2032 0.3048)
						)
						(arc
							(start 0.2032 0.3048)
							(mid 0.275042 0.275042)
							(end 0.3048 0.2032)
						)
					)
					(width 0)
					(fill yes)
				)
			)
		)
	)
	(footprint ""
		(layer "F.Cu")
		(at 102.235 -106.807 -90)
		(property "Reference" "R9585"
			(at 0 0 270)
			(layer "F.SilkS")
			(hide yes)
			(effects
				(font
					(size 1.27 1.27)
				)
			)
		)
		(property "Value" "0R5J-L1-GP"
			(at 0 -8.9535 270)
			(unlocked yes)
			(layer "F.Fab")
			(hide yes)
			(effects
				(font
					(size 1.27 1.016)
					(thickness 0.1524)
				)
			)
		)
		(property "Device Type" "R805H24"
			(at 0 -10.6299 270)
			(unlocked yes)
			(layer "F.Fab")
			(hide yes)
			(effects
				(font
					(size 1.27 1.016)
					(thickness 0.1524)
				)
			)
		)
		(duplicate_pad_numbers_are_jumpers no)
		(fp_line
			(start -0.889 1.7018)
			(end 0.889 1.7018)
			(stroke
				(width 0.1524)
				(type default)
			)
			(layer "F.SilkS")
		)
		(fp_line
			(start 0.889 1.7018)
			(end 0.889 -0.508)
			(stroke
				(width 0.1524)
				(type default)
			)
			(layer "F.SilkS")
		)
		(fp_line
			(start -0.889 0.0762)
			(end -0.889 1.7018)
			(stroke
				(width 0.1524)
				(type default)
			)
			(layer "F.SilkS")
		)
		(fp_line
			(start -0.889 -1.7018)
			(end -0.889 0.2794)
			(stroke
				(width 0.1524)
				(type default)
			)
			(layer "F.SilkS")
		)
		(fp_line
			(start 0.889 -1.7018)
			(end 0.889 -0.381)
			(stroke
				(width 0.1524)
				(type default)
			)
			(layer "F.SilkS")
		)
		(fp_line
			(start 0.889 -1.7018)
			(end -0.889 -1.7018)
			(stroke
				(width 0.1524)
				(type default)
			)
			(layer "F.SilkS")
		)
		(fp_poly
			(pts
				(xy 0.9652 -1.778) (xy 0.9652 1.778) (xy -0.9652 1.778) (xy -0.9652 -1.778)
			)
			(stroke
				(width 0)
				(type default)
			)
			(fill no)
			(layer "F.CrtYd")
		)
		(fp_rect
			(start -0.9652 1.778)
			(end 0.9652 -1.778)
			(stroke
				(width 0)
				(type default)
			)
			(fill no)
			(layer "F.Fab")
		)
		(pad "1" smd rect
			(at 0 -0.9652 270)
			(size 1.397 1.143)
			(layers "F.Cu" "F.Mask" "F.Paste")
			(net "P3V3")
		)
		(pad "2" smd rect
			(at 0 0.9652 270)
			(size 1.397 1.143)
			(layers "F.Cu" "F.Mask" "F.Paste")
			(net "VDD_IO_4")
		)
	)
	(footprint ""
		(layer "F.Cu")
		(at 106.045 -208.026 180)
		(property "Reference" "C9363"
			(at 0 0 180)
			(layer "F.SilkS")
			(hide yes)
			(effects
				(font
					(size 1.27 1.27)
				)
			)
		)
		(property "Value" "SC1KP50V2KX-1GP"
			(at 1.1811 -2.7051 180)
			(unlocked yes)
			(layer "F.Fab")
			(hide yes)
			(effects
				(font
					(size 1.016 1.016)
					(thickness 0.1524)
				)
			)
		)
		(property "Device Type" "C402H22"
			(at 1.1811 -4.2291 180)
			(unlocked yes)
			(layer "F.Fab")
			(hide yes)
			(effects
				(font
					(size 1.016 1.016)
					(thickness 0.1524)
				)
			)
		)
		(duplicate_pad_numbers_are_jumpers no)
		(fp_rect
			(start -0.4318 0.9525)
			(end 0.4318 -0.9525)
			(stroke
				(width 0)
				(type default)
			)
			(fill no)
			(layer "F.CrtYd")
		)
		(fp_rect
			(start -0.4318 0.9525)
			(end 0.4318 -0.9525)
			(stroke
				(width 0)
				(type default)
			)
			(fill no)
			(layer "F.Fab")
		)
		(pad "1" smd custom
			(at 0 -0.4445 180)
			(size 0.1524 0.1524)
			(layers "F.Cu" "F.Mask" "F.Paste")
			(net "SSD3_CLK0_OE_R_N")
			(options
				(clearance outline)
				(anchor circle)
			)
			(primitives
				(gr_poly
					(pts
						(arc
							(start 0.3048 -0.2032)
							(mid 0.275042 -0.275042)
							(end 0.2032 -0.3048)
						)
						(arc
							(start -0.2032 -0.3048)
							(mid -0.275042 -0.275042)
							(end -0.3048 -0.2032)
						)
						(arc
							(start -0.3048 0.2032)
							(mid -0.275042 0.275042)
							(end -0.2032 0.3048)
						)
						(arc
							(start 0.2032 0.3048)
							(mid 0.275042 0.275042)
							(end 0.3048 0.2032)
						)
					)
					(width 0)
					(fill yes)
				)
			)
		)
		(pad "2" smd custom
			(at 0 0.4445 180)
			(size 0.1524 0.1524)
			(layers "F.Cu" "F.Mask" "F.Paste")
			(net "GND")
			(options
				(clearance outline)
				(anchor circle)
			)
			(primitives
				(gr_poly
					(pts
						(arc
							(start 0.3048 -0.2032)
							(mid 0.275042 -0.275042)
							(end 0.2032 -0.3048)
						)
						(arc
							(start -0.2032 -0.3048)
							(mid -0.275042 -0.275042)
							(end -0.3048 -0.2032)
						)
						(arc
							(start -0.3048 0.2032)
							(mid -0.275042 0.275042)
							(end -0.2032 0.3048)
						)
						(arc
							(start 0.2032 0.3048)
							(mid 0.275042 0.275042)
							(end 0.3048 0.2032)
						)
					)
					(width 0)
					(fill yes)
				)
			)
		)
	)
	(footprint ""
		(layer "F.Cu")
		(at 21.144992 -267.877544 180)
		(property "Reference" "C9530"
			(at 0 0 180)
			(layer "F.SilkS")
			(hide yes)
			(effects
				(font
					(size 1.27 1.27)
				)
			)
		)
		(property "Value" "SCD1U16V2KX-3GP"
			(at 1.1811 -2.7051 180)
			(unlocked yes)
			(layer "F.Fab")
			(hide yes)
			(effects
				(font
					(size 1.016 1.016)
					(thickness 0.1524)
				)
			)
		)
		(property "Device Type" "C402H22"
			(at 1.1811 -4.2291 180)
			(unlocked yes)
			(layer "F.Fab")
			(hide yes)
			(effects
				(font
					(size 1.016 1.016)
					(thickness 0.1524)
				)
			)
		)
		(duplicate_pad_numbers_are_jumpers no)
		(fp_rect
			(start -0.4318 0.9525)
			(end 0.4318 -0.9525)
			(stroke
				(width 0)
				(type default)
			)
			(fill no)
			(layer "F.CrtYd")
		)
		(fp_rect
			(start -0.4318 0.9525)
			(end 0.4318 -0.9525)
			(stroke
				(width 0)
				(type default)
			)
			(fill no)
			(layer "F.Fab")
		)
		(pad "1" smd custom
			(at 0 -0.4445 180)
			(size 0.1524 0.1524)
			(layers "F.Cu" "F.Mask" "F.Paste")
			(net "P3V3")
			(options
				(clearance outline)
				(anchor circle)
			)
			(primitives
				(gr_poly
					(pts
						(arc
							(start 0.3048 -0.2032)
							(mid 0.275042 -0.275042)
							(end 0.2032 -0.3048)
						)
						(arc
							(start -0.2032 -0.3048)
							(mid -0.275042 -0.275042)
							(end -0.3048 -0.2032)
						)
						(arc
							(start -0.3048 0.2032)
							(mid -0.275042 0.275042)
							(end -0.2032 0.3048)
						)
						(arc
							(start 0.2032 0.3048)
							(mid 0.275042 0.275042)
							(end 0.3048 0.2032)
						)
					)
					(width 0)
					(fill yes)
				)
			)
		)
		(pad "2" smd custom
			(at 0 0.4445 180)
			(size 0.1524 0.1524)
			(layers "F.Cu" "F.Mask" "F.Paste")
			(net "GND")
			(options
				(clearance outline)
				(anchor circle)
			)
			(primitives
				(gr_poly
					(pts
						(arc
							(start 0.3048 -0.2032)
							(mid 0.275042 -0.275042)
							(end 0.2032 -0.3048)
						)
						(arc
							(start -0.2032 -0.3048)
							(mid -0.275042 -0.275042)
							(end -0.3048 -0.2032)
						)
						(arc
							(start -0.3048 0.2032)
							(mid -0.275042 0.275042)
							(end -0.2032 0.3048)
						)
						(arc
							(start 0.2032 0.3048)
							(mid 0.275042 0.275042)
							(end 0.3048 0.2032)
						)
					)
					(width 0)
					(fill yes)
				)
			)
		)
	)
	(footprint ""
		(layer "F.Cu")
		(at 27.0256 -311.7596)
		(property "Reference" "PC1220"
			(at 0 0 0)
			(layer "F.SilkS")
			(hide yes)
			(effects
				(font
					(size 1.27 1.27)
				)
			)
		)
		(property "Value" "SC22U25V6KX-GP-U"
			(at -2.860802 -5.279644 0)
			(unlocked yes)
			(layer "F.Fab")
			(hide yes)
			(effects
				(font
					(size 1.016 1.016)
					(thickness 0.1524)
				)
			)
		)
		(property "Device Type" "C1206-TO0D3H75"
			(at -2.860802 -6.803644 0)
			(unlocked yes)
			(layer "F.Fab")
			(hide yes)
			(effects
				(font
					(size 1.016 1.016)
					(thickness 0.1524)
				)
			)
		)
		(duplicate_pad_numbers_are_jumpers no)
		(fp_line
			(start -1.3081 -2.3749)
			(end 1.3081 -2.3749)
			(stroke
				(width 0.1524)
				(type default)
			)
			(layer "F.SilkS")
		)
		(fp_line
			(start -1.3081 2.3749)
			(end -1.3081 -2.3749)
			(stroke
				(width 0.1524)
				(type default)
			)
			(layer "F.SilkS")
		)
		(fp_line
			(start 1.3081 -2.3749)
			(end 1.3081 2.3749)
			(stroke
				(width 0.1524)
				(type default)
			)
			(layer "F.SilkS")
		)
		(fp_line
			(start 1.3081 2.3749)
			(end -1.3081 2.3749)
			(stroke
				(width 0.1524)
				(type default)
			)
			(layer "F.SilkS")
		)
		(fp_rect
			(start -0.8001 1.6002)
			(end 0.8001 -1.6002)
			(stroke
				(width 0)
				(type default)
			)
			(fill no)
			(layer "F.CrtYd")
		)
		(fp_poly
			(pts
				(xy -1.5621 2.4511) (xy -1.5621 1.6002) (xy 0.8001 1.6002) (xy 0.8001 -1.6002) (xy -0.8001 -1.6002)
				(xy -0.8001 1.5875) (xy -1.5621 1.5875) (xy -1.5621 -2.4511) (xy 1.5621 -2.4511) (xy 1.5621 2.4511)
			)
			(stroke
				(width 0)
				(type default)
			)
			(fill no)
			(layer "F.CrtYd")
		)
		(fp_rect
			(start -1.5621 2.4511)
			(end 1.5621 -2.4511)
			(stroke
				(width 0)
				(type default)
			)
			(fill no)
			(layer "F.Fab")
		)
		(pad "1" smd rect
			(at 0 -1.392936)
			(size 2.1082 1.4478)
			(layers "F.Cu" "F.Mask" "F.Paste")
			(net "P12V_SSD11")
		)
		(pad "2" smd rect
			(at 0 1.392936)
			(size 2.1082 1.4478)
			(layers "F.Cu" "F.Mask" "F.Paste")
			(net "GND")
		)
	)
	(footprint ""
		(layer "F.Cu")
		(at 24.3078 -91.186 180)
		(property "Reference" "Q17"
			(at 0 0 180)
			(layer "F.SilkS")
			(hide yes)
			(effects
				(font
					(size 1.27 1.27)
				)
			)
		)
		(property "Value" "2N7002A-7-GP"
			(at 0.127 -8.9662 180)
			(unlocked yes)
			(layer "F.Fab")
			(hide yes)
			(effects
				(font
					(size 1.016 1.016)
					(thickness 0.1524)
				)
			)
		)
		(property "Device Type" "SOT23DGS2D4H48"
			(at 0.127 -10.4902 180)
			(unlocked yes)
			(layer "F.Fab")
			(hide yes)
			(effects
				(font
					(size 1.016 1.016)
					(thickness 0.1524)
				)
			)
		)
		(duplicate_pad_numbers_are_jumpers no)
		(fp_line
			(start 1.651 1.778)
			(end 1.651 -1.778)
			(stroke
				(width 0.1524)
				(type default)
			)
			(layer "F.SilkS")
		)
		(fp_line
			(start 1.651 -1.778)
			(end -1.651 -1.778)
			(stroke
				(width 0.1524)
				(type default)
			)
			(layer "F.SilkS")
		)
		(fp_line
			(start -1.651 1.778)
			(end 1.651 1.778)
			(stroke
				(width 0.1524)
				(type default)
			)
			(layer "F.SilkS")
		)
		(fp_line
			(start -1.651 -1.778)
			(end -1.651 1.778)
			(stroke
				(width 0.1524)
				(type default)
			)
			(layer "F.SilkS")
		)
		(fp_poly
			(pts
				(xy -1.778 1.8796) (xy -1.778 -1.8796) (xy 1.778 -1.8796) (xy 1.778 1.8796)
			)
			(stroke
				(width 0)
				(type default)
			)
			(fill no)
			(layer "F.CrtYd")
		)
		(fp_poly
			(pts
				(xy -1.778 1.8796) (xy -1.778 -1.8796) (xy 1.778 -1.8796) (xy 1.778 1.8796)
			)
			(stroke
				(width 0)
				(type default)
			)
			(fill no)
			(layer "F.Fab")
		)
		(pad "D" smd custom
			(at 0 -0.9525 180)
			(size 0.1905 0.1905)
			(layers "F.Cu" "F.Mask" "F.Paste")
			(net "SW_SSD9_R")
			(options
				(clearance outline)
				(anchor circle)
			)
			(primitives
				(gr_poly
					(pts
						(arc
							(start -0.1778 0.5715)
							(mid -0.321484 0.511984)
							(end -0.381 0.3683)
						)
						(arc
							(start -0.381 -0.3683)
							(mid -0.321484 -0.511984)
							(end -0.1778 -0.5715)
						)
						(arc
							(start 0.1778 -0.5715)
							(mid 0.321484 -0.511984)
							(end 0.381 -0.3683)
						)
						(arc
							(start 0.381 0.3683)
							(mid 0.321484 0.511984)
							(end 0.1778 0.5715)
						)
					)
					(width 0)
					(fill yes)
				)
			)
		)
		(pad "G" smd custom
			(at -0.98425 0.9525 180)
			(size 0.1905 0.1905)
			(layers "F.Cu" "F.Mask" "F.Paste")
			(net "SSD9_PWREN")
			(options
				(clearance outline)
				(anchor circle)
			)
			(primitives
				(gr_poly
					(pts
						(arc
							(start -0.1778 0.5715)
							(mid -0.321484 0.511984)
							(end -0.381 0.3683)
						)
						(arc
							(start -0.381 -0.3683)
							(mid -0.321484 -0.511984)
							(end -0.1778 -0.5715)
						)
						(arc
							(start 0.1778 -0.5715)
							(mid 0.321484 -0.511984)
							(end 0.381 -0.3683)
						)
						(arc
							(start 0.381 0.3683)
							(mid 0.321484 0.511984)
							(end 0.1778 0.5715)
						)
					)
					(width 0)
					(fill yes)
				)
			)
		)
		(pad "S" smd custom
			(at 0.98425 0.9525 180)
			(size 0.1905 0.1905)
			(layers "F.Cu" "F.Mask" "F.Paste")
			(net "GND")
			(options
				(clearance outline)
				(anchor circle)
			)
			(primitives
				(gr_poly
					(pts
						(arc
							(start -0.1778 0.5715)
							(mid -0.321484 0.511984)
							(end -0.381 0.3683)
						)
						(arc
							(start -0.381 -0.3683)
							(mid -0.321484 -0.511984)
							(end -0.1778 -0.5715)
						)
						(arc
							(start 0.1778 -0.5715)
							(mid 0.321484 -0.511984)
							(end 0.381 -0.3683)
						)
						(arc
							(start 0.381 0.3683)
							(mid 0.321484 0.511984)
							(end 0.1778 0.5715)
						)
					)
					(width 0)
					(fill yes)
				)
			)
		)
	)
	(footprint ""
		(layer "F.Cu")
		(at 99.949 -211.201 180)
		(property "Reference" "C9516"
			(at 0 0 180)
			(layer "F.SilkS")
			(hide yes)
			(effects
				(font
					(size 1.27 1.27)
				)
			)
		)
		(property "Value" "SCD1U16V2KX-3GP"
			(at 1.1811 -2.7051 180)
			(unlocked yes)
			(layer "F.Fab")
			(hide yes)
			(effects
				(font
					(size 1.016 1.016)
					(thickness 0.1524)
				)
			)
		)
		(property "Device Type" "C402H22"
			(at 1.1811 -4.2291 180)
			(unlocked yes)
			(layer "F.Fab")
			(hide yes)
			(effects
				(font
					(size 1.016 1.016)
					(thickness 0.1524)
				)
			)
		)
		(duplicate_pad_numbers_are_jumpers no)
		(fp_rect
			(start -0.4318 0.9525)
			(end 0.4318 -0.9525)
			(stroke
				(width 0)
				(type default)
			)
			(fill no)
			(layer "F.CrtYd")
		)
		(fp_rect
			(start -0.4318 0.9525)
			(end 0.4318 -0.9525)
			(stroke
				(width 0)
				(type default)
			)
			(fill no)
			(layer "F.Fab")
		)
		(pad "1" smd custom
			(at 0 -0.4445 180)
			(size 0.1524 0.1524)
			(layers "F.Cu" "F.Mask" "F.Paste")
			(net "VDD_DIFF_3")
			(options
				(clearance outline)
				(anchor circle)
			)
			(primitives
				(gr_poly
					(pts
						(arc
							(start 0.3048 -0.2032)
							(mid 0.275042 -0.275042)
							(end 0.2032 -0.3048)
						)
						(arc
							(start -0.2032 -0.3048)
							(mid -0.275042 -0.275042)
							(end -0.3048 -0.2032)
						)
						(arc
							(start -0.3048 0.2032)
							(mid -0.275042 0.275042)
							(end -0.2032 0.3048)
						)
						(arc
							(start 0.2032 0.3048)
							(mid 0.275042 0.275042)
							(end 0.3048 0.2032)
						)
					)
					(width 0)
					(fill yes)
				)
			)
		)
		(pad "2" smd custom
			(at 0 0.4445 180)
			(size 0.1524 0.1524)
			(layers "F.Cu" "F.Mask" "F.Paste")
			(net "GND")
			(options
				(clearance outline)
				(anchor circle)
			)
			(primitives
				(gr_poly
					(pts
						(arc
							(start 0.3048 -0.2032)
							(mid 0.275042 -0.275042)
							(end 0.2032 -0.3048)
						)
						(arc
							(start -0.2032 -0.3048)
							(mid -0.275042 -0.275042)
							(end -0.3048 -0.2032)
						)
						(arc
							(start -0.3048 0.2032)
							(mid -0.275042 0.275042)
							(end -0.2032 0.3048)
						)
						(arc
							(start 0.2032 0.3048)
							(mid 0.275042 0.275042)
							(end 0.3048 0.2032)
						)
					)
					(width 0)
					(fill yes)
				)
			)
		)
	)
	(footprint ""
		(layer "F.Cu")
		(at 206.883 -435.483 90)
		(property "Reference" "PR9088"
			(at 0 0 90)
			(layer "F.SilkS")
			(hide yes)
			(effects
				(font
					(size 1.27 1.27)
				)
			)
		)
		(property "Value" "0R6J-3-GP"
			(at -0.0508 -4.8514 90)
			(unlocked yes)
			(layer "F.Fab")
			(hide yes)
			(effects
				(font
					(size 1.016 1.016)
					(thickness 0.1524)
				)
			)
		)
		(property "Device Type" "R1206H28"
			(at 0 -6.3754 90)
			(unlocked yes)
			(layer "F.Fab")
			(hide yes)
			(effects
				(font
					(size 1.016 1.016)
					(thickness 0.1524)
				)
			)
		)
		(duplicate_pad_numbers_are_jumpers no)
		(fp_line
			(start 1.016 -2.2352)
			(end 1.016 2.2352)
			(stroke
				(width 0.1524)
				(type default)
			)
			(layer "F.SilkS")
		)
		(fp_line
			(start -1.016 -2.2352)
			(end 1.016 -2.2352)
			(stroke
				(width 0.1524)
				(type default)
			)
			(layer "F.SilkS")
		)
		(fp_line
			(start 1.016 2.2352)
			(end -1.016 2.2352)
			(stroke
				(width 0.1524)
				(type default)
			)
			(layer "F.SilkS")
		)
		(fp_line
			(start -1.016 2.2352)
			(end -1.016 -2.2352)
			(stroke
				(width 0.1524)
				(type default)
			)
			(layer "F.SilkS")
		)
		(fp_rect
			(start -1.0922 2.3114)
			(end 1.0922 -2.3114)
			(stroke
				(width 0)
				(type default)
			)
			(fill no)
			(layer "F.CrtYd")
		)
		(fp_poly
			(pts
				(xy -1.0922 -2.3114) (xy 1.0922 -2.3114) (xy 1.0922 2.3114) (xy -1.0922 2.3114)
			)
			(stroke
				(width 0)
				(type default)
			)
			(fill no)
			(layer "F.Fab")
		)
		(pad "1" smd rect
			(at 0 -1.397 90)
			(size 1.651 1.27)
			(layers "F.Cu" "F.Mask" "F.Paste")
			(net "P3V3")
		)
		(pad "2" smd rect
			(at 0 1.397 90)
			(size 1.651 1.27)
			(layers "F.Cu" "F.Mask" "F.Paste")
			(net "P3V3_OUT")
		)
	)
	(footprint ""
		(layer "F.Cu")
		(at 19.4945 -162.073336 180)
		(property "Reference" "R9869"
			(at 0 0 180)
			(layer "F.SilkS")
			(hide yes)
			(effects
				(font
					(size 1.27 1.27)
				)
			)
		)
		(property "Value" "0R2J-2-GP"
			(at 0.064008 -3.993896 180)
			(unlocked yes)
			(layer "F.Fab")
			(hide yes)
			(effects
				(font
					(size 1.016 1.016)
					(thickness 0.1524)
				)
			)
		)
		(property "Device Type" "R402H16"
			(at 0.064008 -5.517896 180)
			(unlocked yes)
			(layer "F.Fab")
			(hide yes)
			(effects
				(font
					(size 1.016 1.016)
					(thickness 0.1524)
				)
			)
		)
		(duplicate_pad_numbers_are_jumpers no)
		(fp_line
			(start 0.508 -0.9398)
			(end -0.508 -0.9398)
			(stroke
				(width 0.1524)
				(type default)
			)
			(layer "F.SilkS")
		)
		(fp_line
			(start -0.508 -0.9398)
			(end -0.508 0.9398)
			(stroke
				(width 0.1524)
				(type default)
			)
			(layer "F.SilkS")
		)
		(fp_rect
			(start -0.508 0.9398)
			(end 0.508 -0.9398)
			(stroke
				(width 0)
				(type default)
			)
			(fill no)
			(layer "F.CrtYd")
		)
		(fp_rect
			(start -0.508 0.9398)
			(end 0.508 -0.9398)
			(stroke
				(width 0)
				(type default)
			)
			(fill no)
			(layer "F.Fab")
		)
		(pad "1" smd custom
			(at 0 -0.4445 180)
			(size 0.1397 0.1397)
			(layers "F.Cu" "F.Mask" "F.Paste")
			(net "SSD_ACT_DR13_R")
			(options
				(clearance outline)
				(anchor circle)
			)
			(primitives
				(gr_poly
					(pts
						(arc
							(start -0.1778 -0.2794)
							(mid -0.249642 -0.249642)
							(end -0.2794 -0.1778)
						)
						(arc
							(start -0.2794 0.1778)
							(mid -0.249642 0.249642)
							(end -0.1778 0.2794)
						)
						(arc
							(start 0.1778 0.2794)
							(mid 0.249642 0.249642)
							(end 0.2794 0.1778)
						)
						(arc
							(start 0.2794 -0.1778)
							(mid 0.249642 -0.249642)
							(end 0.1778 -0.2794)
						)
					)
					(width 0)
					(fill yes)
				)
			)
		)
		(pad "2" smd custom
			(at 0 0.4445 180)
			(size 0.1397 0.1397)
			(layers "F.Cu" "F.Mask" "F.Paste")
			(net "SSD_ACT_DR13")
			(options
				(clearance outline)
				(anchor circle)
			)
			(primitives
				(gr_poly
					(pts
						(arc
							(start -0.1778 -0.2794)
							(mid -0.249642 -0.249642)
							(end -0.2794 -0.1778)
						)
						(arc
							(start -0.2794 0.1778)
							(mid -0.249642 0.249642)
							(end -0.1778 0.2794)
						)
						(arc
							(start 0.1778 0.2794)
							(mid 0.249642 0.249642)
							(end 0.2794 0.1778)
						)
						(arc
							(start 0.2794 -0.1778)
							(mid 0.249642 -0.249642)
							(end 0.1778 -0.2794)
						)
					)
					(width 0)
					(fill yes)
				)
			)
		)
	)
	(footprint ""
		(layer "F.Cu")
		(at 8.3439 -384.0988 180)
		(property "Reference" "C9537"
			(at 0 0 180)
			(layer "F.SilkS")
			(hide yes)
			(effects
				(font
					(size 1.27 1.27)
				)
			)
		)
		(property "Value" "SCD01U50V2KX-1GP"
			(at 1.1811 -2.7051 180)
			(unlocked yes)
			(layer "F.Fab")
			(hide yes)
			(effects
				(font
					(size 1.016 1.016)
					(thickness 0.1524)
				)
			)
		)
		(property "Device Type" "C402H22"
			(at 1.1811 -4.2291 180)
			(unlocked yes)
			(layer "F.Fab")
			(hide yes)
			(effects
				(font
					(size 1.016 1.016)
					(thickness 0.1524)
				)
			)
		)
		(duplicate_pad_numbers_are_jumpers no)
		(fp_rect
			(start -0.4318 0.9525)
			(end 0.4318 -0.9525)
			(stroke
				(width 0)
				(type default)
			)
			(fill no)
			(layer "F.CrtYd")
		)
		(fp_rect
			(start -0.4318 0.9525)
			(end 0.4318 -0.9525)
			(stroke
				(width 0)
				(type default)
			)
			(fill no)
			(layer "F.Fab")
		)
		(pad "1" smd custom
			(at 0 -0.4445 180)
			(size 0.1524 0.1524)
			(layers "F.Cu" "F.Mask" "F.Paste")
			(net "PE_100M_CLK2_N")
			(options
				(clearance outline)
				(anchor circle)
			)
			(primitives
				(gr_poly
					(pts
						(arc
							(start 0.3048 -0.2032)
							(mid 0.275042 -0.275042)
							(end 0.2032 -0.3048)
						)
						(arc
							(start -0.2032 -0.3048)
							(mid -0.275042 -0.275042)
							(end -0.3048 -0.2032)
						)
						(arc
							(start -0.3048 0.2032)
							(mid -0.275042 0.275042)
							(end -0.2032 0.3048)
						)
						(arc
							(start 0.2032 0.3048)
							(mid 0.275042 0.275042)
							(end 0.3048 0.2032)
						)
					)
					(width 0)
					(fill yes)
				)
			)
		)
		(pad "2" smd custom
			(at 0 0.4445 180)
			(size 0.1524 0.1524)
			(layers "F.Cu" "F.Mask" "F.Paste")
			(net "PE_100M_CLK2_C_N")
			(options
				(clearance outline)
				(anchor circle)
			)
			(primitives
				(gr_poly
					(pts
						(arc
							(start 0.3048 -0.2032)
							(mid 0.275042 -0.275042)
							(end 0.2032 -0.3048)
						)
						(arc
							(start -0.2032 -0.3048)
							(mid -0.275042 -0.275042)
							(end -0.3048 -0.2032)
						)
						(arc
							(start -0.3048 0.2032)
							(mid -0.275042 0.275042)
							(end -0.2032 0.3048)
						)
						(arc
							(start 0.2032 0.3048)
							(mid 0.275042 0.275042)
							(end 0.3048 0.2032)
						)
					)
					(width 0)
					(fill yes)
				)
			)
		)
	)
	(footprint ""
		(layer "F.Cu")
		(at 51.562 -134.493)
		(property "Reference" "R353"
			(at 0 0 0)
			(layer "F.SilkS")
			(hide yes)
			(effects
				(font
					(size 1.27 1.27)
				)
			)
		)
		(property "Value" "4K7R2F-GP"
			(at 0.064008 -3.993896 0)
			(unlocked yes)
			(layer "F.Fab")
			(hide yes)
			(effects
				(font
					(size 1.016 1.016)
					(thickness 0.1524)
				)
			)
		)
		(property "Device Type" "R402H16"
			(at 0.064008 -5.517896 0)
			(unlocked yes)
			(layer "F.Fab")
			(hide yes)
			(effects
				(font
					(size 1.016 1.016)
					(thickness 0.1524)
				)
			)
		)
		(duplicate_pad_numbers_are_jumpers no)
		(fp_line
			(start -0.508 -0.9398)
			(end -0.508 0.9398)
			(stroke
				(width 0.1524)
				(type default)
			)
			(layer "F.SilkS")
		)
		(fp_line
			(start 0.508 -0.9398)
			(end -0.508 -0.9398)
			(stroke
				(width 0.1524)
				(type default)
			)
			(layer "F.SilkS")
		)
		(fp_rect
			(start -0.508 0.9398)
			(end 0.508 -0.9398)
			(stroke
				(width 0)
				(type default)
			)
			(fill no)
			(layer "F.CrtYd")
		)
		(fp_rect
			(start -0.508 0.9398)
			(end 0.508 -0.9398)
			(stroke
				(width 0)
				(type default)
			)
			(fill no)
			(layer "F.Fab")
		)
		(pad "1" smd custom
			(at 0 -0.4445)
			(size 0.1397 0.1397)
			(layers "F.Cu" "F.Mask" "F.Paste")
			(net "P3V3")
			(options
				(clearance outline)
				(anchor circle)
			)
			(primitives
				(gr_poly
					(pts
						(arc
							(start -0.1778 -0.2794)
							(mid -0.249642 -0.249642)
							(end -0.2794 -0.1778)
						)
						(arc
							(start -0.2794 0.1778)
							(mid -0.249642 0.249642)
							(end -0.1778 0.2794)
						)
						(arc
							(start 0.1778 0.2794)
							(mid 0.249642 0.249642)
							(end 0.2794 0.1778)
						)
						(arc
							(start 0.2794 -0.1778)
							(mid 0.249642 -0.249642)
							(end 0.1778 -0.2794)
						)
					)
					(width 0)
					(fill yes)
				)
			)
		)
		(pad "2" smd custom
			(at 0 0.4445)
			(size 0.1397 0.1397)
			(layers "F.Cu" "F.Mask" "F.Paste")
			(net "I2C_B_TMP1_A2")
			(options
				(clearance outline)
				(anchor circle)
			)
			(primitives
				(gr_poly
					(pts
						(arc
							(start -0.1778 -0.2794)
							(mid -0.249642 -0.249642)
							(end -0.2794 -0.1778)
						)
						(arc
							(start -0.2794 0.1778)
							(mid -0.249642 0.249642)
							(end -0.1778 0.2794)
						)
						(arc
							(start 0.1778 0.2794)
							(mid 0.249642 0.249642)
							(end 0.2794 0.1778)
						)
						(arc
							(start 0.2794 -0.1778)
							(mid 0.249642 -0.249642)
							(end 0.1778 -0.2794)
						)
					)
					(width 0)
					(fill yes)
				)
			)
		)
	)
	(footprint ""
		(layer "F.Cu")
		(at 20.828 -62.353952 180)
		(property "Reference" "C9532"
			(at 0 0 180)
			(layer "F.SilkS")
			(hide yes)
			(effects
				(font
					(size 1.27 1.27)
				)
			)
		)
		(property "Value" "SCD1U16V2KX-3GP"
			(at 1.1811 -2.7051 180)
			(unlocked yes)
			(layer "F.Fab")
			(hide yes)
			(effects
				(font
					(size 1.016 1.016)
					(thickness 0.1524)
				)
			)
		)
		(property "Device Type" "C402H22"
			(at 1.1811 -4.2291 180)
			(unlocked yes)
			(layer "F.Fab")
			(hide yes)
			(effects
				(font
					(size 1.016 1.016)
					(thickness 0.1524)
				)
			)
		)
		(duplicate_pad_numbers_are_jumpers no)
		(fp_rect
			(start -0.4318 0.9525)
			(end 0.4318 -0.9525)
			(stroke
				(width 0)
				(type default)
			)
			(fill no)
			(layer "F.CrtYd")
		)
		(fp_rect
			(start -0.4318 0.9525)
			(end 0.4318 -0.9525)
			(stroke
				(width 0)
				(type default)
			)
			(fill no)
			(layer "F.Fab")
		)
		(pad "1" smd custom
			(at 0 -0.4445 180)
			(size 0.1524 0.1524)
			(layers "F.Cu" "F.Mask" "F.Paste")
			(net "P3V3")
			(options
				(clearance outline)
				(anchor circle)
			)
			(primitives
				(gr_poly
					(pts
						(arc
							(start 0.3048 -0.2032)
							(mid 0.275042 -0.275042)
							(end 0.2032 -0.3048)
						)
						(arc
							(start -0.2032 -0.3048)
							(mid -0.275042 -0.275042)
							(end -0.3048 -0.2032)
						)
						(arc
							(start -0.3048 0.2032)
							(mid -0.275042 0.275042)
							(end -0.2032 0.3048)
						)
						(arc
							(start 0.2032 0.3048)
							(mid 0.275042 0.275042)
							(end 0.3048 0.2032)
						)
					)
					(width 0)
					(fill yes)
				)
			)
		)
		(pad "2" smd custom
			(at 0 0.4445 180)
			(size 0.1524 0.1524)
			(layers "F.Cu" "F.Mask" "F.Paste")
			(net "GND")
			(options
				(clearance outline)
				(anchor circle)
			)
			(primitives
				(gr_poly
					(pts
						(arc
							(start 0.3048 -0.2032)
							(mid 0.275042 -0.275042)
							(end 0.2032 -0.3048)
						)
						(arc
							(start -0.2032 -0.3048)
							(mid -0.275042 -0.275042)
							(end -0.3048 -0.2032)
						)
						(arc
							(start -0.3048 0.2032)
							(mid -0.275042 0.275042)
							(end -0.2032 0.3048)
						)
						(arc
							(start 0.2032 0.3048)
							(mid 0.275042 0.275042)
							(end 0.3048 0.2032)
						)
					)
					(width 0)
					(fill yes)
				)
			)
		)
	)
	(footprint ""
		(layer "F.Cu")
		(at 227.203 -343.912952 90)
		(property "Reference" "U198"
			(at 0 0 90)
			(layer "F.SilkS")
			(hide yes)
			(effects
				(font
					(size 1.27 1.27)
				)
			)
		)
		(property "Value" "SN74LVC1G08DCKR-GP"
			(at -2.3368 -8.6868 90)
			(unlocked yes)
			(layer "F.Fab")
			(hide yes)
			(effects
				(font
					(size 1.016 1.016)
					(thickness 0.1524)
				)
			)
		)
		(property "Device Type" "SC70-5H44"
			(at -2.3114 -10.414 90)
			(unlocked yes)
			(layer "F.Fab")
			(hide yes)
			(effects
				(font
					(size 1.016 1.016)
					(thickness 0.1524)
				)
			)
		)
		(duplicate_pad_numbers_are_jumpers no)
		(fp_line
			(start 1.3843 -1.8034)
			(end 1.3843 -1.1176)
			(stroke
				(width 0.3302)
				(type default)
			)
			(layer "F.SilkS")
		)
		(fp_line
			(start 0.6604 -1.8034)
			(end 1.3843 -1.8034)
			(stroke
				(width 0.3302)
				(type default)
			)
			(layer "F.SilkS")
		)
		(fp_line
			(start 1.27 -1.7018)
			(end 1.27 1.7018)
			(stroke
				(width 0.1524)
				(type default)
			)
			(layer "F.SilkS")
		)
		(fp_line
			(start -1.27 -1.7018)
			(end 1.27 -1.7018)
			(stroke
				(width 0.1524)
				(type default)
			)
			(layer "F.SilkS")
		)
		(fp_line
			(start 1.27 1.7018)
			(end -1.27 1.7018)
			(stroke
				(width 0.1524)
				(type default)
			)
			(layer "F.SilkS")
		)
		(fp_line
			(start -1.27 1.7018)
			(end -1.27 -1.7018)
			(stroke
				(width 0.1524)
				(type default)
			)
			(layer "F.SilkS")
		)
		(fp_rect
			(start -1.524 1.9558)
			(end 1.524 -1.9558)
			(stroke
				(width 0)
				(type default)
			)
			(fill no)
			(layer "F.CrtYd")
		)
		(fp_poly
			(pts
				(xy -1.524 -1.9558) (xy 1.524 -1.9558) (xy 1.524 1.9558) (xy -1.524 1.9558)
			)
			(stroke
				(width 0)
				(type default)
			)
			(fill no)
			(layer "F.Fab")
		)
		(pad "1" smd rect
			(at 0.65024 -0.8255 90)
			(size 0.4064 1.2192)
			(layers "F.Cu" "F.Mask" "F.Paste")
			(net "SSD1_CLK0_OE_MOS_N")
		)
		(pad "2" smd rect
			(at 0 -0.8255 90)
			(size 0.4064 1.2192)
			(layers "F.Cu" "F.Mask" "F.Paste")
			(net "ATTN_LED_DR1_N")
		)
		(pad "3" smd rect
			(at -0.65024 -0.8255 90)
			(size 0.4064 1.2192)
			(layers "F.Cu" "F.Mask" "F.Paste")
			(net "GND")
		)
		(pad "4" smd rect
			(at -0.65024 0.8255 90)
			(size 0.4064 1.2192)
			(layers "F.Cu" "F.Mask" "F.Paste")
			(net "ATTN_LED_DR1_AND")
		)
		(pad "5" smd rect
			(at 0.65024 0.8255 90)
			(size 0.4064 1.2192)
			(layers "F.Cu" "F.Mask" "F.Paste")
			(net "P3V3")
		)
	)
	(footprint ""
		(layer "F.Cu")
		(at 70.739 -148.59 90)
		(property "Reference" "SR968"
			(at 0 0 90)
			(layer "F.SilkS")
			(hide yes)
			(effects
				(font
					(size 1.27 1.27)
				)
			)
		)
		(property "Value" "2KR2F-3-GP"
			(at 0.064008 -3.993896 90)
			(unlocked yes)
			(layer "F.Fab")
			(hide yes)
			(effects
				(font
					(size 1.016 1.016)
					(thickness 0.1524)
				)
			)
		)
		(property "Device Type" "R402H16"
			(at 0.064008 -5.517896 90)
			(unlocked yes)
			(layer "F.Fab")
			(hide yes)
			(effects
				(font
					(size 1.016 1.016)
					(thickness 0.1524)
				)
			)
		)
		(duplicate_pad_numbers_are_jumpers no)
		(fp_line
			(start 0.508 -0.9398)
			(end -0.508 -0.9398)
			(stroke
				(width 0.1524)
				(type default)
			)
			(layer "F.SilkS")
		)
		(fp_line
			(start -0.508 -0.9398)
			(end -0.508 0.9398)
			(stroke
				(width 0.1524)
				(type default)
			)
			(layer "F.SilkS")
		)
		(fp_rect
			(start -0.508 0.9398)
			(end 0.508 -0.9398)
			(stroke
				(width 0)
				(type default)
			)
			(fill no)
			(layer "F.CrtYd")
		)
		(fp_rect
			(start -0.508 0.9398)
			(end 0.508 -0.9398)
			(stroke
				(width 0)
				(type default)
			)
			(fill no)
			(layer "F.Fab")
		)
		(pad "1" smd custom
			(at 0 -0.4445 90)
			(size 0.1397 0.1397)
			(layers "F.Cu" "F.Mask" "F.Paste")
			(net "P3V3")
			(options
				(clearance outline)
				(anchor circle)
			)
			(primitives
				(gr_poly
					(pts
						(arc
							(start -0.1778 -0.2794)
							(mid -0.249642 -0.249642)
							(end -0.2794 -0.1778)
						)
						(arc
							(start -0.2794 0.1778)
							(mid -0.249642 0.249642)
							(end -0.1778 0.2794)
						)
						(arc
							(start 0.1778 0.2794)
							(mid 0.249642 0.249642)
							(end 0.2794 0.1778)
						)
						(arc
							(start 0.2794 -0.1778)
							(mid 0.249642 -0.249642)
							(end 0.1778 -0.2794)
						)
					)
					(width 0)
					(fill yes)
				)
			)
		)
		(pad "2" smd custom
			(at 0 0.4445 90)
			(size 0.1397 0.1397)
			(layers "F.Cu" "F.Mask" "F.Paste")
			(net "SDA_DR13")
			(options
				(clearance outline)
				(anchor circle)
			)
			(primitives
				(gr_poly
					(pts
						(arc
							(start -0.1778 -0.2794)
							(mid -0.249642 -0.249642)
							(end -0.2794 -0.1778)
						)
						(arc
							(start -0.2794 0.1778)
							(mid -0.249642 0.249642)
							(end -0.1778 0.2794)
						)
						(arc
							(start 0.1778 0.2794)
							(mid 0.249642 0.249642)
							(end 0.2794 0.1778)
						)
						(arc
							(start 0.2794 -0.1778)
							(mid 0.249642 -0.249642)
							(end 0.1778 -0.2794)
						)
					)
					(width 0)
					(fill yes)
				)
			)
		)
	)
	(footprint ""
		(layer "F.Cu")
		(at 96.774 -222.885 -90)
		(property "Reference" "C9369"
			(at 0 0 270)
			(layer "F.SilkS")
			(hide yes)
			(effects
				(font
					(size 1.27 1.27)
				)
			)
		)
		(property "Value" "SC1KP50V2KX-1GP"
			(at 1.1811 -2.7051 270)
			(unlocked yes)
			(layer "F.Fab")
			(hide yes)
			(effects
				(font
					(size 1.016 1.016)
					(thickness 0.1524)
				)
			)
		)
		(property "Device Type" "C402H22"
			(at 1.1811 -4.2291 270)
			(unlocked yes)
			(layer "F.Fab")
			(hide yes)
			(effects
				(font
					(size 1.016 1.016)
					(thickness 0.1524)
				)
			)
		)
		(duplicate_pad_numbers_are_jumpers no)
		(fp_rect
			(start -0.4318 0.9525)
			(end 0.4318 -0.9525)
			(stroke
				(width 0)
				(type default)
			)
			(fill no)
			(layer "F.CrtYd")
		)
		(fp_rect
			(start -0.4318 0.9525)
			(end 0.4318 -0.9525)
			(stroke
				(width 0)
				(type default)
			)
			(fill no)
			(layer "F.Fab")
		)
		(pad "1" smd custom
			(at 0 -0.4445 270)
			(size 0.1524 0.1524)
			(layers "F.Cu" "F.Mask" "F.Paste")
			(net "SSD7_CLK0_OE_R_N")
			(options
				(clearance outline)
				(anchor circle)
			)
			(primitives
				(gr_poly
					(pts
						(arc
							(start 0.3048 -0.2032)
							(mid 0.275042 -0.275042)
							(end 0.2032 -0.3048)
						)
						(arc
							(start -0.2032 -0.3048)
							(mid -0.275042 -0.275042)
							(end -0.3048 -0.2032)
						)
						(arc
							(start -0.3048 0.2032)
							(mid -0.275042 0.275042)
							(end -0.2032 0.3048)
						)
						(arc
							(start 0.2032 0.3048)
							(mid 0.275042 0.275042)
							(end 0.3048 0.2032)
						)
					)
					(width 0)
					(fill yes)
				)
			)
		)
		(pad "2" smd custom
			(at 0 0.4445 270)
			(size 0.1524 0.1524)
			(layers "F.Cu" "F.Mask" "F.Paste")
			(net "GND")
			(options
				(clearance outline)
				(anchor circle)
			)
			(primitives
				(gr_poly
					(pts
						(arc
							(start 0.3048 -0.2032)
							(mid 0.275042 -0.275042)
							(end 0.2032 -0.3048)
						)
						(arc
							(start -0.2032 -0.3048)
							(mid -0.275042 -0.275042)
							(end -0.3048 -0.2032)
						)
						(arc
							(start -0.3048 0.2032)
							(mid -0.275042 0.275042)
							(end -0.2032 0.3048)
						)
						(arc
							(start 0.2032 0.3048)
							(mid 0.275042 0.275042)
							(end 0.3048 0.2032)
						)
					)
					(width 0)
					(fill yes)
				)
			)
		)
	)
	(footprint ""
		(layer "F.Cu")
		(at 72.009 -454.66)
		(property "Reference" "R346"
			(at 0 0 0)
			(layer "F.SilkS")
			(hide yes)
			(effects
				(font
					(size 1.27 1.27)
				)
			)
		)
		(property "Value" "4K7R2F-GP"
			(at 0.064008 -3.993896 0)
			(unlocked yes)
			(layer "F.Fab")
			(hide yes)
			(effects
				(font
					(size 1.016 1.016)
					(thickness 0.1524)
				)
			)
		)
		(property "Device Type" "R402H16"
			(at 0.064008 -5.517896 0)
			(unlocked yes)
			(layer "F.Fab")
			(hide yes)
			(effects
				(font
					(size 1.016 1.016)
					(thickness 0.1524)
				)
			)
		)
		(duplicate_pad_numbers_are_jumpers no)
		(fp_line
			(start -0.508 -0.9398)
			(end -0.508 0.9398)
			(stroke
				(width 0.1524)
				(type default)
			)
			(layer "F.SilkS")
		)
		(fp_line
			(start 0.508 -0.9398)
			(end -0.508 -0.9398)
			(stroke
				(width 0.1524)
				(type default)
			)
			(layer "F.SilkS")
		)
		(fp_rect
			(start -0.508 0.9398)
			(end 0.508 -0.9398)
			(stroke
				(width 0)
				(type default)
			)
			(fill no)
			(layer "F.CrtYd")
		)
		(fp_rect
			(start -0.508 0.9398)
			(end 0.508 -0.9398)
			(stroke
				(width 0)
				(type default)
			)
			(fill no)
			(layer "F.Fab")
		)
		(pad "1" smd custom
			(at 0 -0.4445)
			(size 0.1397 0.1397)
			(layers "F.Cu" "F.Mask" "F.Paste")
			(net "P3V3")
			(options
				(clearance outline)
				(anchor circle)
			)
			(primitives
				(gr_poly
					(pts
						(arc
							(start -0.1778 -0.2794)
							(mid -0.249642 -0.249642)
							(end -0.2794 -0.1778)
						)
						(arc
							(start -0.2794 0.1778)
							(mid -0.249642 0.249642)
							(end -0.1778 0.2794)
						)
						(arc
							(start 0.1778 0.2794)
							(mid 0.249642 0.249642)
							(end 0.2794 0.1778)
						)
						(arc
							(start 0.2794 -0.1778)
							(mid 0.249642 -0.249642)
							(end 0.1778 -0.2794)
						)
					)
					(width 0)
					(fill yes)
				)
			)
		)
		(pad "2" smd custom
			(at 0 0.4445)
			(size 0.1397 0.1397)
			(layers "F.Cu" "F.Mask" "F.Paste")
			(net "EEPROM_A1")
			(options
				(clearance outline)
				(anchor circle)
			)
			(primitives
				(gr_poly
					(pts
						(arc
							(start -0.1778 -0.2794)
							(mid -0.249642 -0.249642)
							(end -0.2794 -0.1778)
						)
						(arc
							(start -0.2794 0.1778)
							(mid -0.249642 0.249642)
							(end -0.1778 0.2794)
						)
						(arc
							(start 0.1778 0.2794)
							(mid 0.249642 0.249642)
							(end 0.2794 0.1778)
						)
						(arc
							(start 0.2794 -0.1778)
							(mid 0.249642 -0.249642)
							(end 0.1778 -0.2794)
						)
					)
					(width 0)
					(fill yes)
				)
			)
		)
	)
	(footprint ""
		(layer "F.Cu")
		(at 29.03093 -84.662518)
		(property "Reference" "SR1109"
			(at 0 0 0)
			(layer "F.SilkS")
			(hide yes)
			(effects
				(font
					(size 1.27 1.27)
				)
			)
		)
		(property "Value" "4K7R2F-GP"
			(at 0.064008 -3.993896 0)
			(unlocked yes)
			(layer "F.Fab")
			(hide yes)
			(effects
				(font
					(size 1.016 1.016)
					(thickness 0.1524)
				)
			)
		)
		(property "Device Type" "R402H16"
			(at 0.064008 -5.517896 0)
			(unlocked yes)
			(layer "F.Fab")
			(hide yes)
			(effects
				(font
					(size 1.016 1.016)
					(thickness 0.1524)
				)
			)
		)
		(duplicate_pad_numbers_are_jumpers no)
		(fp_line
			(start -0.508 -0.9398)
			(end -0.508 0.9398)
			(stroke
				(width 0.1524)
				(type default)
			)
			(layer "F.SilkS")
		)
		(fp_line
			(start 0.508 -0.9398)
			(end -0.508 -0.9398)
			(stroke
				(width 0.1524)
				(type default)
			)
			(layer "F.SilkS")
		)
		(fp_rect
			(start -0.508 0.9398)
			(end 0.508 -0.9398)
			(stroke
				(width 0)
				(type default)
			)
			(fill no)
			(layer "F.CrtYd")
		)
		(fp_rect
			(start -0.508 0.9398)
			(end 0.508 -0.9398)
			(stroke
				(width 0)
				(type default)
			)
			(fill no)
			(layer "F.Fab")
		)
		(pad "1" smd custom
			(at 0 -0.4445)
			(size 0.1397 0.1397)
			(layers "F.Cu" "F.Mask" "F.Paste")
			(net "P3V3")
			(options
				(clearance outline)
				(anchor circle)
			)
			(primitives
				(gr_poly
					(pts
						(arc
							(start -0.1778 -0.2794)
							(mid -0.249642 -0.249642)
							(end -0.2794 -0.1778)
						)
						(arc
							(start -0.2794 0.1778)
							(mid -0.249642 0.249642)
							(end -0.1778 0.2794)
						)
						(arc
							(start 0.1778 0.2794)
							(mid 0.249642 0.249642)
							(end 0.2794 0.1778)
						)
						(arc
							(start 0.2794 -0.1778)
							(mid 0.249642 -0.249642)
							(end 0.1778 -0.2794)
						)
					)
					(width 0)
					(fill yes)
				)
			)
		)
		(pad "2" smd custom
			(at 0 0.4445)
			(size 0.1397 0.1397)
			(layers "F.Cu" "F.Mask" "F.Paste")
			(net "DUALPORTEN#9")
			(options
				(clearance outline)
				(anchor circle)
			)
			(primitives
				(gr_poly
					(pts
						(arc
							(start -0.1778 -0.2794)
							(mid -0.249642 -0.249642)
							(end -0.2794 -0.1778)
						)
						(arc
							(start -0.2794 0.1778)
							(mid -0.249642 0.249642)
							(end -0.1778 0.2794)
						)
						(arc
							(start 0.1778 0.2794)
							(mid 0.249642 0.249642)
							(end 0.2794 0.1778)
						)
						(arc
							(start 0.2794 -0.1778)
							(mid 0.249642 -0.249642)
							(end 0.1778 -0.2794)
						)
					)
					(width 0)
					(fill yes)
				)
			)
		)
	)
	(footprint ""
		(layer "F.Cu")
		(at 31.9278 -12.5984)
		(property "Reference" "SR1119"
			(at 0 0 0)
			(layer "F.SilkS")
			(hide yes)
			(effects
				(font
					(size 1.27 1.27)
				)
			)
		)
		(property "Value" "4K7R2F-GP"
			(at 0.064008 -3.993896 0)
			(unlocked yes)
			(layer "F.Fab")
			(hide yes)
			(effects
				(font
					(size 1.016 1.016)
					(thickness 0.1524)
				)
			)
		)
		(property "Device Type" "R402H16"
			(at 0.064008 -5.517896 0)
			(unlocked yes)
			(layer "F.Fab")
			(hide yes)
			(effects
				(font
					(size 1.016 1.016)
					(thickness 0.1524)
				)
			)
		)
		(duplicate_pad_numbers_are_jumpers no)
		(fp_line
			(start -0.508 -0.9398)
			(end -0.508 0.9398)
			(stroke
				(width 0.1524)
				(type default)
			)
			(layer "F.SilkS")
		)
		(fp_line
			(start 0.508 -0.9398)
			(end -0.508 -0.9398)
			(stroke
				(width 0.1524)
				(type default)
			)
			(layer "F.SilkS")
		)
		(fp_rect
			(start -0.508 0.9398)
			(end 0.508 -0.9398)
			(stroke
				(width 0)
				(type default)
			)
			(fill no)
			(layer "F.CrtYd")
		)
		(fp_rect
			(start -0.508 0.9398)
			(end 0.508 -0.9398)
			(stroke
				(width 0)
				(type default)
			)
			(fill no)
			(layer "F.Fab")
		)
		(pad "1" smd custom
			(at 0 -0.4445)
			(size 0.1397 0.1397)
			(layers "F.Cu" "F.Mask" "F.Paste")
			(net "P3V3")
			(options
				(clearance outline)
				(anchor circle)
			)
			(primitives
				(gr_poly
					(pts
						(arc
							(start -0.1778 -0.2794)
							(mid -0.249642 -0.249642)
							(end -0.2794 -0.1778)
						)
						(arc
							(start -0.2794 0.1778)
							(mid -0.249642 0.249642)
							(end -0.1778 0.2794)
						)
						(arc
							(start 0.1778 0.2794)
							(mid 0.249642 0.249642)
							(end 0.2794 0.1778)
						)
						(arc
							(start 0.2794 -0.1778)
							(mid 0.249642 -0.249642)
							(end 0.1778 -0.2794)
						)
					)
					(width 0)
					(fill yes)
				)
			)
		)
		(pad "2" smd custom
			(at 0 0.4445)
			(size 0.1397 0.1397)
			(layers "F.Cu" "F.Mask" "F.Paste")
			(net "DUALPORTEN#14")
			(options
				(clearance outline)
				(anchor circle)
			)
			(primitives
				(gr_poly
					(pts
						(arc
							(start -0.1778 -0.2794)
							(mid -0.249642 -0.249642)
							(end -0.2794 -0.1778)
						)
						(arc
							(start -0.2794 0.1778)
							(mid -0.249642 0.249642)
							(end -0.1778 0.2794)
						)
						(arc
							(start 0.1778 0.2794)
							(mid 0.249642 0.249642)
							(end 0.2794 0.1778)
						)
						(arc
							(start 0.2794 -0.1778)
							(mid 0.249642 -0.249642)
							(end 0.1778 -0.2794)
						)
					)
					(width 0)
					(fill yes)
				)
			)
		)
	)
	(footprint ""
		(layer "F.Cu")
		(at 28.8671 -197.5231 180)
		(property "Reference" "R9834"
			(at 0 0 180)
			(layer "F.SilkS")
			(hide yes)
			(effects
				(font
					(size 1.27 1.27)
				)
			)
		)
		(property "Value" "47KR2J-2-GP"
			(at 0.064008 -3.993896 180)
			(unlocked yes)
			(layer "F.Fab")
			(hide yes)
			(effects
				(font
					(size 1.016 1.016)
					(thickness 0.1524)
				)
			)
		)
		(property "Device Type" "R402H16"
			(at 0.064008 -5.517896 180)
			(unlocked yes)
			(layer "F.Fab")
			(hide yes)
			(effects
				(font
					(size 1.016 1.016)
					(thickness 0.1524)
				)
			)
		)
		(duplicate_pad_numbers_are_jumpers no)
		(fp_line
			(start 0.508 -0.9398)
			(end -0.508 -0.9398)
			(stroke
				(width 0.1524)
				(type default)
			)
			(layer "F.SilkS")
		)
		(fp_line
			(start -0.508 -0.9398)
			(end -0.508 0.9398)
			(stroke
				(width 0.1524)
				(type default)
			)
			(layer "F.SilkS")
		)
		(fp_rect
			(start -0.508 0.9398)
			(end 0.508 -0.9398)
			(stroke
				(width 0)
				(type default)
			)
			(fill no)
			(layer "F.CrtYd")
		)
		(fp_rect
			(start -0.508 0.9398)
			(end 0.508 -0.9398)
			(stroke
				(width 0)
				(type default)
			)
			(fill no)
			(layer "F.Fab")
		)
		(pad "1" smd custom
			(at 0 -0.4445 180)
			(size 0.1397 0.1397)
			(layers "F.Cu" "F.Mask" "F.Paste")
			(net "P12V")
			(options
				(clearance outline)
				(anchor circle)
			)
			(primitives
				(gr_poly
					(pts
						(arc
							(start -0.1778 -0.2794)
							(mid -0.249642 -0.249642)
							(end -0.2794 -0.1778)
						)
						(arc
							(start -0.2794 0.1778)
							(mid -0.249642 0.249642)
							(end -0.1778 0.2794)
						)
						(arc
							(start 0.1778 0.2794)
							(mid 0.249642 0.249642)
							(end 0.2794 0.1778)
						)
						(arc
							(start 0.2794 -0.1778)
							(mid 0.249642 -0.249642)
							(end 0.1778 -0.2794)
						)
					)
					(width 0)
					(fill yes)
				)
			)
		)
		(pad "2" smd custom
			(at 0 0.4445 180)
			(size 0.1397 0.1397)
			(layers "F.Cu" "F.Mask" "F.Paste")
			(net "P12V_MOST8_GATE")
			(options
				(clearance outline)
				(anchor circle)
			)
			(primitives
				(gr_poly
					(pts
						(arc
							(start -0.1778 -0.2794)
							(mid -0.249642 -0.249642)
							(end -0.2794 -0.1778)
						)
						(arc
							(start -0.2794 0.1778)
							(mid -0.249642 0.249642)
							(end -0.1778 0.2794)
						)
						(arc
							(start 0.1778 0.2794)
							(mid 0.249642 0.249642)
							(end 0.2794 0.1778)
						)
						(arc
							(start 0.2794 -0.1778)
							(mid 0.249642 -0.249642)
							(end 0.1778 -0.2794)
						)
					)
					(width 0)
					(fill yes)
				)
			)
		)
	)
	(footprint ""
		(layer "F.Cu")
		(at 226.187 -439.166 180)
		(property "Reference" "PR97"
			(at 0 0 180)
			(layer "F.SilkS")
			(hide yes)
			(effects
				(font
					(size 1.27 1.27)
				)
			)
		)
		(property "Value" "10KR2F-2-GP"
			(at 0.064008 -3.993896 180)
			(unlocked yes)
			(layer "F.Fab")
			(hide yes)
			(effects
				(font
					(size 1.016 1.016)
					(thickness 0.1524)
				)
			)
		)
		(property "Device Type" "R402H16"
			(at 0.064008 -5.517896 180)
			(unlocked yes)
			(layer "F.Fab")
			(hide yes)
			(effects
				(font
					(size 1.016 1.016)
					(thickness 0.1524)
				)
			)
		)
		(duplicate_pad_numbers_are_jumpers no)
		(fp_line
			(start 0.508 -0.9398)
			(end -0.508 -0.9398)
			(stroke
				(width 0.1524)
				(type default)
			)
			(layer "F.SilkS")
		)
		(fp_line
			(start -0.508 -0.9398)
			(end -0.508 0.9398)
			(stroke
				(width 0.1524)
				(type default)
			)
			(layer "F.SilkS")
		)
		(fp_rect
			(start -0.508 0.9398)
			(end 0.508 -0.9398)
			(stroke
				(width 0)
				(type default)
			)
			(fill no)
			(layer "F.CrtYd")
		)
		(fp_rect
			(start -0.508 0.9398)
			(end 0.508 -0.9398)
			(stroke
				(width 0)
				(type default)
			)
			(fill no)
			(layer "F.Fab")
		)
		(pad "1" smd custom
			(at 0 -0.4445 180)
			(size 0.1397 0.1397)
			(layers "F.Cu" "F.Mask" "F.Paste")
			(net "P3V3_EN_R")
			(options
				(clearance outline)
				(anchor circle)
			)
			(primitives
				(gr_poly
					(pts
						(arc
							(start -0.1778 -0.2794)
							(mid -0.249642 -0.249642)
							(end -0.2794 -0.1778)
						)
						(arc
							(start -0.2794 0.1778)
							(mid -0.249642 0.249642)
							(end -0.1778 0.2794)
						)
						(arc
							(start 0.1778 0.2794)
							(mid 0.249642 0.249642)
							(end 0.2794 0.1778)
						)
						(arc
							(start 0.2794 -0.1778)
							(mid 0.249642 -0.249642)
							(end 0.1778 -0.2794)
						)
					)
					(width 0)
					(fill yes)
				)
			)
		)
		(pad "2" smd custom
			(at 0 0.4445 180)
			(size 0.1397 0.1397)
			(layers "F.Cu" "F.Mask" "F.Paste")
			(net "AGND_P3V3")
			(options
				(clearance outline)
				(anchor circle)
			)
			(primitives
				(gr_poly
					(pts
						(arc
							(start -0.1778 -0.2794)
							(mid -0.249642 -0.249642)
							(end -0.2794 -0.1778)
						)
						(arc
							(start -0.2794 0.1778)
							(mid -0.249642 0.249642)
							(end -0.1778 0.2794)
						)
						(arc
							(start 0.1778 0.2794)
							(mid 0.249642 0.249642)
							(end 0.2794 0.1778)
						)
						(arc
							(start 0.2794 -0.1778)
							(mid 0.249642 -0.249642)
							(end 0.1778 -0.2794)
						)
					)
					(width 0)
					(fill yes)
				)
			)
		)
	)
	(footprint ""
		(layer "F.Cu")
		(at 82.931 -437.134 90)
		(property "Reference" "SR945"
			(at 0 0 90)
			(layer "F.SilkS")
			(hide yes)
			(effects
				(font
					(size 1.27 1.27)
				)
			)
		)
		(property "Value" "4K7R2F-GP"
			(at 0.064008 -3.993896 90)
			(unlocked yes)
			(layer "F.Fab")
			(hide yes)
			(effects
				(font
					(size 1.016 1.016)
					(thickness 0.1524)
				)
			)
		)
		(property "Device Type" "R402H16"
			(at 0.064008 -5.517896 90)
			(unlocked yes)
			(layer "F.Fab")
			(hide yes)
			(effects
				(font
					(size 1.016 1.016)
					(thickness 0.1524)
				)
			)
		)
		(duplicate_pad_numbers_are_jumpers no)
		(fp_line
			(start 0.508 -0.9398)
			(end -0.508 -0.9398)
			(stroke
				(width 0.1524)
				(type default)
			)
			(layer "F.SilkS")
		)
		(fp_line
			(start -0.508 -0.9398)
			(end -0.508 0.9398)
			(stroke
				(width 0.1524)
				(type default)
			)
			(layer "F.SilkS")
		)
		(fp_rect
			(start -0.508 0.9398)
			(end 0.508 -0.9398)
			(stroke
				(width 0)
				(type default)
			)
			(fill no)
			(layer "F.CrtYd")
		)
		(fp_rect
			(start -0.508 0.9398)
			(end 0.508 -0.9398)
			(stroke
				(width 0)
				(type default)
			)
			(fill no)
			(layer "F.Fab")
		)
		(pad "1" smd custom
			(at 0 -0.4445 90)
			(size 0.1397 0.1397)
			(layers "F.Cu" "F.Mask" "F.Paste")
			(net "VDD_DIFF_1")
			(options
				(clearance outline)
				(anchor circle)
			)
			(primitives
				(gr_poly
					(pts
						(arc
							(start -0.1778 -0.2794)
							(mid -0.249642 -0.249642)
							(end -0.2794 -0.1778)
						)
						(arc
							(start -0.2794 0.1778)
							(mid -0.249642 0.249642)
							(end -0.1778 0.2794)
						)
						(arc
							(start 0.1778 0.2794)
							(mid 0.249642 0.249642)
							(end 0.2794 0.1778)
						)
						(arc
							(start 0.2794 -0.1778)
							(mid 0.249642 -0.249642)
							(end 0.1778 -0.2794)
						)
					)
					(width 0)
					(fill yes)
				)
			)
		)
		(pad "2" smd custom
			(at 0 0.4445 90)
			(size 0.1397 0.1397)
			(layers "F.Cu" "F.Mask" "F.Paste")
			(net "CLK_BUF_EU1_100M_133M#")
			(options
				(clearance outline)
				(anchor circle)
			)
			(primitives
				(gr_poly
					(pts
						(arc
							(start -0.1778 -0.2794)
							(mid -0.249642 -0.249642)
							(end -0.2794 -0.1778)
						)
						(arc
							(start -0.2794 0.1778)
							(mid -0.249642 0.249642)
							(end -0.1778 0.2794)
						)
						(arc
							(start 0.1778 0.2794)
							(mid 0.249642 0.249642)
							(end 0.2794 0.1778)
						)
						(arc
							(start 0.2794 -0.1778)
							(mid 0.249642 -0.249642)
							(end 0.1778 -0.2794)
						)
					)
					(width 0)
					(fill yes)
				)
			)
		)
	)
	(footprint ""
		(layer "F.Cu")
		(at 24.9936 -317.0936 180)
		(property "Reference" "PC1223"
			(at 0 0 180)
			(layer "F.SilkS")
			(hide yes)
			(effects
				(font
					(size 1.27 1.27)
				)
			)
		)
		(property "Value" "SCD01U50V2KX-1GP"
			(at 1.1811 -2.7051 180)
			(unlocked yes)
			(layer "F.Fab")
			(hide yes)
			(effects
				(font
					(size 1.016 1.016)
					(thickness 0.1524)
				)
			)
		)
		(property "Device Type" "C402H22"
			(at 1.1811 -4.2291 180)
			(unlocked yes)
			(layer "F.Fab")
			(hide yes)
			(effects
				(font
					(size 1.016 1.016)
					(thickness 0.1524)
				)
			)
		)
		(duplicate_pad_numbers_are_jumpers no)
		(fp_rect
			(start -0.4318 0.9525)
			(end 0.4318 -0.9525)
			(stroke
				(width 0)
				(type default)
			)
			(fill no)
			(layer "F.CrtYd")
		)
		(fp_rect
			(start -0.4318 0.9525)
			(end 0.4318 -0.9525)
			(stroke
				(width 0)
				(type default)
			)
			(fill no)
			(layer "F.Fab")
		)
		(pad "1" smd custom
			(at 0 -0.4445 180)
			(size 0.1524 0.1524)
			(layers "F.Cu" "F.Mask" "F.Paste")
			(net "P12V_SSD11")
			(options
				(clearance outline)
				(anchor circle)
			)
			(primitives
				(gr_poly
					(pts
						(arc
							(start 0.3048 -0.2032)
							(mid 0.275042 -0.275042)
							(end 0.2032 -0.3048)
						)
						(arc
							(start -0.2032 -0.3048)
							(mid -0.275042 -0.275042)
							(end -0.3048 -0.2032)
						)
						(arc
							(start -0.3048 0.2032)
							(mid -0.275042 0.275042)
							(end -0.2032 0.3048)
						)
						(arc
							(start 0.2032 0.3048)
							(mid 0.275042 0.275042)
							(end 0.3048 0.2032)
						)
					)
					(width 0)
					(fill yes)
				)
			)
		)
		(pad "2" smd custom
			(at 0 0.4445 180)
			(size 0.1524 0.1524)
			(layers "F.Cu" "F.Mask" "F.Paste")
			(net "GND")
			(options
				(clearance outline)
				(anchor circle)
			)
			(primitives
				(gr_poly
					(pts
						(arc
							(start 0.3048 -0.2032)
							(mid 0.275042 -0.275042)
							(end 0.2032 -0.3048)
						)
						(arc
							(start -0.2032 -0.3048)
							(mid -0.275042 -0.275042)
							(end -0.3048 -0.2032)
						)
						(arc
							(start -0.3048 0.2032)
							(mid -0.275042 0.275042)
							(end -0.2032 0.3048)
						)
						(arc
							(start 0.2032 0.3048)
							(mid 0.275042 0.275042)
							(end 0.3048 0.2032)
						)
					)
					(width 0)
					(fill yes)
				)
			)
		)
	)
	(footprint ""
		(layer "F.Cu")
		(at 245.491 -421.894 -90)
		(property "Reference" "C355"
			(at 0 0 270)
			(layer "F.SilkS")
			(hide yes)
			(effects
				(font
					(size 1.27 1.27)
				)
			)
		)
		(property "Value" "SC220P50V3JN-GP"
			(at 0 -2.8194 270)
			(unlocked yes)
			(layer "F.Fab")
			(hide yes)
			(effects
				(font
					(size 1.016 1.016)
					(thickness 0.1524)
				)
			)
		)
		(property "Device Type" "C603H36"
			(at 0 -4.3434 270)
			(unlocked yes)
			(layer "F.Fab")
			(hide yes)
			(effects
				(font
					(size 1.016 1.016)
					(thickness 0.1524)
				)
			)
		)
		(duplicate_pad_numbers_are_jumpers no)
		(fp_line
			(start 0.508 0)
			(end -0.508 0)
			(stroke
				(width 0.2032)
				(type default)
			)
			(layer "F.SilkS")
		)
		(fp_rect
			(start -0.5842 1.3335)
			(end 0.5842 -1.3335)
			(stroke
				(width 0)
				(type default)
			)
			(fill no)
			(layer "F.CrtYd")
		)
		(fp_rect
			(start -0.5842 1.3335)
			(end 0.5842 -1.3335)
			(stroke
				(width 0)
				(type default)
			)
			(fill no)
			(layer "F.Fab")
		)
		(pad "1" smd custom
			(at 0 -0.762 270)
			(size 0.2159 0.2159)
			(layers "F.Cu" "F.Mask" "F.Paste")
			(net "I2C_C_SDA")
			(options
				(clearance outline)
				(anchor circle)
			)
			(primitives
				(gr_poly
					(pts
						(arc
							(start -0.3302 -0.4318)
							(mid -0.402042 -0.402042)
							(end -0.4318 -0.3302)
						)
						(arc
							(start -0.4318 0.3302)
							(mid -0.402042 0.402042)
							(end -0.3302 0.4318)
						)
						(arc
							(start 0.3302 0.4318)
							(mid 0.402042 0.402042)
							(end 0.4318 0.3302)
						)
						(arc
							(start 0.4318 -0.3302)
							(mid 0.402042 -0.402042)
							(end 0.3302 -0.4318)
						)
					)
					(width 0)
					(fill yes)
				)
			)
		)
		(pad "2" smd custom
			(at 0 0.762 270)
			(size 0.2159 0.2159)
			(layers "F.Cu" "F.Mask" "F.Paste")
			(net "GND")
			(options
				(clearance outline)
				(anchor circle)
			)
			(primitives
				(gr_poly
					(pts
						(arc
							(start -0.3302 -0.4318)
							(mid -0.402042 -0.402042)
							(end -0.4318 -0.3302)
						)
						(arc
							(start -0.4318 0.3302)
							(mid -0.402042 0.402042)
							(end -0.3302 0.4318)
						)
						(arc
							(start 0.3302 0.4318)
							(mid 0.402042 0.402042)
							(end 0.4318 0.3302)
						)
						(arc
							(start 0.4318 -0.3302)
							(mid 0.402042 -0.402042)
							(end 0.3302 -0.4318)
						)
					)
					(width 0)
					(fill yes)
				)
			)
		)
	)
	(footprint ""
		(layer "F.Cu")
		(at 87.503 -432.943 180)
		(property "Reference" "C8896"
			(at 0 0 180)
			(layer "F.SilkS")
			(hide yes)
			(effects
				(font
					(size 1.27 1.27)
				)
			)
		)
		(property "Value" "SCD1U16V2KX-3GP"
			(at 1.1811 -2.7051 180)
			(unlocked yes)
			(layer "F.Fab")
			(hide yes)
			(effects
				(font
					(size 1.016 1.016)
					(thickness 0.1524)
				)
			)
		)
		(property "Device Type" "C402H22"
			(at 1.1811 -4.2291 180)
			(unlocked yes)
			(layer "F.Fab")
			(hide yes)
			(effects
				(font
					(size 1.016 1.016)
					(thickness 0.1524)
				)
			)
		)
		(duplicate_pad_numbers_are_jumpers no)
		(fp_rect
			(start -0.4318 0.9525)
			(end 0.4318 -0.9525)
			(stroke
				(width 0)
				(type default)
			)
			(fill no)
			(layer "F.CrtYd")
		)
		(fp_rect
			(start -0.4318 0.9525)
			(end 0.4318 -0.9525)
			(stroke
				(width 0)
				(type default)
			)
			(fill no)
			(layer "F.Fab")
		)
		(pad "1" smd custom
			(at 0 -0.4445 180)
			(size 0.1524 0.1524)
			(layers "F.Cu" "F.Mask" "F.Paste")
			(net "VDDR_1")
			(options
				(clearance outline)
				(anchor circle)
			)
			(primitives
				(gr_poly
					(pts
						(arc
							(start 0.3048 -0.2032)
							(mid 0.275042 -0.275042)
							(end 0.2032 -0.3048)
						)
						(arc
							(start -0.2032 -0.3048)
							(mid -0.275042 -0.275042)
							(end -0.3048 -0.2032)
						)
						(arc
							(start -0.3048 0.2032)
							(mid -0.275042 0.275042)
							(end -0.2032 0.3048)
						)
						(arc
							(start 0.2032 0.3048)
							(mid 0.275042 0.275042)
							(end 0.3048 0.2032)
						)
					)
					(width 0)
					(fill yes)
				)
			)
		)
		(pad "2" smd custom
			(at 0 0.4445 180)
			(size 0.1524 0.1524)
			(layers "F.Cu" "F.Mask" "F.Paste")
			(net "GND")
			(options
				(clearance outline)
				(anchor circle)
			)
			(primitives
				(gr_poly
					(pts
						(arc
							(start 0.3048 -0.2032)
							(mid 0.275042 -0.275042)
							(end 0.2032 -0.3048)
						)
						(arc
							(start -0.2032 -0.3048)
							(mid -0.275042 -0.275042)
							(end -0.3048 -0.2032)
						)
						(arc
							(start -0.3048 0.2032)
							(mid -0.275042 0.275042)
							(end -0.2032 0.3048)
						)
						(arc
							(start 0.2032 0.3048)
							(mid 0.275042 0.275042)
							(end 0.3048 0.2032)
						)
					)
					(width 0)
					(fill yes)
				)
			)
		)
	)
	(footprint ""
		(layer "F.Cu")
		(at 208.026 -454.66)
		(property "Reference" "R325"
			(at 0 0 0)
			(layer "F.SilkS")
			(hide yes)
			(effects
				(font
					(size 1.27 1.27)
				)
			)
		)
		(property "Value" "4K7R2J-2-GP"
			(at 0.064008 -3.993896 0)
			(unlocked yes)
			(layer "F.Fab")
			(hide yes)
			(effects
				(font
					(size 1.016 1.016)
					(thickness 0.1524)
				)
			)
		)
		(property "Device Type" "R402H16"
			(at 0.064008 -5.517896 0)
			(unlocked yes)
			(layer "F.Fab")
			(hide yes)
			(effects
				(font
					(size 1.016 1.016)
					(thickness 0.1524)
				)
			)
		)
		(duplicate_pad_numbers_are_jumpers no)
		(fp_line
			(start -0.508 -0.9398)
			(end -0.508 0.9398)
			(stroke
				(width 0.1524)
				(type default)
			)
			(layer "F.SilkS")
		)
		(fp_line
			(start 0.508 -0.9398)
			(end -0.508 -0.9398)
			(stroke
				(width 0.1524)
				(type default)
			)
			(layer "F.SilkS")
		)
		(fp_rect
			(start -0.508 0.9398)
			(end 0.508 -0.9398)
			(stroke
				(width 0)
				(type default)
			)
			(fill no)
			(layer "F.CrtYd")
		)
		(fp_rect
			(start -0.508 0.9398)
			(end 0.508 -0.9398)
			(stroke
				(width 0)
				(type default)
			)
			(fill no)
			(layer "F.Fab")
		)
		(pad "1" smd custom
			(at 0 -0.4445)
			(size 0.1397 0.1397)
			(layers "F.Cu" "F.Mask" "F.Paste")
			(net "I2C_B_TMP2_A0")
			(options
				(clearance outline)
				(anchor circle)
			)
			(primitives
				(gr_poly
					(pts
						(arc
							(start -0.1778 -0.2794)
							(mid -0.249642 -0.249642)
							(end -0.2794 -0.1778)
						)
						(arc
							(start -0.2794 0.1778)
							(mid -0.249642 0.249642)
							(end -0.1778 0.2794)
						)
						(arc
							(start 0.1778 0.2794)
							(mid 0.249642 0.249642)
							(end 0.2794 0.1778)
						)
						(arc
							(start 0.2794 -0.1778)
							(mid 0.249642 -0.249642)
							(end 0.1778 -0.2794)
						)
					)
					(width 0)
					(fill yes)
				)
			)
		)
		(pad "2" smd custom
			(at 0 0.4445)
			(size 0.1397 0.1397)
			(layers "F.Cu" "F.Mask" "F.Paste")
			(net "GND")
			(options
				(clearance outline)
				(anchor circle)
			)
			(primitives
				(gr_poly
					(pts
						(arc
							(start -0.1778 -0.2794)
							(mid -0.249642 -0.249642)
							(end -0.2794 -0.1778)
						)
						(arc
							(start -0.2794 0.1778)
							(mid -0.249642 0.249642)
							(end -0.1778 0.2794)
						)
						(arc
							(start 0.1778 0.2794)
							(mid 0.249642 0.249642)
							(end 0.2794 0.1778)
						)
						(arc
							(start 0.2794 -0.1778)
							(mid 0.249642 -0.249642)
							(end 0.1778 -0.2794)
						)
					)
					(width 0)
					(fill yes)
				)
			)
		)
	)
	(footprint ""
		(layer "F.Cu")
		(at 89.789 -320.167 90)
		(property "Reference" "R9437"
			(at 0 0 90)
			(layer "F.SilkS")
			(hide yes)
			(effects
				(font
					(size 1.27 1.27)
				)
			)
		)
		(property "Value" "4K7R2J-2-GP"
			(at 0.064008 -3.993896 90)
			(unlocked yes)
			(layer "F.Fab")
			(hide yes)
			(effects
				(font
					(size 1.016 1.016)
					(thickness 0.1524)
				)
			)
		)
		(property "Device Type" "R402H16"
			(at 0.064008 -5.517896 90)
			(unlocked yes)
			(layer "F.Fab")
			(hide yes)
			(effects
				(font
					(size 1.016 1.016)
					(thickness 0.1524)
				)
			)
		)
		(duplicate_pad_numbers_are_jumpers no)
		(fp_line
			(start 0.508 -0.9398)
			(end -0.508 -0.9398)
			(stroke
				(width 0.1524)
				(type default)
			)
			(layer "F.SilkS")
		)
		(fp_line
			(start -0.508 -0.9398)
			(end -0.508 0.9398)
			(stroke
				(width 0.1524)
				(type default)
			)
			(layer "F.SilkS")
		)
		(fp_rect
			(start -0.508 0.9398)
			(end 0.508 -0.9398)
			(stroke
				(width 0)
				(type default)
			)
			(fill no)
			(layer "F.CrtYd")
		)
		(fp_rect
			(start -0.508 0.9398)
			(end 0.508 -0.9398)
			(stroke
				(width 0)
				(type default)
			)
			(fill no)
			(layer "F.Fab")
		)
		(pad "1" smd custom
			(at 0 -0.4445 90)
			(size 0.1397 0.1397)
			(layers "F.Cu" "F.Mask" "F.Paste")
			(net "P3V3")
			(options
				(clearance outline)
				(anchor circle)
			)
			(primitives
				(gr_poly
					(pts
						(arc
							(start -0.1778 -0.2794)
							(mid -0.249642 -0.249642)
							(end -0.2794 -0.1778)
						)
						(arc
							(start -0.2794 0.1778)
							(mid -0.249642 0.249642)
							(end -0.1778 0.2794)
						)
						(arc
							(start 0.1778 0.2794)
							(mid 0.249642 0.249642)
							(end 0.2794 0.1778)
						)
						(arc
							(start 0.2794 -0.1778)
							(mid 0.249642 -0.249642)
							(end 0.1778 -0.2794)
						)
					)
					(width 0)
					(fill yes)
				)
			)
		)
		(pad "2" smd custom
			(at 0 0.4445 90)
			(size 0.1397 0.1397)
			(layers "F.Cu" "F.Mask" "F.Paste")
			(net "SSD_PRSNT_NET11")
			(options
				(clearance outline)
				(anchor circle)
			)
			(primitives
				(gr_poly
					(pts
						(arc
							(start -0.1778 -0.2794)
							(mid -0.249642 -0.249642)
							(end -0.2794 -0.1778)
						)
						(arc
							(start -0.2794 0.1778)
							(mid -0.249642 0.249642)
							(end -0.1778 0.2794)
						)
						(arc
							(start 0.1778 0.2794)
							(mid 0.249642 0.249642)
							(end 0.2794 0.1778)
						)
						(arc
							(start 0.2794 -0.1778)
							(mid 0.249642 -0.249642)
							(end 0.1778 -0.2794)
						)
					)
					(width 0)
					(fill yes)
				)
			)
		)
	)
	(footprint ""
		(layer "F.Cu")
		(at 97.028 -86.614 -90)
		(property "Reference" "R9458"
			(at 0 0 270)
			(layer "F.SilkS")
			(hide yes)
			(effects
				(font
					(size 1.27 1.27)
				)
			)
		)
		(property "Value" "4K7R2J-2-GP"
			(at 0.064008 -3.993896 270)
			(unlocked yes)
			(layer "F.Fab")
			(hide yes)
			(effects
				(font
					(size 1.016 1.016)
					(thickness 0.1524)
				)
			)
		)
		(property "Device Type" "R402H16"
			(at 0.064008 -5.517896 270)
			(unlocked yes)
			(layer "F.Fab")
			(hide yes)
			(effects
				(font
					(size 1.016 1.016)
					(thickness 0.1524)
				)
			)
		)
		(duplicate_pad_numbers_are_jumpers no)
		(fp_line
			(start -0.508 -0.9398)
			(end -0.508 0.9398)
			(stroke
				(width 0.1524)
				(type default)
			)
			(layer "F.SilkS")
		)
		(fp_line
			(start 0.508 -0.9398)
			(end -0.508 -0.9398)
			(stroke
				(width 0.1524)
				(type default)
			)
			(layer "F.SilkS")
		)
		(fp_rect
			(start -0.508 0.9398)
			(end 0.508 -0.9398)
			(stroke
				(width 0)
				(type default)
			)
			(fill no)
			(layer "F.CrtYd")
		)
		(fp_rect
			(start -0.508 0.9398)
			(end 0.508 -0.9398)
			(stroke
				(width 0)
				(type default)
			)
			(fill no)
			(layer "F.Fab")
		)
		(pad "1" smd custom
			(at 0 -0.4445 270)
			(size 0.1397 0.1397)
			(layers "F.Cu" "F.Mask" "F.Paste")
			(net "P3V3")
			(options
				(clearance outline)
				(anchor circle)
			)
			(primitives
				(gr_poly
					(pts
						(arc
							(start -0.1778 -0.2794)
							(mid -0.249642 -0.249642)
							(end -0.2794 -0.1778)
						)
						(arc
							(start -0.2794 0.1778)
							(mid -0.249642 0.249642)
							(end -0.1778 0.2794)
						)
						(arc
							(start 0.1778 0.2794)
							(mid 0.249642 0.249642)
							(end 0.2794 0.1778)
						)
						(arc
							(start 0.2794 -0.1778)
							(mid 0.249642 -0.249642)
							(end 0.1778 -0.2794)
						)
					)
					(width 0)
					(fill yes)
				)
			)
		)
		(pad "2" smd custom
			(at 0 0.4445 270)
			(size 0.1397 0.1397)
			(layers "F.Cu" "F.Mask" "F.Paste")
			(net "SSD_PRSNT_NET14")
			(options
				(clearance outline)
				(anchor circle)
			)
			(primitives
				(gr_poly
					(pts
						(arc
							(start -0.1778 -0.2794)
							(mid -0.249642 -0.249642)
							(end -0.2794 -0.1778)
						)
						(arc
							(start -0.2794 0.1778)
							(mid -0.249642 0.249642)
							(end -0.1778 0.2794)
						)
						(arc
							(start 0.1778 0.2794)
							(mid 0.249642 0.249642)
							(end 0.2794 0.1778)
						)
						(arc
							(start 0.2794 -0.1778)
							(mid 0.249642 -0.249642)
							(end 0.1778 -0.2794)
						)
					)
					(width 0)
					(fill yes)
				)
			)
		)
	)
	(footprint ""
		(layer "F.Cu")
		(at 43.0022 -299.593)
		(property "Reference" "R9250"
			(at 0 0 0)
			(layer "F.SilkS")
			(hide yes)
			(effects
				(font
					(size 1.27 1.27)
				)
			)
		)
		(property "Value" "2R2010F-GP"
			(at 0.0762 -4.5466 0)
			(unlocked yes)
			(layer "F.Fab")
			(hide yes)
			(effects
				(font
					(size 1.016 1.016)
					(thickness 0.1524)
				)
			)
		)
		(property "Device Type" "R2010H26"
			(at 0.0762 -6.1468 0)
			(unlocked yes)
			(layer "F.Fab")
			(hide yes)
			(effects
				(font
					(size 1.016 1.016)
					(thickness 0.1524)
				)
			)
		)
		(duplicate_pad_numbers_are_jumpers no)
		(fp_line
			(start -3.302 -1.651)
			(end -3.302 1.651)
			(stroke
				(width 0.1524)
				(type default)
			)
			(layer "F.SilkS")
		)
		(fp_line
			(start -3.302 1.651)
			(end 3.302 1.651)
			(stroke
				(width 0.1524)
				(type default)
			)
			(layer "F.SilkS")
		)
		(fp_line
			(start 3.302 -1.651)
			(end -3.302 -1.651)
			(stroke
				(width 0.1524)
				(type default)
			)
			(layer "F.SilkS")
		)
		(fp_line
			(start 3.302 1.651)
			(end 3.302 -1.651)
			(stroke
				(width 0.1524)
				(type default)
			)
			(layer "F.SilkS")
		)
		(fp_rect
			(start -3.3782 1.7272)
			(end 3.3782 -1.7272)
			(stroke
				(width 0)
				(type default)
			)
			(fill no)
			(layer "F.CrtYd")
		)
		(fp_poly
			(pts
				(xy 3.3782 -1.7272) (xy -3.3782 -1.7272) (xy -3.3782 1.7272) (xy 3.3782 1.7272)
			)
			(stroke
				(width 0)
				(type default)
			)
			(fill no)
			(layer "F.Fab")
		)
		(pad "1" smd rect
			(at -2.3495 0)
			(size 1.143 2.794)
			(layers "F.Cu" "F.Mask" "F.Paste")
			(net "P12V_SSD7")
		)
		(pad "2" smd rect
			(at 2.3495 0)
			(size 1.143 2.794)
			(layers "F.Cu" "F.Mask" "F.Paste")
			(net "12V_PRECH_SSD7")
		)
	)
	(footprint ""
		(layer "F.Cu")
		(at 33.274 -13.6652 180)
		(property "Reference" "PC1232"
			(at 0 0 180)
			(layer "F.SilkS")
			(hide yes)
			(effects
				(font
					(size 1.27 1.27)
				)
			)
		)
		(property "Value" "SCD1U50V3KX-GP"
			(at 0 -2.8194 180)
			(unlocked yes)
			(layer "F.Fab")
			(hide yes)
			(effects
				(font
					(size 1.016 1.016)
					(thickness 0.1524)
				)
			)
		)
		(property "Device Type" "C603H36"
			(at 0 -4.3434 180)
			(unlocked yes)
			(layer "F.Fab")
			(hide yes)
			(effects
				(font
					(size 1.016 1.016)
					(thickness 0.1524)
				)
			)
		)
		(duplicate_pad_numbers_are_jumpers no)
		(fp_line
			(start 0.508 0)
			(end -0.508 0)
			(stroke
				(width 0.2032)
				(type default)
			)
			(layer "F.SilkS")
		)
		(fp_rect
			(start -0.5842 1.3335)
			(end 0.5842 -1.3335)
			(stroke
				(width 0)
				(type default)
			)
			(fill no)
			(layer "F.CrtYd")
		)
		(fp_rect
			(start -0.5842 1.3335)
			(end 0.5842 -1.3335)
			(stroke
				(width 0)
				(type default)
			)
			(fill no)
			(layer "F.Fab")
		)
		(pad "1" smd custom
			(at 0 -0.762 180)
			(size 0.2159 0.2159)
			(layers "F.Cu" "F.Mask" "F.Paste")
			(net "P12V_SSD14")
			(options
				(clearance outline)
				(anchor circle)
			)
			(primitives
				(gr_poly
					(pts
						(arc
							(start -0.3302 -0.4318)
							(mid -0.402042 -0.402042)
							(end -0.4318 -0.3302)
						)
						(arc
							(start -0.4318 0.3302)
							(mid -0.402042 0.402042)
							(end -0.3302 0.4318)
						)
						(arc
							(start 0.3302 0.4318)
							(mid 0.402042 0.402042)
							(end 0.4318 0.3302)
						)
						(arc
							(start 0.4318 -0.3302)
							(mid 0.402042 -0.402042)
							(end 0.3302 -0.4318)
						)
					)
					(width 0)
					(fill yes)
				)
			)
		)
		(pad "2" smd custom
			(at 0 0.762 180)
			(size 0.2159 0.2159)
			(layers "F.Cu" "F.Mask" "F.Paste")
			(net "GND")
			(options
				(clearance outline)
				(anchor circle)
			)
			(primitives
				(gr_poly
					(pts
						(arc
							(start -0.3302 -0.4318)
							(mid -0.402042 -0.402042)
							(end -0.4318 -0.3302)
						)
						(arc
							(start -0.4318 0.3302)
							(mid -0.402042 0.402042)
							(end -0.3302 0.4318)
						)
						(arc
							(start 0.3302 0.4318)
							(mid 0.402042 0.402042)
							(end 0.4318 0.3302)
						)
						(arc
							(start 0.4318 -0.3302)
							(mid 0.402042 -0.402042)
							(end 0.3302 -0.4318)
						)
					)
					(width 0)
					(fill yes)
				)
			)
		)
	)
	(footprint ""
		(layer "F.Cu")
		(at 74.168 -154.178)
		(property "Reference" "SR971"
			(at 0 0 0)
			(layer "F.SilkS")
			(hide yes)
			(effects
				(font
					(size 1.27 1.27)
				)
			)
		)
		(property "Value" "2KR2F-3-GP"
			(at 0.064008 -3.993896 0)
			(unlocked yes)
			(layer "F.Fab")
			(hide yes)
			(effects
				(font
					(size 1.016 1.016)
					(thickness 0.1524)
				)
			)
		)
		(property "Device Type" "R402H16"
			(at 0.064008 -5.517896 0)
			(unlocked yes)
			(layer "F.Fab")
			(hide yes)
			(effects
				(font
					(size 1.016 1.016)
					(thickness 0.1524)
				)
			)
		)
		(duplicate_pad_numbers_are_jumpers no)
		(fp_line
			(start -0.508 -0.9398)
			(end -0.508 0.9398)
			(stroke
				(width 0.1524)
				(type default)
			)
			(layer "F.SilkS")
		)
		(fp_line
			(start 0.508 -0.9398)
			(end -0.508 -0.9398)
			(stroke
				(width 0.1524)
				(type default)
			)
			(layer "F.SilkS")
		)
		(fp_rect
			(start -0.508 0.9398)
			(end 0.508 -0.9398)
			(stroke
				(width 0)
				(type default)
			)
			(fill no)
			(layer "F.CrtYd")
		)
		(fp_rect
			(start -0.508 0.9398)
			(end 0.508 -0.9398)
			(stroke
				(width 0)
				(type default)
			)
			(fill no)
			(layer "F.Fab")
		)
		(pad "1" smd custom
			(at 0 -0.4445)
			(size 0.1397 0.1397)
			(layers "F.Cu" "F.Mask" "F.Paste")
			(net "P3V3")
			(options
				(clearance outline)
				(anchor circle)
			)
			(primitives
				(gr_poly
					(pts
						(arc
							(start -0.1778 -0.2794)
							(mid -0.249642 -0.249642)
							(end -0.2794 -0.1778)
						)
						(arc
							(start -0.2794 0.1778)
							(mid -0.249642 0.249642)
							(end -0.1778 0.2794)
						)
						(arc
							(start 0.1778 0.2794)
							(mid 0.249642 0.249642)
							(end 0.2794 0.1778)
						)
						(arc
							(start 0.2794 -0.1778)
							(mid 0.249642 -0.249642)
							(end 0.1778 -0.2794)
						)
					)
					(width 0)
					(fill yes)
				)
			)
		)
		(pad "2" smd custom
			(at 0 0.4445)
			(size 0.1397 0.1397)
			(layers "F.Cu" "F.Mask" "F.Paste")
			(net "SDA_DR12")
			(options
				(clearance outline)
				(anchor circle)
			)
			(primitives
				(gr_poly
					(pts
						(arc
							(start -0.1778 -0.2794)
							(mid -0.249642 -0.249642)
							(end -0.2794 -0.1778)
						)
						(arc
							(start -0.2794 0.1778)
							(mid -0.249642 0.249642)
							(end -0.1778 0.2794)
						)
						(arc
							(start 0.1778 0.2794)
							(mid 0.249642 0.249642)
							(end 0.2794 0.1778)
						)
						(arc
							(start 0.2794 -0.1778)
							(mid 0.249642 -0.249642)
							(end 0.1778 -0.2794)
						)
					)
					(width 0)
					(fill yes)
				)
			)
		)
	)
	(footprint ""
		(layer "F.Cu")
		(at 6.7564 -378.4854 180)
		(property "Reference" "C9534"
			(at 0 0 180)
			(layer "F.SilkS")
			(hide yes)
			(effects
				(font
					(size 1.27 1.27)
				)
			)
		)
		(property "Value" "SCD01U50V2KX-1GP"
			(at 1.1811 -2.7051 180)
			(unlocked yes)
			(layer "F.Fab")
			(hide yes)
			(effects
				(font
					(size 1.016 1.016)
					(thickness 0.1524)
				)
			)
		)
		(property "Device Type" "C402H22"
			(at 1.1811 -4.2291 180)
			(unlocked yes)
			(layer "F.Fab")
			(hide yes)
			(effects
				(font
					(size 1.016 1.016)
					(thickness 0.1524)
				)
			)
		)
		(duplicate_pad_numbers_are_jumpers no)
		(fp_rect
			(start -0.4318 0.9525)
			(end 0.4318 -0.9525)
			(stroke
				(width 0)
				(type default)
			)
			(fill no)
			(layer "F.CrtYd")
		)
		(fp_rect
			(start -0.4318 0.9525)
			(end 0.4318 -0.9525)
			(stroke
				(width 0)
				(type default)
			)
			(fill no)
			(layer "F.Fab")
		)
		(pad "1" smd custom
			(at 0 -0.4445 180)
			(size 0.1524 0.1524)
			(layers "F.Cu" "F.Mask" "F.Paste")
			(net "PE_100M_CLK1_N")
			(options
				(clearance outline)
				(anchor circle)
			)
			(primitives
				(gr_poly
					(pts
						(arc
							(start 0.3048 -0.2032)
							(mid 0.275042 -0.275042)
							(end 0.2032 -0.3048)
						)
						(arc
							(start -0.2032 -0.3048)
							(mid -0.275042 -0.275042)
							(end -0.3048 -0.2032)
						)
						(arc
							(start -0.3048 0.2032)
							(mid -0.275042 0.275042)
							(end -0.2032 0.3048)
						)
						(arc
							(start 0.2032 0.3048)
							(mid 0.275042 0.275042)
							(end 0.3048 0.2032)
						)
					)
					(width 0)
					(fill yes)
				)
			)
		)
		(pad "2" smd custom
			(at 0 0.4445 180)
			(size 0.1524 0.1524)
			(layers "F.Cu" "F.Mask" "F.Paste")
			(net "PE_100M_CLK1_C_N")
			(options
				(clearance outline)
				(anchor circle)
			)
			(primitives
				(gr_poly
					(pts
						(arc
							(start 0.3048 -0.2032)
							(mid 0.275042 -0.275042)
							(end 0.2032 -0.3048)
						)
						(arc
							(start -0.2032 -0.3048)
							(mid -0.275042 -0.275042)
							(end -0.3048 -0.2032)
						)
						(arc
							(start -0.3048 0.2032)
							(mid -0.275042 0.275042)
							(end -0.2032 0.3048)
						)
						(arc
							(start 0.2032 0.3048)
							(mid 0.275042 0.275042)
							(end 0.3048 0.2032)
						)
					)
					(width 0)
					(fill yes)
				)
			)
		)
	)
	(footprint ""
		(layer "F.Cu")
		(at 36.576 -474.218 180)
		(property "Reference" "PC1209"
			(at 0 0 180)
			(layer "F.SilkS")
			(hide yes)
			(effects
				(font
					(size 1.27 1.27)
				)
			)
		)
		(property "Value" "SCD1U25V3KX-GP"
			(at 0 -2.8194 180)
			(unlocked yes)
			(layer "F.Fab")
			(hide yes)
			(effects
				(font
					(size 1.016 1.016)
					(thickness 0.1524)
				)
			)
		)
		(property "Device Type" "C603H36"
			(at 0 -4.3434 180)
			(unlocked yes)
			(layer "F.Fab")
			(hide yes)
			(effects
				(font
					(size 1.016 1.016)
					(thickness 0.1524)
				)
			)
		)
		(duplicate_pad_numbers_are_jumpers no)
		(fp_line
			(start 0.508 0)
			(end -0.508 0)
			(stroke
				(width 0.2032)
				(type default)
			)
			(layer "F.SilkS")
		)
		(fp_rect
			(start -0.5842 1.3335)
			(end 0.5842 -1.3335)
			(stroke
				(width 0)
				(type default)
			)
			(fill no)
			(layer "F.CrtYd")
		)
		(fp_rect
			(start -0.5842 1.3335)
			(end 0.5842 -1.3335)
			(stroke
				(width 0)
				(type default)
			)
			(fill no)
			(layer "F.Fab")
		)
		(pad "1" smd custom
			(at 0 -0.762 180)
			(size 0.2159 0.2159)
			(layers "F.Cu" "F.Mask" "F.Paste")
			(net "P3V3")
			(options
				(clearance outline)
				(anchor circle)
			)
			(primitives
				(gr_poly
					(pts
						(arc
							(start -0.3302 -0.4318)
							(mid -0.402042 -0.402042)
							(end -0.4318 -0.3302)
						)
						(arc
							(start -0.4318 0.3302)
							(mid -0.402042 0.402042)
							(end -0.3302 0.4318)
						)
						(arc
							(start 0.3302 0.4318)
							(mid 0.402042 0.402042)
							(end 0.4318 0.3302)
						)
						(arc
							(start 0.4318 -0.3302)
							(mid 0.402042 -0.402042)
							(end 0.3302 -0.4318)
						)
					)
					(width 0)
					(fill yes)
				)
			)
		)
		(pad "2" smd custom
			(at 0 0.762 180)
			(size 0.2159 0.2159)
			(layers "F.Cu" "F.Mask" "F.Paste")
			(net "GND")
			(options
				(clearance outline)
				(anchor circle)
			)
			(primitives
				(gr_poly
					(pts
						(arc
							(start -0.3302 -0.4318)
							(mid -0.402042 -0.402042)
							(end -0.4318 -0.3302)
						)
						(arc
							(start -0.4318 0.3302)
							(mid -0.402042 0.402042)
							(end -0.3302 0.4318)
						)
						(arc
							(start 0.3302 0.4318)
							(mid 0.402042 0.402042)
							(end 0.4318 0.3302)
						)
						(arc
							(start 0.4318 -0.3302)
							(mid 0.402042 -0.402042)
							(end 0.3302 -0.4318)
						)
					)
					(width 0)
					(fill yes)
				)
			)
		)
	)
	(footprint ""
		(layer "F.Cu")
		(at 217.043 -81.534 -90)
		(property "Reference" "R395"
			(at 0 0 270)
			(layer "F.SilkS")
			(hide yes)
			(effects
				(font
					(size 1.27 1.27)
				)
			)
		)
		(property "Value" "0R2J-2-GP"
			(at 0.064008 -3.993896 270)
			(unlocked yes)
			(layer "F.Fab")
			(hide yes)
			(effects
				(font
					(size 1.016 1.016)
					(thickness 0.1524)
				)
			)
		)
		(property "Device Type" "R402H16"
			(at 0.064008 -5.517896 270)
			(unlocked yes)
			(layer "F.Fab")
			(hide yes)
			(effects
				(font
					(size 1.016 1.016)
					(thickness 0.1524)
				)
			)
		)
		(duplicate_pad_numbers_are_jumpers no)
		(fp_line
			(start -0.508 -0.9398)
			(end -0.508 0.9398)
			(stroke
				(width 0.1524)
				(type default)
			)
			(layer "F.SilkS")
		)
		(fp_line
			(start 0.508 -0.9398)
			(end -0.508 -0.9398)
			(stroke
				(width 0.1524)
				(type default)
			)
			(layer "F.SilkS")
		)
		(fp_rect
			(start -0.508 0.9398)
			(end 0.508 -0.9398)
			(stroke
				(width 0)
				(type default)
			)
			(fill no)
			(layer "F.CrtYd")
		)
		(fp_rect
			(start -0.508 0.9398)
			(end 0.508 -0.9398)
			(stroke
				(width 0)
				(type default)
			)
			(fill no)
			(layer "F.Fab")
		)
		(pad "1" smd custom
			(at 0 -0.4445 270)
			(size 0.1397 0.1397)
			(layers "F.Cu" "F.Mask" "F.Paste")
			(net "SCL_DR4_R")
			(options
				(clearance outline)
				(anchor circle)
			)
			(primitives
				(gr_poly
					(pts
						(arc
							(start -0.1778 -0.2794)
							(mid -0.249642 -0.249642)
							(end -0.2794 -0.1778)
						)
						(arc
							(start -0.2794 0.1778)
							(mid -0.249642 0.249642)
							(end -0.1778 0.2794)
						)
						(arc
							(start 0.1778 0.2794)
							(mid 0.249642 0.249642)
							(end 0.2794 0.1778)
						)
						(arc
							(start 0.2794 -0.1778)
							(mid 0.249642 -0.249642)
							(end 0.1778 -0.2794)
						)
					)
					(width 0)
					(fill yes)
				)
			)
		)
		(pad "2" smd custom
			(at 0 0.4445 270)
			(size 0.1397 0.1397)
			(layers "F.Cu" "F.Mask" "F.Paste")
			(net "SCL_DR4")
			(options
				(clearance outline)
				(anchor circle)
			)
			(primitives
				(gr_poly
					(pts
						(arc
							(start -0.1778 -0.2794)
							(mid -0.249642 -0.249642)
							(end -0.2794 -0.1778)
						)
						(arc
							(start -0.2794 0.1778)
							(mid -0.249642 0.249642)
							(end -0.1778 0.2794)
						)
						(arc
							(start 0.1778 0.2794)
							(mid 0.249642 0.249642)
							(end 0.2794 0.1778)
						)
						(arc
							(start 0.2794 -0.1778)
							(mid 0.249642 -0.249642)
							(end 0.1778 -0.2794)
						)
					)
					(width 0)
					(fill yes)
				)
			)
		)
	)
	(footprint ""
		(layer "F.Cu")
		(at 83.185 -149.606 90)
		(property "Reference" "SR1153"
			(at 0 0 90)
			(layer "F.SilkS")
			(hide yes)
			(effects
				(font
					(size 1.27 1.27)
				)
			)
		)
		(property "Value" "4K7R2F-GP"
			(at 0.064008 -3.993896 90)
			(unlocked yes)
			(layer "F.Fab")
			(hide yes)
			(effects
				(font
					(size 1.016 1.016)
					(thickness 0.1524)
				)
			)
		)
		(property "Device Type" "R402H16"
			(at 0.064008 -5.517896 90)
			(unlocked yes)
			(layer "F.Fab")
			(hide yes)
			(effects
				(font
					(size 1.016 1.016)
					(thickness 0.1524)
				)
			)
		)
		(duplicate_pad_numbers_are_jumpers no)
		(fp_line
			(start 0.508 -0.9398)
			(end -0.508 -0.9398)
			(stroke
				(width 0.1524)
				(type default)
			)
			(layer "F.SilkS")
		)
		(fp_line
			(start -0.508 -0.9398)
			(end -0.508 0.9398)
			(stroke
				(width 0.1524)
				(type default)
			)
			(layer "F.SilkS")
		)
		(fp_rect
			(start -0.508 0.9398)
			(end 0.508 -0.9398)
			(stroke
				(width 0)
				(type default)
			)
			(fill no)
			(layer "F.CrtYd")
		)
		(fp_rect
			(start -0.508 0.9398)
			(end 0.508 -0.9398)
			(stroke
				(width 0)
				(type default)
			)
			(fill no)
			(layer "F.Fab")
		)
		(pad "1" smd custom
			(at 0 -0.4445 90)
			(size 0.1397 0.1397)
			(layers "F.Cu" "F.Mask" "F.Paste")
			(net "I2C_SW_EU16_ADDRESS_A0")
			(options
				(clearance outline)
				(anchor circle)
			)
			(primitives
				(gr_poly
					(pts
						(arc
							(start -0.1778 -0.2794)
							(mid -0.249642 -0.249642)
							(end -0.2794 -0.1778)
						)
						(arc
							(start -0.2794 0.1778)
							(mid -0.249642 0.249642)
							(end -0.1778 0.2794)
						)
						(arc
							(start 0.1778 0.2794)
							(mid 0.249642 0.249642)
							(end 0.2794 0.1778)
						)
						(arc
							(start 0.2794 -0.1778)
							(mid 0.249642 -0.249642)
							(end 0.1778 -0.2794)
						)
					)
					(width 0)
					(fill yes)
				)
			)
		)
		(pad "2" smd custom
			(at 0 0.4445 90)
			(size 0.1397 0.1397)
			(layers "F.Cu" "F.Mask" "F.Paste")
			(net "GND")
			(options
				(clearance outline)
				(anchor circle)
			)
			(primitives
				(gr_poly
					(pts
						(arc
							(start -0.1778 -0.2794)
							(mid -0.249642 -0.249642)
							(end -0.2794 -0.1778)
						)
						(arc
							(start -0.2794 0.1778)
							(mid -0.249642 0.249642)
							(end -0.1778 0.2794)
						)
						(arc
							(start 0.1778 0.2794)
							(mid 0.249642 0.249642)
							(end 0.2794 0.1778)
						)
						(arc
							(start 0.2794 -0.1778)
							(mid 0.249642 -0.249642)
							(end 0.1778 -0.2794)
						)
					)
					(width 0)
					(fill yes)
				)
			)
		)
	)
	(footprint ""
		(layer "F.Cu")
		(at 8.7122 -465.3534 90)
		(property "Reference" "PC1163"
			(at 0 0 90)
			(layer "F.SilkS")
			(hide yes)
			(effects
				(font
					(size 1.27 1.27)
				)
			)
		)
		(property "Value" "SCD1U50V3KX-GP"
			(at 0 -2.8194 90)
			(unlocked yes)
			(layer "F.Fab")
			(hide yes)
			(effects
				(font
					(size 1.016 1.016)
					(thickness 0.1524)
				)
			)
		)
		(property "Device Type" "C603H36"
			(at 0 -4.3434 90)
			(unlocked yes)
			(layer "F.Fab")
			(hide yes)
			(effects
				(font
					(size 1.016 1.016)
					(thickness 0.1524)
				)
			)
		)
		(duplicate_pad_numbers_are_jumpers no)
		(fp_line
			(start 0.508 0)
			(end -0.508 0)
			(stroke
				(width 0.2032)
				(type default)
			)
			(layer "F.SilkS")
		)
		(fp_rect
			(start -0.5842 1.3335)
			(end 0.5842 -1.3335)
			(stroke
				(width 0)
				(type default)
			)
			(fill no)
			(layer "F.CrtYd")
		)
		(fp_rect
			(start -0.5842 1.3335)
			(end 0.5842 -1.3335)
			(stroke
				(width 0)
				(type default)
			)
			(fill no)
			(layer "F.Fab")
		)
		(pad "1" smd custom
			(at 0 -0.762 90)
			(size 0.2159 0.2159)
			(layers "F.Cu" "F.Mask" "F.Paste")
			(net "P12V")
			(options
				(clearance outline)
				(anchor circle)
			)
			(primitives
				(gr_poly
					(pts
						(arc
							(start -0.3302 -0.4318)
							(mid -0.402042 -0.402042)
							(end -0.4318 -0.3302)
						)
						(arc
							(start -0.4318 0.3302)
							(mid -0.402042 0.402042)
							(end -0.3302 0.4318)
						)
						(arc
							(start 0.3302 0.4318)
							(mid 0.402042 0.402042)
							(end 0.4318 0.3302)
						)
						(arc
							(start 0.4318 -0.3302)
							(mid 0.402042 -0.402042)
							(end 0.3302 -0.4318)
						)
					)
					(width 0)
					(fill yes)
				)
			)
		)
		(pad "2" smd custom
			(at 0 0.762 90)
			(size 0.2159 0.2159)
			(layers "F.Cu" "F.Mask" "F.Paste")
			(net "GND")
			(options
				(clearance outline)
				(anchor circle)
			)
			(primitives
				(gr_poly
					(pts
						(arc
							(start -0.3302 -0.4318)
							(mid -0.402042 -0.402042)
							(end -0.4318 -0.3302)
						)
						(arc
							(start -0.4318 0.3302)
							(mid -0.402042 0.402042)
							(end -0.3302 0.4318)
						)
						(arc
							(start 0.3302 0.4318)
							(mid 0.402042 0.402042)
							(end 0.4318 0.3302)
						)
						(arc
							(start 0.4318 -0.3302)
							(mid 0.402042 -0.402042)
							(end 0.3302 -0.4318)
						)
					)
					(width 0)
					(fill yes)
				)
			)
		)
	)
	(footprint ""
		(layer "F.Cu")
		(at 84.455 -205.994 90)
		(property "Reference" "R424"
			(at 0 0 90)
			(layer "F.SilkS")
			(hide yes)
			(effects
				(font
					(size 1.27 1.27)
				)
			)
		)
		(property "Value" "0R2J-2-GP"
			(at 0.064008 -3.993896 90)
			(unlocked yes)
			(layer "F.Fab")
			(hide yes)
			(effects
				(font
					(size 1.016 1.016)
					(thickness 0.1524)
				)
			)
		)
		(property "Device Type" "R402H16"
			(at 0.064008 -5.517896 90)
			(unlocked yes)
			(layer "F.Fab")
			(hide yes)
			(effects
				(font
					(size 1.016 1.016)
					(thickness 0.1524)
				)
			)
		)
		(duplicate_pad_numbers_are_jumpers no)
		(fp_line
			(start 0.508 -0.9398)
			(end -0.508 -0.9398)
			(stroke
				(width 0.1524)
				(type default)
			)
			(layer "F.SilkS")
		)
		(fp_line
			(start -0.508 -0.9398)
			(end -0.508 0.9398)
			(stroke
				(width 0.1524)
				(type default)
			)
			(layer "F.SilkS")
		)
		(fp_rect
			(start -0.508 0.9398)
			(end 0.508 -0.9398)
			(stroke
				(width 0)
				(type default)
			)
			(fill no)
			(layer "F.CrtYd")
		)
		(fp_rect
			(start -0.508 0.9398)
			(end 0.508 -0.9398)
			(stroke
				(width 0)
				(type default)
			)
			(fill no)
			(layer "F.Fab")
		)
		(pad "1" smd custom
			(at 0 -0.4445 90)
			(size 0.1397 0.1397)
			(layers "F.Cu" "F.Mask" "F.Paste")
			(net "BMC_I2C_SCL_BUF_8")
			(options
				(clearance outline)
				(anchor circle)
			)
			(primitives
				(gr_poly
					(pts
						(arc
							(start -0.1778 -0.2794)
							(mid -0.249642 -0.249642)
							(end -0.2794 -0.1778)
						)
						(arc
							(start -0.2794 0.1778)
							(mid -0.249642 0.249642)
							(end -0.1778 0.2794)
						)
						(arc
							(start 0.1778 0.2794)
							(mid 0.249642 0.249642)
							(end 0.2794 0.1778)
						)
						(arc
							(start 0.2794 -0.1778)
							(mid 0.249642 -0.249642)
							(end 0.1778 -0.2794)
						)
					)
					(width 0)
					(fill yes)
				)
			)
		)
		(pad "2" smd custom
			(at 0 0.4445 90)
			(size 0.1397 0.1397)
			(layers "F.Cu" "F.Mask" "F.Paste")
			(net "I2C_SCL_BUF_8_EU3_R")
			(options
				(clearance outline)
				(anchor circle)
			)
			(primitives
				(gr_poly
					(pts
						(arc
							(start -0.1778 -0.2794)
							(mid -0.249642 -0.249642)
							(end -0.2794 -0.1778)
						)
						(arc
							(start -0.2794 0.1778)
							(mid -0.249642 0.249642)
							(end -0.1778 0.2794)
						)
						(arc
							(start 0.1778 0.2794)
							(mid 0.249642 0.249642)
							(end 0.2794 0.1778)
						)
						(arc
							(start 0.2794 -0.1778)
							(mid 0.249642 -0.249642)
							(end 0.1778 -0.2794)
						)
					)
					(width 0)
					(fill yes)
				)
			)
		)
	)
	(footprint ""
		(layer "F.Cu")
		(at 89.535 -18.669)
		(property "Reference" "R381"
			(at 0 0 0)
			(layer "F.SilkS")
			(hide yes)
			(effects
				(font
					(size 1.27 1.27)
				)
			)
		)
		(property "Value" "4K7R2J-2-GP"
			(at 0.064008 -3.993896 0)
			(unlocked yes)
			(layer "F.Fab")
			(hide yes)
			(effects
				(font
					(size 1.016 1.016)
					(thickness 0.1524)
				)
			)
		)
		(property "Device Type" "R402H16"
			(at 0.064008 -5.517896 0)
			(unlocked yes)
			(layer "F.Fab")
			(hide yes)
			(effects
				(font
					(size 1.016 1.016)
					(thickness 0.1524)
				)
			)
		)
		(duplicate_pad_numbers_are_jumpers no)
		(fp_line
			(start -0.508 -0.9398)
			(end -0.508 0.9398)
			(stroke
				(width 0.1524)
				(type default)
			)
			(layer "F.SilkS")
		)
		(fp_line
			(start 0.508 -0.9398)
			(end -0.508 -0.9398)
			(stroke
				(width 0.1524)
				(type default)
			)
			(layer "F.SilkS")
		)
		(fp_rect
			(start -0.508 0.9398)
			(end 0.508 -0.9398)
			(stroke
				(width 0)
				(type default)
			)
			(fill no)
			(layer "F.CrtYd")
		)
		(fp_rect
			(start -0.508 0.9398)
			(end 0.508 -0.9398)
			(stroke
				(width 0)
				(type default)
			)
			(fill no)
			(layer "F.Fab")
		)
		(pad "1" smd custom
			(at 0 -0.4445)
			(size 0.1397 0.1397)
			(layers "F.Cu" "F.Mask" "F.Paste")
			(net "VOL_SEN_ADDR")
			(options
				(clearance outline)
				(anchor circle)
			)
			(primitives
				(gr_poly
					(pts
						(arc
							(start -0.1778 -0.2794)
							(mid -0.249642 -0.249642)
							(end -0.2794 -0.1778)
						)
						(arc
							(start -0.2794 0.1778)
							(mid -0.249642 0.249642)
							(end -0.1778 0.2794)
						)
						(arc
							(start 0.1778 0.2794)
							(mid 0.249642 0.249642)
							(end 0.2794 0.1778)
						)
						(arc
							(start 0.2794 -0.1778)
							(mid 0.249642 -0.249642)
							(end 0.1778 -0.2794)
						)
					)
					(width 0)
					(fill yes)
				)
			)
		)
		(pad "2" smd custom
			(at 0 0.4445)
			(size 0.1397 0.1397)
			(layers "F.Cu" "F.Mask" "F.Paste")
			(net "GND")
			(options
				(clearance outline)
				(anchor circle)
			)
			(primitives
				(gr_poly
					(pts
						(arc
							(start -0.1778 -0.2794)
							(mid -0.249642 -0.249642)
							(end -0.2794 -0.1778)
						)
						(arc
							(start -0.2794 0.1778)
							(mid -0.249642 0.249642)
							(end -0.1778 0.2794)
						)
						(arc
							(start 0.1778 0.2794)
							(mid 0.249642 0.249642)
							(end 0.2794 0.1778)
						)
						(arc
							(start 0.2794 -0.1778)
							(mid 0.249642 -0.249642)
							(end 0.1778 -0.2794)
						)
					)
					(width 0)
					(fill yes)
				)
			)
		)
	)
	(footprint ""
		(layer "F.Cu")
		(at 82.931 -309.499 90)
		(property "Reference" "SR950"
			(at 0 0 90)
			(layer "F.SilkS")
			(hide yes)
			(effects
				(font
					(size 1.27 1.27)
				)
			)
		)
		(property "Value" "4K7R2F-GP"
			(at 0.064008 -3.993896 90)
			(unlocked yes)
			(layer "F.Fab")
			(hide yes)
			(effects
				(font
					(size 1.016 1.016)
					(thickness 0.1524)
				)
			)
		)
		(property "Device Type" "R402H16"
			(at 0.064008 -5.517896 90)
			(unlocked yes)
			(layer "F.Fab")
			(hide yes)
			(effects
				(font
					(size 1.016 1.016)
					(thickness 0.1524)
				)
			)
		)
		(duplicate_pad_numbers_are_jumpers no)
		(fp_line
			(start 0.508 -0.9398)
			(end -0.508 -0.9398)
			(stroke
				(width 0.1524)
				(type default)
			)
			(layer "F.SilkS")
		)
		(fp_line
			(start -0.508 -0.9398)
			(end -0.508 0.9398)
			(stroke
				(width 0.1524)
				(type default)
			)
			(layer "F.SilkS")
		)
		(fp_rect
			(start -0.508 0.9398)
			(end 0.508 -0.9398)
			(stroke
				(width 0)
				(type default)
			)
			(fill no)
			(layer "F.CrtYd")
		)
		(fp_rect
			(start -0.508 0.9398)
			(end 0.508 -0.9398)
			(stroke
				(width 0)
				(type default)
			)
			(fill no)
			(layer "F.Fab")
		)
		(pad "1" smd custom
			(at 0 -0.4445 90)
			(size 0.1397 0.1397)
			(layers "F.Cu" "F.Mask" "F.Paste")
			(net "VDD_DIFF_2")
			(options
				(clearance outline)
				(anchor circle)
			)
			(primitives
				(gr_poly
					(pts
						(arc
							(start -0.1778 -0.2794)
							(mid -0.249642 -0.249642)
							(end -0.2794 -0.1778)
						)
						(arc
							(start -0.2794 0.1778)
							(mid -0.249642 0.249642)
							(end -0.1778 0.2794)
						)
						(arc
							(start 0.1778 0.2794)
							(mid 0.249642 0.249642)
							(end 0.2794 0.1778)
						)
						(arc
							(start 0.2794 -0.1778)
							(mid 0.249642 -0.249642)
							(end 0.1778 -0.2794)
						)
					)
					(width 0)
					(fill yes)
				)
			)
		)
		(pad "2" smd custom
			(at 0 0.4445 90)
			(size 0.1397 0.1397)
			(layers "F.Cu" "F.Mask" "F.Paste")
			(net "CLK_BUF_EU2_HIBW_BYPM_LOBW#")
			(options
				(clearance outline)
				(anchor circle)
			)
			(primitives
				(gr_poly
					(pts
						(arc
							(start -0.1778 -0.2794)
							(mid -0.249642 -0.249642)
							(end -0.2794 -0.1778)
						)
						(arc
							(start -0.2794 0.1778)
							(mid -0.249642 0.249642)
							(end -0.1778 0.2794)
						)
						(arc
							(start 0.1778 0.2794)
							(mid 0.249642 0.249642)
							(end 0.2794 0.1778)
						)
						(arc
							(start 0.2794 -0.1778)
							(mid 0.249642 -0.249642)
							(end 0.1778 -0.2794)
						)
					)
					(width 0)
					(fill yes)
				)
			)
		)
	)
	(footprint ""
		(layer "F.Cu")
		(at 29.845 -218.44 90)
		(property "Reference" "R413"
			(at 0 0 90)
			(layer "F.SilkS")
			(hide yes)
			(effects
				(font
					(size 1.27 1.27)
				)
			)
		)
		(property "Value" "0R2J-2-GP"
			(at 0.064008 -3.993896 90)
			(unlocked yes)
			(layer "F.Fab")
			(hide yes)
			(effects
				(font
					(size 1.016 1.016)
					(thickness 0.1524)
				)
			)
		)
		(property "Device Type" "R402H16"
			(at 0.064008 -5.517896 90)
			(unlocked yes)
			(layer "F.Fab")
			(hide yes)
			(effects
				(font
					(size 1.016 1.016)
					(thickness 0.1524)
				)
			)
		)
		(duplicate_pad_numbers_are_jumpers no)
		(fp_line
			(start 0.508 -0.9398)
			(end -0.508 -0.9398)
			(stroke
				(width 0.1524)
				(type default)
			)
			(layer "F.SilkS")
		)
		(fp_line
			(start -0.508 -0.9398)
			(end -0.508 0.9398)
			(stroke
				(width 0.1524)
				(type default)
			)
			(layer "F.SilkS")
		)
		(fp_rect
			(start -0.508 0.9398)
			(end 0.508 -0.9398)
			(stroke
				(width 0)
				(type default)
			)
			(fill no)
			(layer "F.CrtYd")
		)
		(fp_rect
			(start -0.508 0.9398)
			(end 0.508 -0.9398)
			(stroke
				(width 0)
				(type default)
			)
			(fill no)
			(layer "F.Fab")
		)
		(pad "1" smd custom
			(at 0 -0.4445 90)
			(size 0.1397 0.1397)
			(layers "F.Cu" "F.Mask" "F.Paste")
			(net "SCL_DR12_R")
			(options
				(clearance outline)
				(anchor circle)
			)
			(primitives
				(gr_poly
					(pts
						(arc
							(start -0.1778 -0.2794)
							(mid -0.249642 -0.249642)
							(end -0.2794 -0.1778)
						)
						(arc
							(start -0.2794 0.1778)
							(mid -0.249642 0.249642)
							(end -0.1778 0.2794)
						)
						(arc
							(start 0.1778 0.2794)
							(mid 0.249642 0.249642)
							(end 0.2794 0.1778)
						)
						(arc
							(start 0.2794 -0.1778)
							(mid 0.249642 -0.249642)
							(end 0.1778 -0.2794)
						)
					)
					(width 0)
					(fill yes)
				)
			)
		)
		(pad "2" smd custom
			(at 0 0.4445 90)
			(size 0.1397 0.1397)
			(layers "F.Cu" "F.Mask" "F.Paste")
			(net "SCL_DR12")
			(options
				(clearance outline)
				(anchor circle)
			)
			(primitives
				(gr_poly
					(pts
						(arc
							(start -0.1778 -0.2794)
							(mid -0.249642 -0.249642)
							(end -0.2794 -0.1778)
						)
						(arc
							(start -0.2794 0.1778)
							(mid -0.249642 0.249642)
							(end -0.1778 0.2794)
						)
						(arc
							(start 0.1778 0.2794)
							(mid 0.249642 0.249642)
							(end 0.2794 0.1778)
						)
						(arc
							(start 0.2794 -0.1778)
							(mid 0.249642 -0.249642)
							(end 0.1778 -0.2794)
						)
					)
					(width 0)
					(fill yes)
				)
			)
		)
	)
	(footprint ""
		(layer "F.Cu")
		(at 42.650918 -243.84 90)
		(property "Reference" "R9831"
			(at 0 0 90)
			(layer "F.SilkS")
			(hide yes)
			(effects
				(font
					(size 1.27 1.27)
				)
			)
		)
		(property "Value" "0R2J-2-GP"
			(at 0.064008 -3.993896 90)
			(unlocked yes)
			(layer "F.Fab")
			(hide yes)
			(effects
				(font
					(size 1.016 1.016)
					(thickness 0.1524)
				)
			)
		)
		(property "Device Type" "R402H16"
			(at 0.064008 -5.517896 90)
			(unlocked yes)
			(layer "F.Fab")
			(hide yes)
			(effects
				(font
					(size 1.016 1.016)
					(thickness 0.1524)
				)
			)
		)
		(duplicate_pad_numbers_are_jumpers no)
		(fp_line
			(start 0.508 -0.9398)
			(end -0.508 -0.9398)
			(stroke
				(width 0.1524)
				(type default)
			)
			(layer "F.SilkS")
		)
		(fp_line
			(start -0.508 -0.9398)
			(end -0.508 0.9398)
			(stroke
				(width 0.1524)
				(type default)
			)
			(layer "F.SilkS")
		)
		(fp_rect
			(start -0.508 0.9398)
			(end 0.508 -0.9398)
			(stroke
				(width 0)
				(type default)
			)
			(fill no)
			(layer "F.CrtYd")
		)
		(fp_rect
			(start -0.508 0.9398)
			(end 0.508 -0.9398)
			(stroke
				(width 0)
				(type default)
			)
			(fill no)
			(layer "F.Fab")
		)
		(pad "1" smd custom
			(at 0 -0.4445 90)
			(size 0.1397 0.1397)
			(layers "F.Cu" "F.Mask" "F.Paste")
			(net "SSD_ACT_DR7_R")
			(options
				(clearance outline)
				(anchor circle)
			)
			(primitives
				(gr_poly
					(pts
						(arc
							(start -0.1778 -0.2794)
							(mid -0.249642 -0.249642)
							(end -0.2794 -0.1778)
						)
						(arc
							(start -0.2794 0.1778)
							(mid -0.249642 0.249642)
							(end -0.1778 0.2794)
						)
						(arc
							(start 0.1778 0.2794)
							(mid 0.249642 0.249642)
							(end 0.2794 0.1778)
						)
						(arc
							(start 0.2794 -0.1778)
							(mid 0.249642 -0.249642)
							(end 0.1778 -0.2794)
						)
					)
					(width 0)
					(fill yes)
				)
			)
		)
		(pad "2" smd custom
			(at 0 0.4445 90)
			(size 0.1397 0.1397)
			(layers "F.Cu" "F.Mask" "F.Paste")
			(net "SSD_ACT_DR7")
			(options
				(clearance outline)
				(anchor circle)
			)
			(primitives
				(gr_poly
					(pts
						(arc
							(start -0.1778 -0.2794)
							(mid -0.249642 -0.249642)
							(end -0.2794 -0.1778)
						)
						(arc
							(start -0.2794 0.1778)
							(mid -0.249642 0.249642)
							(end -0.1778 0.2794)
						)
						(arc
							(start 0.1778 0.2794)
							(mid 0.249642 0.249642)
							(end 0.2794 0.1778)
						)
						(arc
							(start 0.2794 -0.1778)
							(mid 0.249642 -0.249642)
							(end 0.1778 -0.2794)
						)
					)
					(width 0)
					(fill yes)
				)
			)
		)
	)
	(footprint ""
		(layer "F.Cu")
		(at 224.663 -438.658)
		(property "Reference" "PR9091"
			(at 0 0 0)
			(layer "F.SilkS")
			(hide yes)
			(effects
				(font
					(size 1.27 1.27)
				)
			)
		)
		(property "Value" "3D01R5F-GP"
			(at 0 -8.9535 0)
			(unlocked yes)
			(layer "F.Fab")
			(hide yes)
			(effects
				(font
					(size 1.27 1.016)
					(thickness 0.1524)
				)
			)
		)
		(property "Device Type" "R805H24"
			(at 0 -10.6299 0)
			(unlocked yes)
			(layer "F.Fab")
			(hide yes)
			(effects
				(font
					(size 1.27 1.016)
					(thickness 0.1524)
				)
			)
		)
		(duplicate_pad_numbers_are_jumpers no)
		(fp_line
			(start -0.889 -1.7018)
			(end -0.889 0.2794)
			(stroke
				(width 0.1524)
				(type default)
			)
			(layer "F.SilkS")
		)
		(fp_line
			(start -0.889 0.0762)
			(end -0.889 1.7018)
			(stroke
				(width 0.1524)
				(type default)
			)
			(layer "F.SilkS")
		)
		(fp_line
			(start -0.889 1.7018)
			(end 0.889 1.7018)
			(stroke
				(width 0.1524)
				(type default)
			)
			(layer "F.SilkS")
		)
		(fp_line
			(start 0.889 -1.7018)
			(end -0.889 -1.7018)
			(stroke
				(width 0.1524)
				(type default)
			)
			(layer "F.SilkS")
		)
		(fp_line
			(start 0.889 -1.7018)
			(end 0.889 -0.381)
			(stroke
				(width 0.1524)
				(type default)
			)
			(layer "F.SilkS")
		)
		(fp_line
			(start 0.889 1.7018)
			(end 0.889 -0.508)
			(stroke
				(width 0.1524)
				(type default)
			)
			(layer "F.SilkS")
		)
		(fp_poly
			(pts
				(xy 0.9652 -1.778) (xy 0.9652 1.778) (xy -0.9652 1.778) (xy -0.9652 -1.778)
			)
			(stroke
				(width 0)
				(type default)
			)
			(fill no)
			(layer "F.CrtYd")
		)
		(fp_rect
			(start -0.9652 1.778)
			(end 0.9652 -1.778)
			(stroke
				(width 0)
				(type default)
			)
			(fill no)
			(layer "F.Fab")
		)
		(pad "1" smd rect
			(at 0 -0.9652)
			(size 1.397 1.143)
			(layers "F.Cu" "F.Mask" "F.Paste")
			(net "P3V3_SNB")
		)
		(pad "2" smd rect
			(at 0 0.9652)
			(size 1.397 1.143)
			(layers "F.Cu" "F.Mask" "F.Paste")
			(net "GND")
		)
	)
	(footprint ""
		(layer "F.Cu")
		(at 228.499924 -41.099994)
		(property "Reference" "LED4"
			(at 0 0 0)
			(layer "F.SilkS")
			(hide yes)
			(effects
				(font
					(size 1.27 1.27)
				)
			)
		)
		(property "Value" "LED-RB-4-GP"
			(at 5.88899 1.80848 0)
			(unlocked yes)
			(layer "F.Fab")
			(hide yes)
			(effects
				(font
					(size 1.016 1.016)
					(thickness 0.1524)
				)
			)
		)
		(property "Device Type" "LED1613-4PH20"
			(at 5.88899 0.28448 0)
			(unlocked yes)
			(layer "F.Fab")
			(hide yes)
			(effects
				(font
					(size 1.016 1.016)
					(thickness 0.1524)
				)
			)
		)
		(duplicate_pad_numbers_are_jumpers no)
		(fp_line
			(start -1.4478 -0.9652)
			(end 1.4478 -0.9652)
			(stroke
				(width 0.1524)
				(type default)
			)
			(layer "F.SilkS")
		)
		(fp_line
			(start -1.4478 0.9652)
			(end -1.4478 -0.9652)
			(stroke
				(width 0.1524)
				(type default)
			)
			(layer "F.SilkS")
		)
		(fp_line
			(start -1.4478 0.9652)
			(end -1.4478 -0.9652)
			(stroke
				(width 0.508)
				(type default)
			)
			(layer "F.SilkS")
		)
		(fp_line
			(start 1.4478 -0.9652)
			(end 1.4478 0.9652)
			(stroke
				(width 0.1524)
				(type default)
			)
			(layer "F.SilkS")
		)
		(fp_line
			(start 1.4478 0.9652)
			(end -1.4478 0.9652)
			(stroke
				(width 0.1524)
				(type default)
			)
			(layer "F.SilkS")
		)
		(fp_rect
			(start -0.8001 0.6477)
			(end 0.8001 -0.6477)
			(stroke
				(width 0)
				(type default)
			)
			(fill no)
			(layer "F.CrtYd")
		)
		(fp_poly
			(pts
				(xy -1.7018 1.2192) (xy -1.7018 -0.06223) (xy -0.8001 -0.06223) (xy -0.8001 0.6477) (xy 0.8001 0.6477)
				(xy 0.8001 -0.6477) (xy -0.8001 -0.6477) (xy -0.8001 -0.0635) (xy -1.7018 -0.0635) (xy -1.7018 -1.2192)
				(xy 1.7018 -1.2192) (xy 1.7018 1.2192)
			)
			(stroke
				(width 0)
				(type default)
			)
			(fill no)
			(layer "F.CrtYd")
		)
		(fp_rect
			(start -1.7018 1.2192)
			(end 1.7018 -1.2192)
			(stroke
				(width 0)
				(type default)
			)
			(fill no)
			(layer "F.Fab")
		)
		(pad "1" smd rect
			(at -0.73025 0.4064)
			(size 0.9144 0.6096)
			(layers "F.Cu" "F.Mask" "F.Paste")
			(net "SSD_ACT_DR4_MOS_N")
		)
		(pad "2" smd rect
			(at -0.73025 -0.4064)
			(size 0.9144 0.6096)
			(layers "F.Cu" "F.Mask" "F.Paste")
			(net "ATTN_LED_DR4_MOS_N")
		)
		(pad "3" smd rect
			(at 0.73025 -0.4064)
			(size 0.9144 0.6096)
			(layers "F.Cu" "F.Mask" "F.Paste")
			(net "DRV_ATTN_4")
		)
		(pad "4" smd rect
			(at 0.73025 0.4064)
			(size 0.9144 0.6096)
			(layers "F.Cu" "F.Mask" "F.Paste")
			(net "DRV_ACT_4")
		)
	)
	(footprint ""
		(layer "F.Cu")
		(at 47.879 -348.742 -90)
		(property "Reference" "R9898"
			(at 0 0 270)
			(layer "F.SilkS")
			(hide yes)
			(effects
				(font
					(size 1.27 1.27)
				)
			)
		)
		(property "Value" "1K82R2F-1-GP"
			(at 0.064008 -3.993896 270)
			(unlocked yes)
			(layer "F.Fab")
			(hide yes)
			(effects
				(font
					(size 1.016 1.016)
					(thickness 0.1524)
				)
			)
		)
		(property "Device Type" "R402H16"
			(at 0.064008 -5.517896 270)
			(unlocked yes)
			(layer "F.Fab")
			(hide yes)
			(effects
				(font
					(size 1.016 1.016)
					(thickness 0.1524)
				)
			)
		)
		(duplicate_pad_numbers_are_jumpers no)
		(fp_line
			(start -0.508 -0.9398)
			(end -0.508 0.9398)
			(stroke
				(width 0.1524)
				(type default)
			)
			(layer "F.SilkS")
		)
		(fp_line
			(start 0.508 -0.9398)
			(end -0.508 -0.9398)
			(stroke
				(width 0.1524)
				(type default)
			)
			(layer "F.SilkS")
		)
		(fp_rect
			(start -0.508 0.9398)
			(end 0.508 -0.9398)
			(stroke
				(width 0)
				(type default)
			)
			(fill no)
			(layer "F.CrtYd")
		)
		(fp_rect
			(start -0.508 0.9398)
			(end 0.508 -0.9398)
			(stroke
				(width 0)
				(type default)
			)
			(fill no)
			(layer "F.Fab")
		)
		(pad "1" smd custom
			(at 0 -0.4445 270)
			(size 0.1397 0.1397)
			(layers "F.Cu" "F.Mask" "F.Paste")
			(net "P12V")
			(options
				(clearance outline)
				(anchor circle)
			)
			(primitives
				(gr_poly
					(pts
						(arc
							(start -0.1778 -0.2794)
							(mid -0.249642 -0.249642)
							(end -0.2794 -0.1778)
						)
						(arc
							(start -0.2794 0.1778)
							(mid -0.249642 0.249642)
							(end -0.1778 0.2794)
						)
						(arc
							(start 0.1778 0.2794)
							(mid 0.249642 0.249642)
							(end 0.2794 0.1778)
						)
						(arc
							(start 0.2794 -0.1778)
							(mid 0.249642 -0.249642)
							(end 0.1778 -0.2794)
						)
					)
					(width 0)
					(fill yes)
				)
			)
		)
		(pad "2" smd custom
			(at 0 0.4445 270)
			(size 0.1397 0.1397)
			(layers "F.Cu" "F.Mask" "F.Paste")
			(net "DRV_ACT_6")
			(options
				(clearance outline)
				(anchor circle)
			)
			(primitives
				(gr_poly
					(pts
						(arc
							(start -0.1778 -0.2794)
							(mid -0.249642 -0.249642)
							(end -0.2794 -0.1778)
						)
						(arc
							(start -0.2794 0.1778)
							(mid -0.249642 0.249642)
							(end -0.1778 0.2794)
						)
						(arc
							(start 0.1778 0.2794)
							(mid 0.249642 0.249642)
							(end 0.2794 0.1778)
						)
						(arc
							(start 0.2794 -0.1778)
							(mid 0.249642 -0.249642)
							(end 0.1778 -0.2794)
						)
					)
					(width 0)
					(fill yes)
				)
			)
		)
	)
	(footprint ""
		(layer "F.Cu")
		(at 206.883 -437.769 90)
		(property "Reference" "PR9087"
			(at 0 0 90)
			(layer "F.SilkS")
			(hide yes)
			(effects
				(font
					(size 1.27 1.27)
				)
			)
		)
		(property "Value" "0R6J-3-GP"
			(at -0.0508 -4.8514 90)
			(unlocked yes)
			(layer "F.Fab")
			(hide yes)
			(effects
				(font
					(size 1.016 1.016)
					(thickness 0.1524)
				)
			)
		)
		(property "Device Type" "R1206H28"
			(at 0 -6.3754 90)
			(unlocked yes)
			(layer "F.Fab")
			(hide yes)
			(effects
				(font
					(size 1.016 1.016)
					(thickness 0.1524)
				)
			)
		)
		(duplicate_pad_numbers_are_jumpers no)
		(fp_line
			(start 1.016 -2.2352)
			(end 1.016 2.2352)
			(stroke
				(width 0.1524)
				(type default)
			)
			(layer "F.SilkS")
		)
		(fp_line
			(start -1.016 -2.2352)
			(end 1.016 -2.2352)
			(stroke
				(width 0.1524)
				(type default)
			)
			(layer "F.SilkS")
		)
		(fp_line
			(start 1.016 2.2352)
			(end -1.016 2.2352)
			(stroke
				(width 0.1524)
				(type default)
			)
			(layer "F.SilkS")
		)
		(fp_line
			(start -1.016 2.2352)
			(end -1.016 -2.2352)
			(stroke
				(width 0.1524)
				(type default)
			)
			(layer "F.SilkS")
		)
		(fp_rect
			(start -1.0922 2.3114)
			(end 1.0922 -2.3114)
			(stroke
				(width 0)
				(type default)
			)
			(fill no)
			(layer "F.CrtYd")
		)
		(fp_poly
			(pts
				(xy -1.0922 -2.3114) (xy 1.0922 -2.3114) (xy 1.0922 2.3114) (xy -1.0922 2.3114)
			)
			(stroke
				(width 0)
				(type default)
			)
			(fill no)
			(layer "F.Fab")
		)
		(pad "1" smd rect
			(at 0 -1.397 90)
			(size 1.651 1.27)
			(layers "F.Cu" "F.Mask" "F.Paste")
			(net "P3V3")
		)
		(pad "2" smd rect
			(at 0 1.397 90)
			(size 1.651 1.27)
			(layers "F.Cu" "F.Mask" "F.Paste")
			(net "P3V3_OUT")
		)
	)
	(footprint ""
		(layer "F.Cu")
		(at 213.3981 -94.5261 180)
		(property "Reference" "R9806"
			(at 0 0 180)
			(layer "F.SilkS")
			(hide yes)
			(effects
				(font
					(size 1.27 1.27)
				)
			)
		)
		(property "Value" "47KR2J-2-GP"
			(at 0.064008 -3.993896 180)
			(unlocked yes)
			(layer "F.Fab")
			(hide yes)
			(effects
				(font
					(size 1.016 1.016)
					(thickness 0.1524)
				)
			)
		)
		(property "Device Type" "R402H16"
			(at 0.064008 -5.517896 180)
			(unlocked yes)
			(layer "F.Fab")
			(hide yes)
			(effects
				(font
					(size 1.016 1.016)
					(thickness 0.1524)
				)
			)
		)
		(duplicate_pad_numbers_are_jumpers no)
		(fp_line
			(start 0.508 -0.9398)
			(end -0.508 -0.9398)
			(stroke
				(width 0.1524)
				(type default)
			)
			(layer "F.SilkS")
		)
		(fp_line
			(start -0.508 -0.9398)
			(end -0.508 0.9398)
			(stroke
				(width 0.1524)
				(type default)
			)
			(layer "F.SilkS")
		)
		(fp_rect
			(start -0.508 0.9398)
			(end 0.508 -0.9398)
			(stroke
				(width 0)
				(type default)
			)
			(fill no)
			(layer "F.CrtYd")
		)
		(fp_rect
			(start -0.508 0.9398)
			(end 0.508 -0.9398)
			(stroke
				(width 0)
				(type default)
			)
			(fill no)
			(layer "F.Fab")
		)
		(pad "1" smd custom
			(at 0 -0.4445 180)
			(size 0.1397 0.1397)
			(layers "F.Cu" "F.Mask" "F.Paste")
			(net "P12V")
			(options
				(clearance outline)
				(anchor circle)
			)
			(primitives
				(gr_poly
					(pts
						(arc
							(start -0.1778 -0.2794)
							(mid -0.249642 -0.249642)
							(end -0.2794 -0.1778)
						)
						(arc
							(start -0.2794 0.1778)
							(mid -0.249642 0.249642)
							(end -0.1778 0.2794)
						)
						(arc
							(start 0.1778 0.2794)
							(mid 0.249642 0.249642)
							(end 0.2794 0.1778)
						)
						(arc
							(start 0.2794 -0.1778)
							(mid 0.249642 -0.249642)
							(end 0.1778 -0.2794)
						)
					)
					(width 0)
					(fill yes)
				)
			)
		)
		(pad "2" smd custom
			(at 0 0.4445 180)
			(size 0.1397 0.1397)
			(layers "F.Cu" "F.Mask" "F.Paste")
			(net "P12V_MOST4_GATE")
			(options
				(clearance outline)
				(anchor circle)
			)
			(primitives
				(gr_poly
					(pts
						(arc
							(start -0.1778 -0.2794)
							(mid -0.249642 -0.249642)
							(end -0.2794 -0.1778)
						)
						(arc
							(start -0.2794 0.1778)
							(mid -0.249642 0.249642)
							(end -0.1778 0.2794)
						)
						(arc
							(start 0.1778 0.2794)
							(mid 0.249642 0.249642)
							(end 0.2794 0.1778)
						)
						(arc
							(start 0.2794 -0.1778)
							(mid 0.249642 -0.249642)
							(end 0.1778 -0.2794)
						)
					)
					(width 0)
					(fill yes)
				)
			)
		)
	)
	(footprint ""
		(layer "F.Cu")
		(at 83.185 -150.622 -90)
		(property "Reference" "SR1049"
			(at 0 0 270)
			(layer "F.SilkS")
			(hide yes)
			(effects
				(font
					(size 1.27 1.27)
				)
			)
		)
		(property "Value" "4K7R2F-GP"
			(at 0.064008 -3.993896 270)
			(unlocked yes)
			(layer "F.Fab")
			(hide yes)
			(effects
				(font
					(size 1.016 1.016)
					(thickness 0.1524)
				)
			)
		)
		(property "Device Type" "R402H16"
			(at 0.064008 -5.517896 270)
			(unlocked yes)
			(layer "F.Fab")
			(hide yes)
			(effects
				(font
					(size 1.016 1.016)
					(thickness 0.1524)
				)
			)
		)
		(duplicate_pad_numbers_are_jumpers no)
		(fp_line
			(start -0.508 -0.9398)
			(end -0.508 0.9398)
			(stroke
				(width 0.1524)
				(type default)
			)
			(layer "F.SilkS")
		)
		(fp_line
			(start 0.508 -0.9398)
			(end -0.508 -0.9398)
			(stroke
				(width 0.1524)
				(type default)
			)
			(layer "F.SilkS")
		)
		(fp_rect
			(start -0.508 0.9398)
			(end 0.508 -0.9398)
			(stroke
				(width 0)
				(type default)
			)
			(fill no)
			(layer "F.CrtYd")
		)
		(fp_rect
			(start -0.508 0.9398)
			(end 0.508 -0.9398)
			(stroke
				(width 0)
				(type default)
			)
			(fill no)
			(layer "F.Fab")
		)
		(pad "1" smd custom
			(at 0 -0.4445 270)
			(size 0.1397 0.1397)
			(layers "F.Cu" "F.Mask" "F.Paste")
			(net "P3V3")
			(options
				(clearance outline)
				(anchor circle)
			)
			(primitives
				(gr_poly
					(pts
						(arc
							(start -0.1778 -0.2794)
							(mid -0.249642 -0.249642)
							(end -0.2794 -0.1778)
						)
						(arc
							(start -0.2794 0.1778)
							(mid -0.249642 0.249642)
							(end -0.1778 0.2794)
						)
						(arc
							(start 0.1778 0.2794)
							(mid 0.249642 0.249642)
							(end 0.2794 0.1778)
						)
						(arc
							(start 0.2794 -0.1778)
							(mid 0.249642 -0.249642)
							(end 0.1778 -0.2794)
						)
					)
					(width 0)
					(fill yes)
				)
			)
		)
		(pad "2" smd custom
			(at 0 0.4445 270)
			(size 0.1397 0.1397)
			(layers "F.Cu" "F.Mask" "F.Paste")
			(net "I2C_SW_EU16_ADDRESS_A0")
			(options
				(clearance outline)
				(anchor circle)
			)
			(primitives
				(gr_poly
					(pts
						(arc
							(start -0.1778 -0.2794)
							(mid -0.249642 -0.249642)
							(end -0.2794 -0.1778)
						)
						(arc
							(start -0.2794 0.1778)
							(mid -0.249642 0.249642)
							(end -0.1778 0.2794)
						)
						(arc
							(start 0.1778 0.2794)
							(mid 0.249642 0.249642)
							(end 0.2794 0.1778)
						)
						(arc
							(start 0.2794 -0.1778)
							(mid 0.249642 -0.249642)
							(end 0.1778 -0.2794)
						)
					)
					(width 0)
					(fill yes)
				)
			)
		)
	)
	(footprint ""
		(layer "F.Cu")
		(at 230.632 -243.199158 -90)
		(property "Reference" "R9797"
			(at 0 0 270)
			(layer "F.SilkS")
			(hide yes)
			(effects
				(font
					(size 1.27 1.27)
				)
			)
		)
		(property "Value" "0R2J-2-GP"
			(at 0.064008 -3.993896 270)
			(unlocked yes)
			(layer "F.Fab")
			(hide yes)
			(effects
				(font
					(size 1.016 1.016)
					(thickness 0.1524)
				)
			)
		)
		(property "Device Type" "R402H16"
			(at 0.064008 -5.517896 270)
			(unlocked yes)
			(layer "F.Fab")
			(hide yes)
			(effects
				(font
					(size 1.016 1.016)
					(thickness 0.1524)
				)
			)
		)
		(duplicate_pad_numbers_are_jumpers no)
		(fp_line
			(start -0.508 -0.9398)
			(end -0.508 0.9398)
			(stroke
				(width 0.1524)
				(type default)
			)
			(layer "F.SilkS")
		)
		(fp_line
			(start 0.508 -0.9398)
			(end -0.508 -0.9398)
			(stroke
				(width 0.1524)
				(type default)
			)
			(layer "F.SilkS")
		)
		(fp_rect
			(start -0.508 0.9398)
			(end 0.508 -0.9398)
			(stroke
				(width 0)
				(type default)
			)
			(fill no)
			(layer "F.CrtYd")
		)
		(fp_rect
			(start -0.508 0.9398)
			(end 0.508 -0.9398)
			(stroke
				(width 0)
				(type default)
			)
			(fill no)
			(layer "F.Fab")
		)
		(pad "1" smd custom
			(at 0 -0.4445 270)
			(size 0.1397 0.1397)
			(layers "F.Cu" "F.Mask" "F.Paste")
			(net "SSD_ACT_DR2_R")
			(options
				(clearance outline)
				(anchor circle)
			)
			(primitives
				(gr_poly
					(pts
						(arc
							(start -0.1778 -0.2794)
							(mid -0.249642 -0.249642)
							(end -0.2794 -0.1778)
						)
						(arc
							(start -0.2794 0.1778)
							(mid -0.249642 0.249642)
							(end -0.1778 0.2794)
						)
						(arc
							(start 0.1778 0.2794)
							(mid 0.249642 0.249642)
							(end 0.2794 0.1778)
						)
						(arc
							(start 0.2794 -0.1778)
							(mid 0.249642 -0.249642)
							(end 0.1778 -0.2794)
						)
					)
					(width 0)
					(fill yes)
				)
			)
		)
		(pad "2" smd custom
			(at 0 0.4445 270)
			(size 0.1397 0.1397)
			(layers "F.Cu" "F.Mask" "F.Paste")
			(net "SSD_ACT_DR2")
			(options
				(clearance outline)
				(anchor circle)
			)
			(primitives
				(gr_poly
					(pts
						(arc
							(start -0.1778 -0.2794)
							(mid -0.249642 -0.249642)
							(end -0.2794 -0.1778)
						)
						(arc
							(start -0.2794 0.1778)
							(mid -0.249642 0.249642)
							(end -0.1778 0.2794)
						)
						(arc
							(start 0.1778 0.2794)
							(mid 0.249642 0.249642)
							(end 0.2794 0.1778)
						)
						(arc
							(start 0.2794 -0.1778)
							(mid 0.249642 -0.249642)
							(end 0.1778 -0.2794)
						)
					)
					(width 0)
					(fill yes)
				)
			)
		)
	)
	(footprint ""
		(layer "F.Cu")
		(at 24.892 -262.886952 90)
		(property "Reference" "Q89"
			(at 0 0 90)
			(layer "F.SilkS")
			(hide yes)
			(effects
				(font
					(size 1.27 1.27)
				)
			)
		)
		(property "Value" "2N7002A-7-GP"
			(at 0.127 -8.9662 90)
			(unlocked yes)
			(layer "F.Fab")
			(hide yes)
			(effects
				(font
					(size 1.016 1.016)
					(thickness 0.1524)
				)
			)
		)
		(property "Device Type" "SOT23DGS2D4H48"
			(at 0.127 -10.4902 90)
			(unlocked yes)
			(layer "F.Fab")
			(hide yes)
			(effects
				(font
					(size 1.016 1.016)
					(thickness 0.1524)
				)
			)
		)
		(duplicate_pad_numbers_are_jumpers no)
		(fp_line
			(start 1.651 -1.778)
			(end -1.651 -1.778)
			(stroke
				(width 0.1524)
				(type default)
			)
			(layer "F.SilkS")
		)
		(fp_line
			(start -1.651 -1.778)
			(end -1.651 1.778)
			(stroke
				(width 0.1524)
				(type default)
			)
			(layer "F.SilkS")
		)
		(fp_line
			(start 1.651 1.778)
			(end 1.651 -1.778)
			(stroke
				(width 0.1524)
				(type default)
			)
			(layer "F.SilkS")
		)
		(fp_line
			(start -1.651 1.778)
			(end 1.651 1.778)
			(stroke
				(width 0.1524)
				(type default)
			)
			(layer "F.SilkS")
		)
		(fp_poly
			(pts
				(xy -1.778 1.8796) (xy -1.778 -1.8796) (xy 1.778 -1.8796) (xy 1.778 1.8796)
			)
			(stroke
				(width 0)
				(type default)
			)
			(fill no)
			(layer "F.CrtYd")
		)
		(fp_poly
			(pts
				(xy -1.778 1.8796) (xy -1.778 -1.8796) (xy 1.778 -1.8796) (xy 1.778 1.8796)
			)
			(stroke
				(width 0)
				(type default)
			)
			(fill no)
			(layer "F.Fab")
		)
		(pad "D" smd custom
			(at 0 -0.9525 90)
			(size 0.1905 0.1905)
			(layers "F.Cu" "F.Mask" "F.Paste")
			(net "SSD12_CLK0_OE_MOS_N")
			(options
				(clearance outline)
				(anchor circle)
			)
			(primitives
				(gr_poly
					(pts
						(arc
							(start -0.1778 0.5715)
							(mid -0.321484 0.511984)
							(end -0.381 0.3683)
						)
						(arc
							(start -0.381 -0.3683)
							(mid -0.321484 -0.511984)
							(end -0.1778 -0.5715)
						)
						(arc
							(start 0.1778 -0.5715)
							(mid 0.321484 -0.511984)
							(end 0.381 -0.3683)
						)
						(arc
							(start 0.381 0.3683)
							(mid 0.321484 0.511984)
							(end 0.1778 0.5715)
						)
					)
					(width 0)
					(fill yes)
				)
			)
		)
		(pad "G" smd custom
			(at -0.98425 0.9525 90)
			(size 0.1905 0.1905)
			(layers "F.Cu" "F.Mask" "F.Paste")
			(net "SSD12_CLK0_OE_R_N")
			(options
				(clearance outline)
				(anchor circle)
			)
			(primitives
				(gr_poly
					(pts
						(arc
							(start -0.1778 0.5715)
							(mid -0.321484 0.511984)
							(end -0.381 0.3683)
						)
						(arc
							(start -0.381 -0.3683)
							(mid -0.321484 -0.511984)
							(end -0.1778 -0.5715)
						)
						(arc
							(start 0.1778 -0.5715)
							(mid 0.321484 -0.511984)
							(end 0.381 -0.3683)
						)
						(arc
							(start 0.381 0.3683)
							(mid 0.321484 0.511984)
							(end 0.1778 0.5715)
						)
					)
					(width 0)
					(fill yes)
				)
			)
		)
		(pad "S" smd custom
			(at 0.98425 0.9525 90)
			(size 0.1905 0.1905)
			(layers "F.Cu" "F.Mask" "F.Paste")
			(net "GND")
			(options
				(clearance outline)
				(anchor circle)
			)
			(primitives
				(gr_poly
					(pts
						(arc
							(start -0.1778 0.5715)
							(mid -0.321484 0.511984)
							(end -0.381 0.3683)
						)
						(arc
							(start -0.381 -0.3683)
							(mid -0.321484 -0.511984)
							(end -0.1778 -0.5715)
						)
						(arc
							(start 0.1778 -0.5715)
							(mid 0.321484 -0.511984)
							(end 0.381 -0.3683)
						)
						(arc
							(start 0.381 0.3683)
							(mid 0.321484 0.511984)
							(end 0.1778 0.5715)
						)
					)
					(width 0)
					(fill yes)
				)
			)
		)
	)
	(footprint ""
		(layer "F.Cu")
		(at 49.022 -454.787 -90)
		(property "Reference" "R9414"
			(at 0 0 270)
			(layer "F.SilkS")
			(hide yes)
			(effects
				(font
					(size 1.27 1.27)
				)
			)
		)
		(property "Value" "330R2F-GP"
			(at 0.064008 -3.993896 270)
			(unlocked yes)
			(layer "F.Fab")
			(hide yes)
			(effects
				(font
					(size 1.016 1.016)
					(thickness 0.1524)
				)
			)
		)
		(property "Device Type" "R402H16"
			(at 0.064008 -5.517896 270)
			(unlocked yes)
			(layer "F.Fab")
			(hide yes)
			(effects
				(font
					(size 1.016 1.016)
					(thickness 0.1524)
				)
			)
		)
		(duplicate_pad_numbers_are_jumpers no)
		(fp_line
			(start -0.508 -0.9398)
			(end -0.508 0.9398)
			(stroke
				(width 0.1524)
				(type default)
			)
			(layer "F.SilkS")
		)
		(fp_line
			(start 0.508 -0.9398)
			(end -0.508 -0.9398)
			(stroke
				(width 0.1524)
				(type default)
			)
			(layer "F.SilkS")
		)
		(fp_rect
			(start -0.508 0.9398)
			(end 0.508 -0.9398)
			(stroke
				(width 0)
				(type default)
			)
			(fill no)
			(layer "F.CrtYd")
		)
		(fp_rect
			(start -0.508 0.9398)
			(end 0.508 -0.9398)
			(stroke
				(width 0)
				(type default)
			)
			(fill no)
			(layer "F.Fab")
		)
		(pad "1" smd custom
			(at 0 -0.4445 270)
			(size 0.1397 0.1397)
			(layers "F.Cu" "F.Mask" "F.Paste")
			(net "P3V3")
			(options
				(clearance outline)
				(anchor circle)
			)
			(primitives
				(gr_poly
					(pts
						(arc
							(start -0.1778 -0.2794)
							(mid -0.249642 -0.249642)
							(end -0.2794 -0.1778)
						)
						(arc
							(start -0.2794 0.1778)
							(mid -0.249642 0.249642)
							(end -0.1778 0.2794)
						)
						(arc
							(start 0.1778 0.2794)
							(mid 0.249642 0.249642)
							(end 0.2794 0.1778)
						)
						(arc
							(start 0.2794 -0.1778)
							(mid 0.249642 -0.249642)
							(end 0.1778 -0.2794)
						)
					)
					(width 0)
					(fill yes)
				)
			)
		)
		(pad "2" smd custom
			(at 0 0.4445 270)
			(size 0.1397 0.1397)
			(layers "F.Cu" "F.Mask" "F.Paste")
			(net "DRV_ATTN_5")
			(options
				(clearance outline)
				(anchor circle)
			)
			(primitives
				(gr_poly
					(pts
						(arc
							(start -0.1778 -0.2794)
							(mid -0.249642 -0.249642)
							(end -0.2794 -0.1778)
						)
						(arc
							(start -0.2794 0.1778)
							(mid -0.249642 0.249642)
							(end -0.1778 0.2794)
						)
						(arc
							(start 0.1778 0.2794)
							(mid 0.249642 0.249642)
							(end 0.2794 0.1778)
						)
						(arc
							(start 0.2794 -0.1778)
							(mid 0.249642 -0.249642)
							(end 0.1778 -0.2794)
						)
					)
					(width 0)
					(fill yes)
				)
			)
		)
	)
	(footprint ""
		(layer "F.Cu")
		(at 206.67345 -95.95485 90)
		(property "Reference" "R9805"
			(at 0 0 90)
			(layer "F.SilkS")
			(hide yes)
			(effects
				(font
					(size 1.27 1.27)
				)
			)
		)
		(property "Value" "1KR2J-1-GP"
			(at 0.064008 -3.993896 90)
			(unlocked yes)
			(layer "F.Fab")
			(hide yes)
			(effects
				(font
					(size 1.016 1.016)
					(thickness 0.1524)
				)
			)
		)
		(property "Device Type" "R402H16"
			(at 0.064008 -5.517896 90)
			(unlocked yes)
			(layer "F.Fab")
			(hide yes)
			(effects
				(font
					(size 1.016 1.016)
					(thickness 0.1524)
				)
			)
		)
		(duplicate_pad_numbers_are_jumpers no)
		(fp_line
			(start 0.508 -0.9398)
			(end -0.508 -0.9398)
			(stroke
				(width 0.1524)
				(type default)
			)
			(layer "F.SilkS")
		)
		(fp_line
			(start -0.508 -0.9398)
			(end -0.508 0.9398)
			(stroke
				(width 0.1524)
				(type default)
			)
			(layer "F.SilkS")
		)
		(fp_rect
			(start -0.508 0.9398)
			(end 0.508 -0.9398)
			(stroke
				(width 0)
				(type default)
			)
			(fill no)
			(layer "F.CrtYd")
		)
		(fp_rect
			(start -0.508 0.9398)
			(end 0.508 -0.9398)
			(stroke
				(width 0)
				(type default)
			)
			(fill no)
			(layer "F.Fab")
		)
		(pad "1" smd custom
			(at 0 -0.4445 90)
			(size 0.1397 0.1397)
			(layers "F.Cu" "F.Mask" "F.Paste")
			(net "SSD4_PWREN")
			(options
				(clearance outline)
				(anchor circle)
			)
			(primitives
				(gr_poly
					(pts
						(arc
							(start -0.1778 -0.2794)
							(mid -0.249642 -0.249642)
							(end -0.2794 -0.1778)
						)
						(arc
							(start -0.2794 0.1778)
							(mid -0.249642 0.249642)
							(end -0.1778 0.2794)
						)
						(arc
							(start 0.1778 0.2794)
							(mid 0.249642 0.249642)
							(end 0.2794 0.1778)
						)
						(arc
							(start 0.2794 -0.1778)
							(mid 0.249642 -0.249642)
							(end 0.1778 -0.2794)
						)
					)
					(width 0)
					(fill yes)
				)
			)
		)
		(pad "2" smd custom
			(at 0 0.4445 90)
			(size 0.1397 0.1397)
			(layers "F.Cu" "F.Mask" "F.Paste")
			(net "SSD4_PWREN_R")
			(options
				(clearance outline)
				(anchor circle)
			)
			(primitives
				(gr_poly
					(pts
						(arc
							(start -0.1778 -0.2794)
							(mid -0.249642 -0.249642)
							(end -0.2794 -0.1778)
						)
						(arc
							(start -0.2794 0.1778)
							(mid -0.249642 0.249642)
							(end -0.1778 0.2794)
						)
						(arc
							(start 0.1778 0.2794)
							(mid 0.249642 0.249642)
							(end 0.2794 0.1778)
						)
						(arc
							(start 0.2794 -0.1778)
							(mid 0.249642 -0.249642)
							(end 0.1778 -0.2794)
						)
					)
					(width 0)
					(fill yes)
				)
			)
		)
	)
	(footprint ""
		(layer "F.Cu")
		(at 224.625662 -421.703246 -90)
		(property "Reference" "PR9086"
			(at 0 0 270)
			(layer "F.SilkS")
			(hide yes)
			(effects
				(font
					(size 1.27 1.27)
				)
			)
		)
		(property "Value" "0R6J-3-GP"
			(at -0.0508 -4.8514 270)
			(unlocked yes)
			(layer "F.Fab")
			(hide yes)
			(effects
				(font
					(size 1.016 1.016)
					(thickness 0.1524)
				)
			)
		)
		(property "Device Type" "R1206H28"
			(at 0 -6.3754 270)
			(unlocked yes)
			(layer "F.Fab")
			(hide yes)
			(effects
				(font
					(size 1.016 1.016)
					(thickness 0.1524)
				)
			)
		)
		(duplicate_pad_numbers_are_jumpers no)
		(fp_line
			(start -1.016 2.2352)
			(end -1.016 -2.2352)
			(stroke
				(width 0.1524)
				(type default)
			)
			(layer "F.SilkS")
		)
		(fp_line
			(start 1.016 2.2352)
			(end -1.016 2.2352)
			(stroke
				(width 0.1524)
				(type default)
			)
			(layer "F.SilkS")
		)
		(fp_line
			(start -1.016 -2.2352)
			(end 1.016 -2.2352)
			(stroke
				(width 0.1524)
				(type default)
			)
			(layer "F.SilkS")
		)
		(fp_line
			(start 1.016 -2.2352)
			(end 1.016 2.2352)
			(stroke
				(width 0.1524)
				(type default)
			)
			(layer "F.SilkS")
		)
		(fp_rect
			(start -1.0922 2.3114)
			(end 1.0922 -2.3114)
			(stroke
				(width 0)
				(type default)
			)
			(fill no)
			(layer "F.CrtYd")
		)
		(fp_poly
			(pts
				(xy -1.0922 -2.3114) (xy 1.0922 -2.3114) (xy 1.0922 2.3114) (xy -1.0922 2.3114)
			)
			(stroke
				(width 0)
				(type default)
			)
			(fill no)
			(layer "F.Fab")
		)
		(pad "1" smd rect
			(at 0 -1.397 270)
			(size 1.651 1.27)
			(layers "F.Cu" "F.Mask" "F.Paste")
			(net "P3V3_VIN")
		)
		(pad "2" smd rect
			(at 0 1.397 270)
			(size 1.651 1.27)
			(layers "F.Cu" "F.Mask" "F.Paste")
			(net "P12V")
		)
	)
	(footprint ""
		(layer "F.Cu")
		(at 197.571106 -493.523778)
		(property "Reference" "D18"
			(at 0 0 0)
			(layer "F.SilkS")
			(hide yes)
			(effects
				(font
					(size 1.27 1.27)
				)
			)
		)
		(property "Value" "RB551V30-1-GP"
			(at 0 -6.7818 0)
			(unlocked yes)
			(layer "F.Fab")
			(hide yes)
			(effects
				(font
					(size 1.016 1.016)
					(thickness 0.1524)
				)
			)
		)
		(property "Device Type" "SOD323AKH44"
			(at 0 -8.6868 0)
			(unlocked yes)
			(layer "F.Fab")
			(hide yes)
			(effects
				(font
					(size 1.016 1.016)
					(thickness 0.1524)
				)
			)
		)
		(duplicate_pad_numbers_are_jumpers no)
		(fp_line
			(start -0.889 -1.9304)
			(end 0.889 -1.9304)
			(stroke
				(width 0.1524)
				(type default)
			)
			(layer "F.SilkS")
		)
		(fp_line
			(start -0.889 2.159)
			(end -0.889 -1.9304)
			(stroke
				(width 0.1524)
				(type default)
			)
			(layer "F.SilkS")
		)
		(fp_line
			(start 0.762 2.0574)
			(end -0.762 2.0574)
			(stroke
				(width 0.508)
				(type default)
			)
			(layer "F.SilkS")
		)
		(fp_line
			(start 0.889 -1.9304)
			(end 0.889 2.159)
			(stroke
				(width 0.1524)
				(type default)
			)
			(layer "F.SilkS")
		)
		(fp_line
			(start 0.889 2.159)
			(end -0.889 2.159)
			(stroke
				(width 0.1524)
				(type default)
			)
			(layer "F.SilkS")
		)
		(fp_rect
			(start -1.016 2.3114)
			(end 1.016 -2.0066)
			(stroke
				(width 0)
				(type default)
			)
			(fill no)
			(layer "F.CrtYd")
		)
		(fp_poly
			(pts
				(xy -1.016 -2.0066) (xy 1.016 -2.0066) (xy 1.016 2.3114) (xy -1.016 2.3114)
			)
			(stroke
				(width 0)
				(type default)
			)
			(fill no)
			(layer "F.Fab")
		)
		(pad "A" smd rect
			(at 0 -1.143)
			(size 0.5588 1.016)
			(layers "F.Cu" "F.Mask" "F.Paste")
			(net "SW_SSD0_R")
		)
		(pad "K" smd rect
			(at 0 1.143)
			(size 0.5588 1.016)
			(layers "F.Cu" "F.Mask" "F.Paste")
			(net "SW_SSD0_N")
		)
	)
	(footprint ""
		(layer "F.Cu")
		(at 227.203 -446.913 90)
		(property "Reference" "U197"
			(at 0 0 90)
			(layer "F.SilkS")
			(hide yes)
			(effects
				(font
					(size 1.27 1.27)
				)
			)
		)
		(property "Value" "SN74LVC1G08DCKR-GP"
			(at -2.3368 -8.6868 90)
			(unlocked yes)
			(layer "F.Fab")
			(hide yes)
			(effects
				(font
					(size 1.016 1.016)
					(thickness 0.1524)
				)
			)
		)
		(property "Device Type" "SC70-5H44"
			(at -2.3114 -10.414 90)
			(unlocked yes)
			(layer "F.Fab")
			(hide yes)
			(effects
				(font
					(size 1.016 1.016)
					(thickness 0.1524)
				)
			)
		)
		(duplicate_pad_numbers_are_jumpers no)
		(fp_line
			(start 1.3843 -1.8034)
			(end 1.3843 -1.1176)
			(stroke
				(width 0.3302)
				(type default)
			)
			(layer "F.SilkS")
		)
		(fp_line
			(start 0.6604 -1.8034)
			(end 1.3843 -1.8034)
			(stroke
				(width 0.3302)
				(type default)
			)
			(layer "F.SilkS")
		)
		(fp_line
			(start 1.27 -1.7018)
			(end 1.27 1.7018)
			(stroke
				(width 0.1524)
				(type default)
			)
			(layer "F.SilkS")
		)
		(fp_line
			(start -1.27 -1.7018)
			(end 1.27 -1.7018)
			(stroke
				(width 0.1524)
				(type default)
			)
			(layer "F.SilkS")
		)
		(fp_line
			(start 1.27 1.7018)
			(end -1.27 1.7018)
			(stroke
				(width 0.1524)
				(type default)
			)
			(layer "F.SilkS")
		)
		(fp_line
			(start -1.27 1.7018)
			(end -1.27 -1.7018)
			(stroke
				(width 0.1524)
				(type default)
			)
			(layer "F.SilkS")
		)
		(fp_rect
			(start -1.524 1.9558)
			(end 1.524 -1.9558)
			(stroke
				(width 0)
				(type default)
			)
			(fill no)
			(layer "F.CrtYd")
		)
		(fp_poly
			(pts
				(xy -1.524 -1.9558) (xy 1.524 -1.9558) (xy 1.524 1.9558) (xy -1.524 1.9558)
			)
			(stroke
				(width 0)
				(type default)
			)
			(fill no)
			(layer "F.Fab")
		)
		(pad "1" smd rect
			(at 0.65024 -0.8255 90)
			(size 0.4064 1.2192)
			(layers "F.Cu" "F.Mask" "F.Paste")
			(net "SSD0_CLK0_OE_MOS_N")
		)
		(pad "2" smd rect
			(at 0 -0.8255 90)
			(size 0.4064 1.2192)
			(layers "F.Cu" "F.Mask" "F.Paste")
			(net "ATTN_LED_DR0_N")
		)
		(pad "3" smd rect
			(at -0.65024 -0.8255 90)
			(size 0.4064 1.2192)
			(layers "F.Cu" "F.Mask" "F.Paste")
			(net "GND")
		)
		(pad "4" smd rect
			(at -0.65024 0.8255 90)
			(size 0.4064 1.2192)
			(layers "F.Cu" "F.Mask" "F.Paste")
			(net "ATTN_LED_DR0_AND")
		)
		(pad "5" smd rect
			(at 0.65024 0.8255 90)
			(size 0.4064 1.2192)
			(layers "F.Cu" "F.Mask" "F.Paste")
			(net "P3V3")
		)
	)
	(footprint ""
		(layer "F.Cu")
		(at 233.807 -138.80211 180)
		(property "Reference" "Q43"
			(at 0 0 180)
			(layer "F.SilkS")
			(hide yes)
			(effects
				(font
					(size 1.27 1.27)
				)
			)
		)
		(property "Value" "2N7002A-7-GP"
			(at 0.127 -8.9662 180)
			(unlocked yes)
			(layer "F.Fab")
			(hide yes)
			(effects
				(font
					(size 1.016 1.016)
					(thickness 0.1524)
				)
			)
		)
		(property "Device Type" "SOT23DGS2D4H48"
			(at 0.127 -10.4902 180)
			(unlocked yes)
			(layer "F.Fab")
			(hide yes)
			(effects
				(font
					(size 1.016 1.016)
					(thickness 0.1524)
				)
			)
		)
		(duplicate_pad_numbers_are_jumpers no)
		(fp_line
			(start 1.651 1.778)
			(end 1.651 -1.778)
			(stroke
				(width 0.1524)
				(type default)
			)
			(layer "F.SilkS")
		)
		(fp_line
			(start 1.651 -1.778)
			(end -1.651 -1.778)
			(stroke
				(width 0.1524)
				(type default)
			)
			(layer "F.SilkS")
		)
		(fp_line
			(start -1.651 1.778)
			(end 1.651 1.778)
			(stroke
				(width 0.1524)
				(type default)
			)
			(layer "F.SilkS")
		)
		(fp_line
			(start -1.651 -1.778)
			(end -1.651 1.778)
			(stroke
				(width 0.1524)
				(type default)
			)
			(layer "F.SilkS")
		)
		(fp_poly
			(pts
				(xy -1.778 1.8796) (xy -1.778 -1.8796) (xy 1.778 -1.8796) (xy 1.778 1.8796)
			)
			(stroke
				(width 0)
				(type default)
			)
			(fill no)
			(layer "F.CrtYd")
		)
		(fp_poly
			(pts
				(xy -1.778 1.8796) (xy -1.778 -1.8796) (xy 1.778 -1.8796) (xy 1.778 1.8796)
			)
			(stroke
				(width 0)
				(type default)
			)
			(fill no)
			(layer "F.Fab")
		)
		(pad "D" smd custom
			(at 0 -0.9525 180)
			(size 0.1905 0.1905)
			(layers "F.Cu" "F.Mask" "F.Paste")
			(net "SSD_ACT_DR3_MOS_N")
			(options
				(clearance outline)
				(anchor circle)
			)
			(primitives
				(gr_poly
					(pts
						(arc
							(start -0.1778 0.5715)
							(mid -0.321484 0.511984)
							(end -0.381 0.3683)
						)
						(arc
							(start -0.381 -0.3683)
							(mid -0.321484 -0.511984)
							(end -0.1778 -0.5715)
						)
						(arc
							(start 0.1778 -0.5715)
							(mid 0.321484 -0.511984)
							(end 0.381 -0.3683)
						)
						(arc
							(start 0.381 0.3683)
							(mid 0.321484 0.511984)
							(end 0.1778 0.5715)
						)
					)
					(width 0)
					(fill yes)
				)
			)
		)
		(pad "G" smd custom
			(at -0.98425 0.9525 180)
			(size 0.1905 0.1905)
			(layers "F.Cu" "F.Mask" "F.Paste")
			(net "ATTN_LED_DR3_AND_R")
			(options
				(clearance outline)
				(anchor circle)
			)
			(primitives
				(gr_poly
					(pts
						(arc
							(start -0.1778 0.5715)
							(mid -0.321484 0.511984)
							(end -0.381 0.3683)
						)
						(arc
							(start -0.381 -0.3683)
							(mid -0.321484 -0.511984)
							(end -0.1778 -0.5715)
						)
						(arc
							(start 0.1778 -0.5715)
							(mid 0.321484 -0.511984)
							(end 0.381 -0.3683)
						)
						(arc
							(start 0.381 0.3683)
							(mid 0.321484 0.511984)
							(end 0.1778 0.5715)
						)
					)
					(width 0)
					(fill yes)
				)
			)
		)
		(pad "S" smd custom
			(at 0.98425 0.9525 180)
			(size 0.1905 0.1905)
			(layers "F.Cu" "F.Mask" "F.Paste")
			(net "SSD_ACT_DR3_R")
			(options
				(clearance outline)
				(anchor circle)
			)
			(primitives
				(gr_poly
					(pts
						(arc
							(start -0.1778 0.5715)
							(mid -0.321484 0.511984)
							(end -0.381 0.3683)
						)
						(arc
							(start -0.381 -0.3683)
							(mid -0.321484 -0.511984)
							(end -0.1778 -0.5715)
						)
						(arc
							(start 0.1778 -0.5715)
							(mid 0.321484 -0.511984)
							(end 0.381 -0.3683)
						)
						(arc
							(start 0.381 0.3683)
							(mid 0.321484 0.511984)
							(end 0.1778 0.5715)
						)
					)
					(width 0)
					(fill yes)
				)
			)
		)
	)
	(footprint ""
		(layer "F.Cu")
		(at 220.0402 -395.6558)
		(property "Reference" "PC1236"
			(at 0 0 0)
			(layer "F.SilkS")
			(hide yes)
			(effects
				(font
					(size 1.27 1.27)
				)
			)
		)
		(property "Value" "SC22U25V6KX-GP-U"
			(at -2.860802 -5.279644 0)
			(unlocked yes)
			(layer "F.Fab")
			(hide yes)
			(effects
				(font
					(size 1.016 1.016)
					(thickness 0.1524)
				)
			)
		)
		(property "Device Type" "C1206-TO0D3H75"
			(at -2.860802 -6.803644 0)
			(unlocked yes)
			(layer "F.Fab")
			(hide yes)
			(effects
				(font
					(size 1.016 1.016)
					(thickness 0.1524)
				)
			)
		)
		(duplicate_pad_numbers_are_jumpers no)
		(fp_line
			(start -1.3081 -2.3749)
			(end 1.3081 -2.3749)
			(stroke
				(width 0.1524)
				(type default)
			)
			(layer "F.SilkS")
		)
		(fp_line
			(start -1.3081 2.3749)
			(end -1.3081 -2.3749)
			(stroke
				(width 0.1524)
				(type default)
			)
			(layer "F.SilkS")
		)
		(fp_line
			(start 1.3081 -2.3749)
			(end 1.3081 2.3749)
			(stroke
				(width 0.1524)
				(type default)
			)
			(layer "F.SilkS")
		)
		(fp_line
			(start 1.3081 2.3749)
			(end -1.3081 2.3749)
			(stroke
				(width 0.1524)
				(type default)
			)
			(layer "F.SilkS")
		)
		(fp_rect
			(start -0.8001 1.6002)
			(end 0.8001 -1.6002)
			(stroke
				(width 0)
				(type default)
			)
			(fill no)
			(layer "F.CrtYd")
		)
		(fp_poly
			(pts
				(xy -1.5621 2.4511) (xy -1.5621 1.6002) (xy 0.8001 1.6002) (xy 0.8001 -1.6002) (xy -0.8001 -1.6002)
				(xy -0.8001 1.5875) (xy -1.5621 1.5875) (xy -1.5621 -2.4511) (xy 1.5621 -2.4511) (xy 1.5621 2.4511)
			)
			(stroke
				(width 0)
				(type default)
			)
			(fill no)
			(layer "F.CrtYd")
		)
		(fp_rect
			(start -1.5621 2.4511)
			(end 1.5621 -2.4511)
			(stroke
				(width 0)
				(type default)
			)
			(fill no)
			(layer "F.Fab")
		)
		(pad "1" smd rect
			(at 0 -1.392936)
			(size 2.1082 1.4478)
			(layers "F.Cu" "F.Mask" "F.Paste")
			(net "P12V_SSD1")
		)
		(pad "2" smd rect
			(at 0 1.392936)
			(size 2.1082 1.4478)
			(layers "F.Cu" "F.Mask" "F.Paste")
			(net "GND")
		)
	)
	(footprint ""
		(layer "F.Cu")
		(at 199.222106 -491.110778)
		(property "Reference" "R551"
			(at 0 0 0)
			(layer "F.SilkS")
			(hide yes)
			(effects
				(font
					(size 1.27 1.27)
				)
			)
		)
		(property "Value" "200KR2F-L-GP"
			(at 0.064008 -3.993896 0)
			(unlocked yes)
			(layer "F.Fab")
			(hide yes)
			(effects
				(font
					(size 1.016 1.016)
					(thickness 0.1524)
				)
			)
		)
		(property "Device Type" "R402H16"
			(at 0.064008 -5.517896 0)
			(unlocked yes)
			(layer "F.Fab")
			(hide yes)
			(effects
				(font
					(size 1.016 1.016)
					(thickness 0.1524)
				)
			)
		)
		(duplicate_pad_numbers_are_jumpers no)
		(fp_line
			(start -0.508 -0.9398)
			(end -0.508 0.9398)
			(stroke
				(width 0.1524)
				(type default)
			)
			(layer "F.SilkS")
		)
		(fp_line
			(start 0.508 -0.9398)
			(end -0.508 -0.9398)
			(stroke
				(width 0.1524)
				(type default)
			)
			(layer "F.SilkS")
		)
		(fp_rect
			(start -0.508 0.9398)
			(end 0.508 -0.9398)
			(stroke
				(width 0)
				(type default)
			)
			(fill no)
			(layer "F.CrtYd")
		)
		(fp_rect
			(start -0.508 0.9398)
			(end 0.508 -0.9398)
			(stroke
				(width 0)
				(type default)
			)
			(fill no)
			(layer "F.Fab")
		)
		(pad "1" smd custom
			(at 0 -0.4445)
			(size 0.1397 0.1397)
			(layers "F.Cu" "F.Mask" "F.Paste")
			(net "SW_SSD0_R")
			(options
				(clearance outline)
				(anchor circle)
			)
			(primitives
				(gr_poly
					(pts
						(arc
							(start -0.1778 -0.2794)
							(mid -0.249642 -0.249642)
							(end -0.2794 -0.1778)
						)
						(arc
							(start -0.2794 0.1778)
							(mid -0.249642 0.249642)
							(end -0.1778 0.2794)
						)
						(arc
							(start 0.1778 0.2794)
							(mid 0.249642 0.249642)
							(end 0.2794 0.1778)
						)
						(arc
							(start 0.2794 -0.1778)
							(mid 0.249642 -0.249642)
							(end 0.1778 -0.2794)
						)
					)
					(width 0)
					(fill yes)
				)
			)
		)
		(pad "2" smd custom
			(at 0 0.4445)
			(size 0.1397 0.1397)
			(layers "F.Cu" "F.Mask" "F.Paste")
			(net "SW_SSD0_N")
			(options
				(clearance outline)
				(anchor circle)
			)
			(primitives
				(gr_poly
					(pts
						(arc
							(start -0.1778 -0.2794)
							(mid -0.249642 -0.249642)
							(end -0.2794 -0.1778)
						)
						(arc
							(start -0.2794 0.1778)
							(mid -0.249642 0.249642)
							(end -0.1778 0.2794)
						)
						(arc
							(start 0.1778 0.2794)
							(mid 0.249642 0.249642)
							(end 0.2794 0.1778)
						)
						(arc
							(start 0.2794 -0.1778)
							(mid 0.249642 -0.249642)
							(end 0.1778 -0.2794)
						)
					)
					(width 0)
					(fill yes)
				)
			)
		)
	)
	(footprint ""
		(layer "F.Cu")
		(at 208.153 -190.119)
		(property "Reference" "R554"
			(at 0 0 0)
			(layer "F.SilkS")
			(hide yes)
			(effects
				(font
					(size 1.27 1.27)
				)
			)
		)
		(property "Value" "200KR2F-L-GP"
			(at 0.064008 -3.993896 0)
			(unlocked yes)
			(layer "F.Fab")
			(hide yes)
			(effects
				(font
					(size 1.016 1.016)
					(thickness 0.1524)
				)
			)
		)
		(property "Device Type" "R402H16"
			(at 0.064008 -5.517896 0)
			(unlocked yes)
			(layer "F.Fab")
			(hide yes)
			(effects
				(font
					(size 1.016 1.016)
					(thickness 0.1524)
				)
			)
		)
		(duplicate_pad_numbers_are_jumpers no)
		(fp_line
			(start -0.508 -0.9398)
			(end -0.508 0.9398)
			(stroke
				(width 0.1524)
				(type default)
			)
			(layer "F.SilkS")
		)
		(fp_line
			(start 0.508 -0.9398)
			(end -0.508 -0.9398)
			(stroke
				(width 0.1524)
				(type default)
			)
			(layer "F.SilkS")
		)
		(fp_rect
			(start -0.508 0.9398)
			(end 0.508 -0.9398)
			(stroke
				(width 0)
				(type default)
			)
			(fill no)
			(layer "F.CrtYd")
		)
		(fp_rect
			(start -0.508 0.9398)
			(end 0.508 -0.9398)
			(stroke
				(width 0)
				(type default)
			)
			(fill no)
			(layer "F.Fab")
		)
		(pad "1" smd custom
			(at 0 -0.4445)
			(size 0.1397 0.1397)
			(layers "F.Cu" "F.Mask" "F.Paste")
			(net "SW_SSD3_R")
			(options
				(clearance outline)
				(anchor circle)
			)
			(primitives
				(gr_poly
					(pts
						(arc
							(start -0.1778 -0.2794)
							(mid -0.249642 -0.249642)
							(end -0.2794 -0.1778)
						)
						(arc
							(start -0.2794 0.1778)
							(mid -0.249642 0.249642)
							(end -0.1778 0.2794)
						)
						(arc
							(start 0.1778 0.2794)
							(mid 0.249642 0.249642)
							(end 0.2794 0.1778)
						)
						(arc
							(start 0.2794 -0.1778)
							(mid 0.249642 -0.249642)
							(end 0.1778 -0.2794)
						)
					)
					(width 0)
					(fill yes)
				)
			)
		)
		(pad "2" smd custom
			(at 0 0.4445)
			(size 0.1397 0.1397)
			(layers "F.Cu" "F.Mask" "F.Paste")
			(net "SW_SSD3_N")
			(options
				(clearance outline)
				(anchor circle)
			)
			(primitives
				(gr_poly
					(pts
						(arc
							(start -0.1778 -0.2794)
							(mid -0.249642 -0.249642)
							(end -0.2794 -0.1778)
						)
						(arc
							(start -0.2794 0.1778)
							(mid -0.249642 0.249642)
							(end -0.1778 0.2794)
						)
						(arc
							(start 0.1778 0.2794)
							(mid 0.249642 0.249642)
							(end 0.2794 0.1778)
						)
						(arc
							(start 0.2794 -0.1778)
							(mid 0.249642 -0.249642)
							(end 0.1778 -0.2794)
						)
					)
					(width 0)
					(fill yes)
				)
			)
		)
	)
	(footprint ""
		(layer "F.Cu")
		(at 77.4954 -100.2792)
		(property "Reference" "R9976"
			(at 0 0 0)
			(layer "F.SilkS")
			(hide yes)
			(effects
				(font
					(size 1.27 1.27)
				)
			)
		)
		(property "Value" "56R2F-1-GP"
			(at 0.064008 -3.993896 0)
			(unlocked yes)
			(layer "F.Fab")
			(hide yes)
			(effects
				(font
					(size 1.016 1.016)
					(thickness 0.1524)
				)
			)
		)
		(property "Device Type" "R402H16"
			(at 0.064008 -5.517896 0)
			(unlocked yes)
			(layer "F.Fab")
			(hide yes)
			(effects
				(font
					(size 1.016 1.016)
					(thickness 0.1524)
				)
			)
		)
		(duplicate_pad_numbers_are_jumpers no)
		(fp_line
			(start -0.508 -0.9398)
			(end -0.508 0.9398)
			(stroke
				(width 0.1524)
				(type default)
			)
			(layer "F.SilkS")
		)
		(fp_line
			(start 0.508 -0.9398)
			(end -0.508 -0.9398)
			(stroke
				(width 0.1524)
				(type default)
			)
			(layer "F.SilkS")
		)
		(fp_rect
			(start -0.508 0.9398)
			(end 0.508 -0.9398)
			(stroke
				(width 0)
				(type default)
			)
			(fill no)
			(layer "F.CrtYd")
		)
		(fp_rect
			(start -0.508 0.9398)
			(end 0.508 -0.9398)
			(stroke
				(width 0)
				(type default)
			)
			(fill no)
			(layer "F.Fab")
		)
		(pad "1" smd custom
			(at 0 -0.4445)
			(size 0.1397 0.1397)
			(layers "F.Cu" "F.Mask" "F.Paste")
			(net "PE_100M_CLK1_N")
			(options
				(clearance outline)
				(anchor circle)
			)
			(primitives
				(gr_poly
					(pts
						(arc
							(start -0.1778 -0.2794)
							(mid -0.249642 -0.249642)
							(end -0.2794 -0.1778)
						)
						(arc
							(start -0.2794 0.1778)
							(mid -0.249642 0.249642)
							(end -0.1778 0.2794)
						)
						(arc
							(start 0.1778 0.2794)
							(mid 0.249642 0.249642)
							(end 0.2794 0.1778)
						)
						(arc
							(start 0.2794 -0.1778)
							(mid 0.249642 -0.249642)
							(end 0.1778 -0.2794)
						)
					)
					(width 0)
					(fill yes)
				)
			)
		)
		(pad "2" smd custom
			(at 0 0.4445)
			(size 0.1397 0.1397)
			(layers "F.Cu" "F.Mask" "F.Paste")
			(net "GND")
			(options
				(clearance outline)
				(anchor circle)
			)
			(primitives
				(gr_poly
					(pts
						(arc
							(start -0.1778 -0.2794)
							(mid -0.249642 -0.249642)
							(end -0.2794 -0.1778)
						)
						(arc
							(start -0.2794 0.1778)
							(mid -0.249642 0.249642)
							(end -0.1778 0.2794)
						)
						(arc
							(start 0.1778 0.2794)
							(mid 0.249642 0.249642)
							(end 0.2794 0.1778)
						)
						(arc
							(start 0.2794 -0.1778)
							(mid 0.249642 -0.249642)
							(end 0.1778 -0.2794)
						)
					)
					(width 0)
					(fill yes)
				)
			)
		)
	)
	(footprint ""
		(layer "F.Cu")
		(at 234.061 -350.770952 -90)
		(property "Reference" "R9449"
			(at 0 0 270)
			(layer "F.SilkS")
			(hide yes)
			(effects
				(font
					(size 1.27 1.27)
				)
			)
		)
		(property "Value" "330R2F-GP"
			(at 0.064008 -3.993896 270)
			(unlocked yes)
			(layer "F.Fab")
			(hide yes)
			(effects
				(font
					(size 1.016 1.016)
					(thickness 0.1524)
				)
			)
		)
		(property "Device Type" "R402H16"
			(at 0.064008 -5.517896 270)
			(unlocked yes)
			(layer "F.Fab")
			(hide yes)
			(effects
				(font
					(size 1.016 1.016)
					(thickness 0.1524)
				)
			)
		)
		(duplicate_pad_numbers_are_jumpers no)
		(fp_line
			(start -0.508 -0.9398)
			(end -0.508 0.9398)
			(stroke
				(width 0.1524)
				(type default)
			)
			(layer "F.SilkS")
		)
		(fp_line
			(start 0.508 -0.9398)
			(end -0.508 -0.9398)
			(stroke
				(width 0.1524)
				(type default)
			)
			(layer "F.SilkS")
		)
		(fp_rect
			(start -0.508 0.9398)
			(end 0.508 -0.9398)
			(stroke
				(width 0)
				(type default)
			)
			(fill no)
			(layer "F.CrtYd")
		)
		(fp_rect
			(start -0.508 0.9398)
			(end 0.508 -0.9398)
			(stroke
				(width 0)
				(type default)
			)
			(fill no)
			(layer "F.Fab")
		)
		(pad "1" smd custom
			(at 0 -0.4445 270)
			(size 0.1397 0.1397)
			(layers "F.Cu" "F.Mask" "F.Paste")
			(net "P3V3")
			(options
				(clearance outline)
				(anchor circle)
			)
			(primitives
				(gr_poly
					(pts
						(arc
							(start -0.1778 -0.2794)
							(mid -0.249642 -0.249642)
							(end -0.2794 -0.1778)
						)
						(arc
							(start -0.2794 0.1778)
							(mid -0.249642 0.249642)
							(end -0.1778 0.2794)
						)
						(arc
							(start 0.1778 0.2794)
							(mid 0.249642 0.249642)
							(end 0.2794 0.1778)
						)
						(arc
							(start 0.2794 -0.1778)
							(mid 0.249642 -0.249642)
							(end 0.1778 -0.2794)
						)
					)
					(width 0)
					(fill yes)
				)
			)
		)
		(pad "2" smd custom
			(at 0 0.4445 270)
			(size 0.1397 0.1397)
			(layers "F.Cu" "F.Mask" "F.Paste")
			(net "DRV_ATTN_1")
			(options
				(clearance outline)
				(anchor circle)
			)
			(primitives
				(gr_poly
					(pts
						(arc
							(start -0.1778 -0.2794)
							(mid -0.249642 -0.249642)
							(end -0.2794 -0.1778)
						)
						(arc
							(start -0.2794 0.1778)
							(mid -0.249642 0.249642)
							(end -0.1778 0.2794)
						)
						(arc
							(start 0.1778 0.2794)
							(mid 0.249642 0.249642)
							(end 0.2794 0.1778)
						)
						(arc
							(start 0.2794 -0.1778)
							(mid 0.249642 -0.249642)
							(end 0.1778 -0.2794)
						)
					)
					(width 0)
					(fill yes)
				)
			)
		)
	)
	(footprint ""
		(layer "F.Cu")
		(at 207.391 -300.228 180)
		(property "Reference" "R9501"
			(at 0 0 180)
			(layer "F.SilkS")
			(hide yes)
			(effects
				(font
					(size 1.27 1.27)
				)
			)
		)
		(property "Value" "4K7R2J-2-GP"
			(at 0.064008 -3.993896 180)
			(unlocked yes)
			(layer "F.Fab")
			(hide yes)
			(effects
				(font
					(size 1.016 1.016)
					(thickness 0.1524)
				)
			)
		)
		(property "Device Type" "R402H16"
			(at 0.064008 -5.517896 180)
			(unlocked yes)
			(layer "F.Fab")
			(hide yes)
			(effects
				(font
					(size 1.016 1.016)
					(thickness 0.1524)
				)
			)
		)
		(duplicate_pad_numbers_are_jumpers no)
		(fp_line
			(start 0.508 -0.9398)
			(end -0.508 -0.9398)
			(stroke
				(width 0.1524)
				(type default)
			)
			(layer "F.SilkS")
		)
		(fp_line
			(start -0.508 -0.9398)
			(end -0.508 0.9398)
			(stroke
				(width 0.1524)
				(type default)
			)
			(layer "F.SilkS")
		)
		(fp_rect
			(start -0.508 0.9398)
			(end 0.508 -0.9398)
			(stroke
				(width 0)
				(type default)
			)
			(fill no)
			(layer "F.CrtYd")
		)
		(fp_rect
			(start -0.508 0.9398)
			(end 0.508 -0.9398)
			(stroke
				(width 0)
				(type default)
			)
			(fill no)
			(layer "F.Fab")
		)
		(pad "1" smd custom
			(at 0 -0.4445 180)
			(size 0.1397 0.1397)
			(layers "F.Cu" "F.Mask" "F.Paste")
			(net "P3V3")
			(options
				(clearance outline)
				(anchor circle)
			)
			(primitives
				(gr_poly
					(pts
						(arc
							(start -0.1778 -0.2794)
							(mid -0.249642 -0.249642)
							(end -0.2794 -0.1778)
						)
						(arc
							(start -0.2794 0.1778)
							(mid -0.249642 0.249642)
							(end -0.1778 0.2794)
						)
						(arc
							(start 0.1778 0.2794)
							(mid 0.249642 0.249642)
							(end 0.2794 0.1778)
						)
						(arc
							(start 0.2794 -0.1778)
							(mid 0.249642 -0.249642)
							(end 0.1778 -0.2794)
						)
					)
					(width 0)
					(fill yes)
				)
			)
		)
		(pad "2" smd custom
			(at 0 0.4445 180)
			(size 0.1397 0.1397)
			(layers "F.Cu" "F.Mask" "F.Paste")
			(net "SSD2_PWREN")
			(options
				(clearance outline)
				(anchor circle)
			)
			(primitives
				(gr_poly
					(pts
						(arc
							(start -0.1778 -0.2794)
							(mid -0.249642 -0.249642)
							(end -0.2794 -0.1778)
						)
						(arc
							(start -0.2794 0.1778)
							(mid -0.249642 0.249642)
							(end -0.1778 0.2794)
						)
						(arc
							(start 0.1778 0.2794)
							(mid 0.249642 0.249642)
							(end 0.2794 0.1778)
						)
						(arc
							(start 0.2794 -0.1778)
							(mid 0.249642 -0.249642)
							(end 0.1778 -0.2794)
						)
					)
					(width 0)
					(fill yes)
				)
			)
		)
	)
	(footprint ""
		(layer "F.Cu")
		(at 25.3238 -87.122)
		(property "Reference" "C391"
			(at 0 0 0)
			(layer "F.SilkS")
			(hide yes)
			(effects
				(font
					(size 1.27 1.27)
				)
			)
		)
		(property "Value" "SCD1U25V2KX-2-GP"
			(at 1.1811 -2.7051 0)
			(unlocked yes)
			(layer "F.Fab")
			(hide yes)
			(effects
				(font
					(size 1.016 1.016)
					(thickness 0.1524)
				)
			)
		)
		(property "Device Type" "C402H22"
			(at 1.1811 -4.2291 0)
			(unlocked yes)
			(layer "F.Fab")
			(hide yes)
			(effects
				(font
					(size 1.016 1.016)
					(thickness 0.1524)
				)
			)
		)
		(duplicate_pad_numbers_are_jumpers no)
		(fp_rect
			(start -0.4318 0.9525)
			(end 0.4318 -0.9525)
			(stroke
				(width 0)
				(type default)
			)
			(fill no)
			(layer "F.CrtYd")
		)
		(fp_rect
			(start -0.4318 0.9525)
			(end 0.4318 -0.9525)
			(stroke
				(width 0)
				(type default)
			)
			(fill no)
			(layer "F.Fab")
		)
		(pad "1" smd custom
			(at 0 -0.4445)
			(size 0.1524 0.1524)
			(layers "F.Cu" "F.Mask" "F.Paste")
			(net "P12V")
			(options
				(clearance outline)
				(anchor circle)
			)
			(primitives
				(gr_poly
					(pts
						(arc
							(start 0.3048 -0.2032)
							(mid 0.275042 -0.275042)
							(end 0.2032 -0.3048)
						)
						(arc
							(start -0.2032 -0.3048)
							(mid -0.275042 -0.275042)
							(end -0.3048 -0.2032)
						)
						(arc
							(start -0.3048 0.2032)
							(mid -0.275042 0.275042)
							(end -0.2032 0.3048)
						)
						(arc
							(start 0.2032 0.3048)
							(mid 0.275042 0.275042)
							(end 0.3048 0.2032)
						)
					)
					(width 0)
					(fill yes)
				)
			)
		)
		(pad "2" smd custom
			(at 0 0.4445)
			(size 0.1524 0.1524)
			(layers "F.Cu" "F.Mask" "F.Paste")
			(net "SW_SSD9_N")
			(options
				(clearance outline)
				(anchor circle)
			)
			(primitives
				(gr_poly
					(pts
						(arc
							(start 0.3048 -0.2032)
							(mid 0.275042 -0.275042)
							(end 0.2032 -0.3048)
						)
						(arc
							(start -0.2032 -0.3048)
							(mid -0.275042 -0.275042)
							(end -0.3048 -0.2032)
						)
						(arc
							(start -0.3048 0.2032)
							(mid -0.275042 0.275042)
							(end -0.2032 0.3048)
						)
						(arc
							(start 0.2032 0.3048)
							(mid 0.275042 0.275042)
							(end 0.3048 0.2032)
						)
					)
					(width 0)
					(fill yes)
				)
			)
		)
	)
	(footprint ""
		(layer "F.Cu")
		(at 91.313 -219.456 180)
		(property "Reference" "R9091"
			(at 0 0 180)
			(layer "F.SilkS")
			(hide yes)
			(effects
				(font
					(size 1.27 1.27)
				)
			)
		)
		(property "Value" "27R2F-GP"
			(at 0.064008 -3.993896 180)
			(unlocked yes)
			(layer "F.Fab")
			(hide yes)
			(effects
				(font
					(size 1.016 1.016)
					(thickness 0.1524)
				)
			)
		)
		(property "Device Type" "R402H16"
			(at 0.064008 -5.517896 180)
			(unlocked yes)
			(layer "F.Fab")
			(hide yes)
			(effects
				(font
					(size 1.016 1.016)
					(thickness 0.1524)
				)
			)
		)
		(duplicate_pad_numbers_are_jumpers no)
		(fp_line
			(start 0.508 -0.9398)
			(end -0.508 -0.9398)
			(stroke
				(width 0.1524)
				(type default)
			)
			(layer "F.SilkS")
		)
		(fp_line
			(start -0.508 -0.9398)
			(end -0.508 0.9398)
			(stroke
				(width 0.1524)
				(type default)
			)
			(layer "F.SilkS")
		)
		(fp_rect
			(start -0.508 0.9398)
			(end 0.508 -0.9398)
			(stroke
				(width 0)
				(type default)
			)
			(fill no)
			(layer "F.CrtYd")
		)
		(fp_rect
			(start -0.508 0.9398)
			(end 0.508 -0.9398)
			(stroke
				(width 0)
				(type default)
			)
			(fill no)
			(layer "F.Fab")
		)
		(pad "1" smd custom
			(at 0 -0.4445 180)
			(size 0.1397 0.1397)
			(layers "F.Cu" "F.Mask" "F.Paste")
			(net "PE_CLK_100M_DR12_2_R_P")
			(options
				(clearance outline)
				(anchor circle)
			)
			(primitives
				(gr_poly
					(pts
						(arc
							(start -0.1778 -0.2794)
							(mid -0.249642 -0.249642)
							(end -0.2794 -0.1778)
						)
						(arc
							(start -0.2794 0.1778)
							(mid -0.249642 0.249642)
							(end -0.1778 0.2794)
						)
						(arc
							(start 0.1778 0.2794)
							(mid 0.249642 0.249642)
							(end 0.2794 0.1778)
						)
						(arc
							(start 0.2794 -0.1778)
							(mid 0.249642 -0.249642)
							(end 0.1778 -0.2794)
						)
					)
					(width 0)
					(fill yes)
				)
			)
		)
		(pad "2" smd custom
			(at 0 0.4445 180)
			(size 0.1397 0.1397)
			(layers "F.Cu" "F.Mask" "F.Paste")
			(net "PE_CLK100M_DR12_2_P")
			(options
				(clearance outline)
				(anchor circle)
			)
			(primitives
				(gr_poly
					(pts
						(arc
							(start -0.1778 -0.2794)
							(mid -0.249642 -0.249642)
							(end -0.2794 -0.1778)
						)
						(arc
							(start -0.2794 0.1778)
							(mid -0.249642 0.249642)
							(end -0.1778 0.2794)
						)
						(arc
							(start 0.1778 0.2794)
							(mid 0.249642 0.249642)
							(end 0.2794 0.1778)
						)
						(arc
							(start 0.2794 -0.1778)
							(mid 0.249642 -0.249642)
							(end 0.1778 -0.2794)
						)
					)
					(width 0)
					(fill yes)
				)
			)
		)
	)
	(footprint ""
		(layer "F.Cu")
		(at 77.1144 -366.522)
		(property "Reference" "SR988"
			(at 0 0 0)
			(layer "F.SilkS")
			(hide yes)
			(effects
				(font
					(size 1.27 1.27)
				)
			)
		)
		(property "Value" "2KR2F-3-GP"
			(at 0.064008 -3.993896 0)
			(unlocked yes)
			(layer "F.Fab")
			(hide yes)
			(effects
				(font
					(size 1.016 1.016)
					(thickness 0.1524)
				)
			)
		)
		(property "Device Type" "R402H16"
			(at 0.064008 -5.517896 0)
			(unlocked yes)
			(layer "F.Fab")
			(hide yes)
			(effects
				(font
					(size 1.016 1.016)
					(thickness 0.1524)
				)
			)
		)
		(duplicate_pad_numbers_are_jumpers no)
		(fp_line
			(start -0.508 -0.9398)
			(end -0.508 0.9398)
			(stroke
				(width 0.1524)
				(type default)
			)
			(layer "F.SilkS")
		)
		(fp_line
			(start 0.508 -0.9398)
			(end -0.508 -0.9398)
			(stroke
				(width 0.1524)
				(type default)
			)
			(layer "F.SilkS")
		)
		(fp_rect
			(start -0.508 0.9398)
			(end 0.508 -0.9398)
			(stroke
				(width 0)
				(type default)
			)
			(fill no)
			(layer "F.CrtYd")
		)
		(fp_rect
			(start -0.508 0.9398)
			(end 0.508 -0.9398)
			(stroke
				(width 0)
				(type default)
			)
			(fill no)
			(layer "F.Fab")
		)
		(pad "1" smd custom
			(at 0 -0.4445)
			(size 0.1397 0.1397)
			(layers "F.Cu" "F.Mask" "F.Paste")
			(net "P3V3")
			(options
				(clearance outline)
				(anchor circle)
			)
			(primitives
				(gr_poly
					(pts
						(arc
							(start -0.1778 -0.2794)
							(mid -0.249642 -0.249642)
							(end -0.2794 -0.1778)
						)
						(arc
							(start -0.2794 0.1778)
							(mid -0.249642 0.249642)
							(end -0.1778 0.2794)
						)
						(arc
							(start 0.1778 0.2794)
							(mid 0.249642 0.249642)
							(end 0.2794 0.1778)
						)
						(arc
							(start 0.2794 -0.1778)
							(mid 0.249642 -0.249642)
							(end 0.1778 -0.2794)
						)
					)
					(width 0)
					(fill yes)
				)
			)
		)
		(pad "2" smd custom
			(at 0 0.4445)
			(size 0.1397 0.1397)
			(layers "F.Cu" "F.Mask" "F.Paste")
			(net "SCL_DR5")
			(options
				(clearance outline)
				(anchor circle)
			)
			(primitives
				(gr_poly
					(pts
						(arc
							(start -0.1778 -0.2794)
							(mid -0.249642 -0.249642)
							(end -0.2794 -0.1778)
						)
						(arc
							(start -0.2794 0.1778)
							(mid -0.249642 0.249642)
							(end -0.1778 0.2794)
						)
						(arc
							(start 0.1778 0.2794)
							(mid 0.249642 0.249642)
							(end 0.2794 0.1778)
						)
						(arc
							(start 0.2794 -0.1778)
							(mid 0.249642 -0.249642)
							(end 0.1778 -0.2794)
						)
					)
					(width 0)
					(fill yes)
				)
			)
		)
	)
	(footprint ""
		(layer "F.Cu")
		(at 45.466 -140.589 -90)
		(property "Reference" "C344"
			(at 0 0 270)
			(layer "F.SilkS")
			(hide yes)
			(effects
				(font
					(size 1.27 1.27)
				)
			)
		)
		(property "Value" "SCD1U16V2KX-3GP"
			(at 1.1811 -2.7051 270)
			(unlocked yes)
			(layer "F.Fab")
			(hide yes)
			(effects
				(font
					(size 1.016 1.016)
					(thickness 0.1524)
				)
			)
		)
		(property "Device Type" "C402H22"
			(at 1.1811 -4.2291 270)
			(unlocked yes)
			(layer "F.Fab")
			(hide yes)
			(effects
				(font
					(size 1.016 1.016)
					(thickness 0.1524)
				)
			)
		)
		(duplicate_pad_numbers_are_jumpers no)
		(fp_rect
			(start -0.4318 0.9525)
			(end 0.4318 -0.9525)
			(stroke
				(width 0)
				(type default)
			)
			(fill no)
			(layer "F.CrtYd")
		)
		(fp_rect
			(start -0.4318 0.9525)
			(end 0.4318 -0.9525)
			(stroke
				(width 0)
				(type default)
			)
			(fill no)
			(layer "F.Fab")
		)
		(pad "1" smd custom
			(at 0 -0.4445 270)
			(size 0.1524 0.1524)
			(layers "F.Cu" "F.Mask" "F.Paste")
			(net "P3V3")
			(options
				(clearance outline)
				(anchor circle)
			)
			(primitives
				(gr_poly
					(pts
						(arc
							(start 0.3048 -0.2032)
							(mid 0.275042 -0.275042)
							(end 0.2032 -0.3048)
						)
						(arc
							(start -0.2032 -0.3048)
							(mid -0.275042 -0.275042)
							(end -0.3048 -0.2032)
						)
						(arc
							(start -0.3048 0.2032)
							(mid -0.275042 0.275042)
							(end -0.2032 0.3048)
						)
						(arc
							(start 0.2032 0.3048)
							(mid 0.275042 0.275042)
							(end 0.3048 0.2032)
						)
					)
					(width 0)
					(fill yes)
				)
			)
		)
		(pad "2" smd custom
			(at 0 0.4445 270)
			(size 0.1524 0.1524)
			(layers "F.Cu" "F.Mask" "F.Paste")
			(net "GND")
			(options
				(clearance outline)
				(anchor circle)
			)
			(primitives
				(gr_poly
					(pts
						(arc
							(start 0.3048 -0.2032)
							(mid 0.275042 -0.275042)
							(end 0.2032 -0.3048)
						)
						(arc
							(start -0.2032 -0.3048)
							(mid -0.275042 -0.275042)
							(end -0.3048 -0.2032)
						)
						(arc
							(start -0.3048 0.2032)
							(mid -0.275042 0.275042)
							(end -0.2032 0.3048)
						)
						(arc
							(start 0.2032 0.3048)
							(mid 0.275042 0.275042)
							(end 0.3048 0.2032)
						)
					)
					(width 0)
					(fill yes)
				)
			)
		)
	)
	(footprint ""
		(layer "F.Cu")
		(at 225.1075 -450.4055 90)
		(property "Reference" "R9782"
			(at 0 0 90)
			(layer "F.SilkS")
			(hide yes)
			(effects
				(font
					(size 1.27 1.27)
				)
			)
		)
		(property "Value" "0R2J-2-GP"
			(at 0.064008 -3.993896 90)
			(unlocked yes)
			(layer "F.Fab")
			(hide yes)
			(effects
				(font
					(size 1.016 1.016)
					(thickness 0.1524)
				)
			)
		)
		(property "Device Type" "R402H16"
			(at 0.064008 -5.517896 90)
			(unlocked yes)
			(layer "F.Fab")
			(hide yes)
			(effects
				(font
					(size 1.016 1.016)
					(thickness 0.1524)
				)
			)
		)
		(duplicate_pad_numbers_are_jumpers no)
		(fp_line
			(start 0.508 -0.9398)
			(end -0.508 -0.9398)
			(stroke
				(width 0.1524)
				(type default)
			)
			(layer "F.SilkS")
		)
		(fp_line
			(start -0.508 -0.9398)
			(end -0.508 0.9398)
			(stroke
				(width 0.1524)
				(type default)
			)
			(layer "F.SilkS")
		)
		(fp_rect
			(start -0.508 0.9398)
			(end 0.508 -0.9398)
			(stroke
				(width 0)
				(type default)
			)
			(fill no)
			(layer "F.CrtYd")
		)
		(fp_rect
			(start -0.508 0.9398)
			(end 0.508 -0.9398)
			(stroke
				(width 0)
				(type default)
			)
			(fill no)
			(layer "F.Fab")
		)
		(pad "1" smd custom
			(at 0 -0.4445 90)
			(size 0.1397 0.1397)
			(layers "F.Cu" "F.Mask" "F.Paste")
			(net "ATTN_LED_DR0_R")
			(options
				(clearance outline)
				(anchor circle)
			)
			(primitives
				(gr_poly
					(pts
						(arc
							(start -0.1778 -0.2794)
							(mid -0.249642 -0.249642)
							(end -0.2794 -0.1778)
						)
						(arc
							(start -0.2794 0.1778)
							(mid -0.249642 0.249642)
							(end -0.1778 0.2794)
						)
						(arc
							(start 0.1778 0.2794)
							(mid 0.249642 0.249642)
							(end 0.2794 0.1778)
						)
						(arc
							(start 0.2794 -0.1778)
							(mid 0.249642 -0.249642)
							(end 0.1778 -0.2794)
						)
					)
					(width 0)
					(fill yes)
				)
			)
		)
		(pad "2" smd custom
			(at 0 0.4445 90)
			(size 0.1397 0.1397)
			(layers "F.Cu" "F.Mask" "F.Paste")
			(net "ATTN_LED_DR0_N")
			(options
				(clearance outline)
				(anchor circle)
			)
			(primitives
				(gr_poly
					(pts
						(arc
							(start -0.1778 -0.2794)
							(mid -0.249642 -0.249642)
							(end -0.2794 -0.1778)
						)
						(arc
							(start -0.2794 0.1778)
							(mid -0.249642 0.249642)
							(end -0.1778 0.2794)
						)
						(arc
							(start 0.1778 0.2794)
							(mid 0.249642 0.249642)
							(end 0.2794 0.1778)
						)
						(arc
							(start 0.2794 -0.1778)
							(mid 0.249642 -0.249642)
							(end 0.1778 -0.2794)
						)
					)
					(width 0)
					(fill yes)
				)
			)
		)
	)
	(footprint ""
		(layer "F.Cu")
		(at 107.442 -436.499 -90)
		(property "Reference" "R9591"
			(at 0 0 270)
			(layer "F.SilkS")
			(hide yes)
			(effects
				(font
					(size 1.27 1.27)
				)
			)
		)
		(property "Value" "10R2F-L-GP"
			(at 0.064008 -3.993896 270)
			(unlocked yes)
			(layer "F.Fab")
			(hide yes)
			(effects
				(font
					(size 1.016 1.016)
					(thickness 0.1524)
				)
			)
		)
		(property "Device Type" "R402H14"
			(at 0.064008 -5.517896 270)
			(unlocked yes)
			(layer "F.Fab")
			(hide yes)
			(effects
				(font
					(size 1.016 1.016)
					(thickness 0.1524)
				)
			)
		)
		(duplicate_pad_numbers_are_jumpers no)
		(fp_line
			(start -0.508 -0.9398)
			(end -0.508 0.9398)
			(stroke
				(width 0.1524)
				(type default)
			)
			(layer "F.SilkS")
		)
		(fp_line
			(start 0.508 -0.9398)
			(end -0.508 -0.9398)
			(stroke
				(width 0.1524)
				(type default)
			)
			(layer "F.SilkS")
		)
		(fp_rect
			(start -0.508 0.9398)
			(end 0.508 -0.9398)
			(stroke
				(width 0)
				(type default)
			)
			(fill no)
			(layer "F.CrtYd")
		)
		(fp_rect
			(start -0.508 0.9398)
			(end 0.508 -0.9398)
			(stroke
				(width 0)
				(type default)
			)
			(fill no)
			(layer "F.Fab")
		)
		(pad "1" smd custom
			(at 0 -0.4445 270)
			(size 0.1397 0.1397)
			(layers "F.Cu" "F.Mask" "F.Paste")
			(net "SSD0_CLK0_OE_N")
			(options
				(clearance outline)
				(anchor circle)
			)
			(primitives
				(gr_poly
					(pts
						(arc
							(start -0.1778 -0.2794)
							(mid -0.249642 -0.249642)
							(end -0.2794 -0.1778)
						)
						(arc
							(start -0.2794 0.1778)
							(mid -0.249642 0.249642)
							(end -0.1778 0.2794)
						)
						(arc
							(start 0.1778 0.2794)
							(mid 0.249642 0.249642)
							(end 0.2794 0.1778)
						)
						(arc
							(start 0.2794 -0.1778)
							(mid 0.249642 -0.249642)
							(end 0.1778 -0.2794)
						)
					)
					(width 0)
					(fill yes)
				)
			)
		)
		(pad "2" smd custom
			(at 0 0.4445 270)
			(size 0.1397 0.1397)
			(layers "F.Cu" "F.Mask" "F.Paste")
			(net "SSD0_CLK0_OE_R_N")
			(options
				(clearance outline)
				(anchor circle)
			)
			(primitives
				(gr_poly
					(pts
						(arc
							(start -0.1778 -0.2794)
							(mid -0.249642 -0.249642)
							(end -0.2794 -0.1778)
						)
						(arc
							(start -0.2794 0.1778)
							(mid -0.249642 0.249642)
							(end -0.1778 0.2794)
						)
						(arc
							(start 0.1778 0.2794)
							(mid 0.249642 0.249642)
							(end 0.2794 0.1778)
						)
						(arc
							(start 0.2794 -0.1778)
							(mid 0.249642 -0.249642)
							(end 0.1778 -0.2794)
						)
					)
					(width 0)
					(fill yes)
				)
			)
		)
	)
	(footprint ""
		(layer "F.Cu")
		(at 23.71725 -402.53285 -90)
		(property "Reference" "Q57"
			(at 0 0 270)
			(layer "F.SilkS")
			(hide yes)
			(effects
				(font
					(size 1.27 1.27)
				)
			)
		)
		(property "Value" "2N7002A-7-GP"
			(at 0.127 -8.9662 270)
			(unlocked yes)
			(layer "F.Fab")
			(hide yes)
			(effects
				(font
					(size 1.016 1.016)
					(thickness 0.1524)
				)
			)
		)
		(property "Device Type" "SOT23DGS2D4H48"
			(at 0.127 -10.4902 270)
			(unlocked yes)
			(layer "F.Fab")
			(hide yes)
			(effects
				(font
					(size 1.016 1.016)
					(thickness 0.1524)
				)
			)
		)
		(duplicate_pad_numbers_are_jumpers no)
		(fp_line
			(start -1.651 1.778)
			(end 1.651 1.778)
			(stroke
				(width 0.1524)
				(type default)
			)
			(layer "F.SilkS")
		)
		(fp_line
			(start 1.651 1.778)
			(end 1.651 -1.778)
			(stroke
				(width 0.1524)
				(type default)
			)
			(layer "F.SilkS")
		)
		(fp_line
			(start -1.651 -1.778)
			(end -1.651 1.778)
			(stroke
				(width 0.1524)
				(type default)
			)
			(layer "F.SilkS")
		)
		(fp_line
			(start 1.651 -1.778)
			(end -1.651 -1.778)
			(stroke
				(width 0.1524)
				(type default)
			)
			(layer "F.SilkS")
		)
		(fp_poly
			(pts
				(xy -1.778 1.8796) (xy -1.778 -1.8796) (xy 1.778 -1.8796) (xy 1.778 1.8796)
			)
			(stroke
				(width 0)
				(type default)
			)
			(fill no)
			(layer "F.CrtYd")
		)
		(fp_poly
			(pts
				(xy -1.778 1.8796) (xy -1.778 -1.8796) (xy 1.778 -1.8796) (xy 1.778 1.8796)
			)
			(stroke
				(width 0)
				(type default)
			)
			(fill no)
			(layer "F.Fab")
		)
		(pad "D" smd custom
			(at 0 -0.9525 270)
			(size 0.1905 0.1905)
			(layers "F.Cu" "F.Mask" "F.Paste")
			(net "P12V_MOST6_GATE")
			(options
				(clearance outline)
				(anchor circle)
			)
			(primitives
				(gr_poly
					(pts
						(arc
							(start -0.1778 0.5715)
							(mid -0.321484 0.511984)
							(end -0.381 0.3683)
						)
						(arc
							(start -0.381 -0.3683)
							(mid -0.321484 -0.511984)
							(end -0.1778 -0.5715)
						)
						(arc
							(start 0.1778 -0.5715)
							(mid 0.321484 -0.511984)
							(end 0.381 -0.3683)
						)
						(arc
							(start 0.381 0.3683)
							(mid 0.321484 0.511984)
							(end 0.1778 0.5715)
						)
					)
					(width 0)
					(fill yes)
				)
			)
		)
		(pad "G" smd custom
			(at -0.98425 0.9525 270)
			(size 0.1905 0.1905)
			(layers "F.Cu" "F.Mask" "F.Paste")
			(net "SSD6_PWREN_R")
			(options
				(clearance outline)
				(anchor circle)
			)
			(primitives
				(gr_poly
					(pts
						(arc
							(start -0.1778 0.5715)
							(mid -0.321484 0.511984)
							(end -0.381 0.3683)
						)
						(arc
							(start -0.381 -0.3683)
							(mid -0.321484 -0.511984)
							(end -0.1778 -0.5715)
						)
						(arc
							(start 0.1778 -0.5715)
							(mid 0.321484 -0.511984)
							(end 0.381 -0.3683)
						)
						(arc
							(start 0.381 0.3683)
							(mid 0.321484 0.511984)
							(end 0.1778 0.5715)
						)
					)
					(width 0)
					(fill yes)
				)
			)
		)
		(pad "S" smd custom
			(at 0.98425 0.9525 270)
			(size 0.1905 0.1905)
			(layers "F.Cu" "F.Mask" "F.Paste")
			(net "GND")
			(options
				(clearance outline)
				(anchor circle)
			)
			(primitives
				(gr_poly
					(pts
						(arc
							(start -0.1778 0.5715)
							(mid -0.321484 0.511984)
							(end -0.381 0.3683)
						)
						(arc
							(start -0.381 -0.3683)
							(mid -0.321484 -0.511984)
							(end -0.1778 -0.5715)
						)
						(arc
							(start 0.1778 -0.5715)
							(mid 0.321484 -0.511984)
							(end 0.381 -0.3683)
						)
						(arc
							(start 0.381 0.3683)
							(mid 0.321484 0.511984)
							(end 0.1778 0.5715)
						)
					)
					(width 0)
					(fill yes)
				)
			)
		)
	)
	(footprint ""
		(layer "F.Cu")
		(at 38.6334 -13.6652 180)
		(property "Reference" "PC1231"
			(at 0 0 180)
			(layer "F.SilkS")
			(hide yes)
			(effects
				(font
					(size 1.27 1.27)
				)
			)
		)
		(property "Value" "SC22U25V6KX-GP-U"
			(at -2.860802 -5.279644 180)
			(unlocked yes)
			(layer "F.Fab")
			(hide yes)
			(effects
				(font
					(size 1.016 1.016)
					(thickness 0.1524)
				)
			)
		)
		(property "Device Type" "C1206-TO0D3H75"
			(at -2.860802 -6.803644 180)
			(unlocked yes)
			(layer "F.Fab")
			(hide yes)
			(effects
				(font
					(size 1.016 1.016)
					(thickness 0.1524)
				)
			)
		)
		(duplicate_pad_numbers_are_jumpers no)
		(fp_line
			(start 1.3081 2.3749)
			(end -1.3081 2.3749)
			(stroke
				(width 0.1524)
				(type default)
			)
			(layer "F.SilkS")
		)
		(fp_line
			(start 1.3081 -2.3749)
			(end 1.3081 2.3749)
			(stroke
				(width 0.1524)
				(type default)
			)
			(layer "F.SilkS")
		)
		(fp_line
			(start -1.3081 2.3749)
			(end -1.3081 -2.3749)
			(stroke
				(width 0.1524)
				(type default)
			)
			(layer "F.SilkS")
		)
		(fp_line
			(start -1.3081 -2.3749)
			(end 1.3081 -2.3749)
			(stroke
				(width 0.1524)
				(type default)
			)
			(layer "F.SilkS")
		)
		(fp_rect
			(start -0.8001 1.6002)
			(end 0.8001 -1.6002)
			(stroke
				(width 0)
				(type default)
			)
			(fill no)
			(layer "F.CrtYd")
		)
		(fp_poly
			(pts
				(xy -1.5621 2.4511) (xy -1.5621 1.6002) (xy 0.8001 1.6002) (xy 0.8001 -1.6002) (xy -0.8001 -1.6002)
				(xy -0.8001 1.5875) (xy -1.5621 1.5875) (xy -1.5621 -2.4511) (xy 1.5621 -2.4511) (xy 1.5621 2.4511)
			)
			(stroke
				(width 0)
				(type default)
			)
			(fill no)
			(layer "F.CrtYd")
		)
		(fp_rect
			(start -1.5621 2.4511)
			(end 1.5621 -2.4511)
			(stroke
				(width 0)
				(type default)
			)
			(fill no)
			(layer "F.Fab")
		)
		(pad "1" smd rect
			(at 0 -1.392936 180)
			(size 2.1082 1.4478)
			(layers "F.Cu" "F.Mask" "F.Paste")
			(net "P12V_SSD14")
		)
		(pad "2" smd rect
			(at 0 1.392936 180)
			(size 2.1082 1.4478)
			(layers "F.Cu" "F.Mask" "F.Paste")
			(net "GND")
		)
	)
	(footprint ""
		(layer "F.Cu")
		(at 215.9 -403.9616 -90)
		(property "Reference" "Q32"
			(at 0 0 270)
			(layer "F.SilkS")
			(hide yes)
			(effects
				(font
					(size 1.27 1.27)
				)
			)
		)
		(property "Value" "2N7002A-7-GP"
			(at 0.127 -8.9662 270)
			(unlocked yes)
			(layer "F.Fab")
			(hide yes)
			(effects
				(font
					(size 1.016 1.016)
					(thickness 0.1524)
				)
			)
		)
		(property "Device Type" "SOT23DGS2D4H48"
			(at 0.127 -10.4902 270)
			(unlocked yes)
			(layer "F.Fab")
			(hide yes)
			(effects
				(font
					(size 1.016 1.016)
					(thickness 0.1524)
				)
			)
		)
		(duplicate_pad_numbers_are_jumpers no)
		(fp_line
			(start -1.651 1.778)
			(end 1.651 1.778)
			(stroke
				(width 0.1524)
				(type default)
			)
			(layer "F.SilkS")
		)
		(fp_line
			(start 1.651 1.778)
			(end 1.651 -1.778)
			(stroke
				(width 0.1524)
				(type default)
			)
			(layer "F.SilkS")
		)
		(fp_line
			(start -1.651 -1.778)
			(end -1.651 1.778)
			(stroke
				(width 0.1524)
				(type default)
			)
			(layer "F.SilkS")
		)
		(fp_line
			(start 1.651 -1.778)
			(end -1.651 -1.778)
			(stroke
				(width 0.1524)
				(type default)
			)
			(layer "F.SilkS")
		)
		(fp_poly
			(pts
				(xy -1.778 1.8796) (xy -1.778 -1.8796) (xy 1.778 -1.8796) (xy 1.778 1.8796)
			)
			(stroke
				(width 0)
				(type default)
			)
			(fill no)
			(layer "F.CrtYd")
		)
		(fp_poly
			(pts
				(xy -1.778 1.8796) (xy -1.778 -1.8796) (xy 1.778 -1.8796) (xy 1.778 1.8796)
			)
			(stroke
				(width 0)
				(type default)
			)
			(fill no)
			(layer "F.Fab")
		)
		(pad "D" smd custom
			(at 0 -0.9525 270)
			(size 0.1905 0.1905)
			(layers "F.Cu" "F.Mask" "F.Paste")
			(net "P12V_MOST1_GATE_D")
			(options
				(clearance outline)
				(anchor circle)
			)
			(primitives
				(gr_poly
					(pts
						(arc
							(start -0.1778 0.5715)
							(mid -0.321484 0.511984)
							(end -0.381 0.3683)
						)
						(arc
							(start -0.381 -0.3683)
							(mid -0.321484 -0.511984)
							(end -0.1778 -0.5715)
						)
						(arc
							(start 0.1778 -0.5715)
							(mid 0.321484 -0.511984)
							(end 0.381 -0.3683)
						)
						(arc
							(start 0.381 0.3683)
							(mid 0.321484 0.511984)
							(end 0.1778 0.5715)
						)
					)
					(width 0)
					(fill yes)
				)
			)
		)
		(pad "G" smd custom
			(at -0.98425 0.9525 270)
			(size 0.1905 0.1905)
			(layers "F.Cu" "F.Mask" "F.Paste")
			(net "P12V_MOST1_GATE")
			(options
				(clearance outline)
				(anchor circle)
			)
			(primitives
				(gr_poly
					(pts
						(arc
							(start -0.1778 0.5715)
							(mid -0.321484 0.511984)
							(end -0.381 0.3683)
						)
						(arc
							(start -0.381 -0.3683)
							(mid -0.321484 -0.511984)
							(end -0.1778 -0.5715)
						)
						(arc
							(start 0.1778 -0.5715)
							(mid 0.321484 -0.511984)
							(end 0.381 -0.3683)
						)
						(arc
							(start 0.381 0.3683)
							(mid 0.321484 0.511984)
							(end 0.1778 0.5715)
						)
					)
					(width 0)
					(fill yes)
				)
			)
		)
		(pad "S" smd custom
			(at 0.98425 0.9525 270)
			(size 0.1905 0.1905)
			(layers "F.Cu" "F.Mask" "F.Paste")
			(net "GND")
			(options
				(clearance outline)
				(anchor circle)
			)
			(primitives
				(gr_poly
					(pts
						(arc
							(start -0.1778 0.5715)
							(mid -0.321484 0.511984)
							(end -0.381 0.3683)
						)
						(arc
							(start -0.381 -0.3683)
							(mid -0.321484 -0.511984)
							(end -0.1778 -0.5715)
						)
						(arc
							(start 0.1778 -0.5715)
							(mid 0.321484 -0.511984)
							(end 0.381 -0.3683)
						)
						(arc
							(start 0.381 0.3683)
							(mid 0.321484 0.511984)
							(end 0.1778 0.5715)
						)
					)
					(width 0)
					(fill yes)
				)
			)
		)
	)
	(footprint ""
		(layer "F.Cu")
		(at 16.637 -491.363 180)
		(property "Reference" "R571"
			(at 0 0 180)
			(layer "F.SilkS")
			(hide yes)
			(effects
				(font
					(size 1.27 1.27)
				)
			)
		)
		(property "Value" "300KR2F-GP"
			(at 0.064008 -3.993896 180)
			(unlocked yes)
			(layer "F.Fab")
			(hide yes)
			(effects
				(font
					(size 1.016 1.016)
					(thickness 0.1524)
				)
			)
		)
		(property "Device Type" "R402H16"
			(at 0.064008 -5.517896 180)
			(unlocked yes)
			(layer "F.Fab")
			(hide yes)
			(effects
				(font
					(size 1.016 1.016)
					(thickness 0.1524)
				)
			)
		)
		(duplicate_pad_numbers_are_jumpers no)
		(fp_line
			(start 0.508 -0.9398)
			(end -0.508 -0.9398)
			(stroke
				(width 0.1524)
				(type default)
			)
			(layer "F.SilkS")
		)
		(fp_line
			(start -0.508 -0.9398)
			(end -0.508 0.9398)
			(stroke
				(width 0.1524)
				(type default)
			)
			(layer "F.SilkS")
		)
		(fp_rect
			(start -0.508 0.9398)
			(end 0.508 -0.9398)
			(stroke
				(width 0)
				(type default)
			)
			(fill no)
			(layer "F.CrtYd")
		)
		(fp_rect
			(start -0.508 0.9398)
			(end 0.508 -0.9398)
			(stroke
				(width 0)
				(type default)
			)
			(fill no)
			(layer "F.Fab")
		)
		(pad "1" smd custom
			(at 0 -0.4445 180)
			(size 0.1397 0.1397)
			(layers "F.Cu" "F.Mask" "F.Paste")
			(net "SW_SSD5_N")
			(options
				(clearance outline)
				(anchor circle)
			)
			(primitives
				(gr_poly
					(pts
						(arc
							(start -0.1778 -0.2794)
							(mid -0.249642 -0.249642)
							(end -0.2794 -0.1778)
						)
						(arc
							(start -0.2794 0.1778)
							(mid -0.249642 0.249642)
							(end -0.1778 0.2794)
						)
						(arc
							(start 0.1778 0.2794)
							(mid 0.249642 0.249642)
							(end 0.2794 0.1778)
						)
						(arc
							(start 0.2794 -0.1778)
							(mid 0.249642 -0.249642)
							(end 0.1778 -0.2794)
						)
					)
					(width 0)
					(fill yes)
				)
			)
		)
		(pad "2" smd custom
			(at 0 0.4445 180)
			(size 0.1397 0.1397)
			(layers "F.Cu" "F.Mask" "F.Paste")
			(net "P12V")
			(options
				(clearance outline)
				(anchor circle)
			)
			(primitives
				(gr_poly
					(pts
						(arc
							(start -0.1778 -0.2794)
							(mid -0.249642 -0.249642)
							(end -0.2794 -0.1778)
						)
						(arc
							(start -0.2794 0.1778)
							(mid -0.249642 0.249642)
							(end -0.1778 0.2794)
						)
						(arc
							(start 0.1778 0.2794)
							(mid 0.249642 0.249642)
							(end 0.2794 0.1778)
						)
						(arc
							(start 0.2794 -0.1778)
							(mid 0.249642 -0.249642)
							(end 0.1778 -0.2794)
						)
					)
					(width 0)
					(fill yes)
				)
			)
		)
	)
	(footprint ""
		(layer "F.Cu")
		(at 87.757 -317.246 -90)
		(property "Reference" "C9371"
			(at 0 0 270)
			(layer "F.SilkS")
			(hide yes)
			(effects
				(font
					(size 1.27 1.27)
				)
			)
		)
		(property "Value" "SC1KP50V2KX-1GP"
			(at 1.1811 -2.7051 270)
			(unlocked yes)
			(layer "F.Fab")
			(hide yes)
			(effects
				(font
					(size 1.016 1.016)
					(thickness 0.1524)
				)
			)
		)
		(property "Device Type" "C402H22"
			(at 1.1811 -4.2291 270)
			(unlocked yes)
			(layer "F.Fab")
			(hide yes)
			(effects
				(font
					(size 1.016 1.016)
					(thickness 0.1524)
				)
			)
		)
		(duplicate_pad_numbers_are_jumpers no)
		(fp_rect
			(start -0.4318 0.9525)
			(end 0.4318 -0.9525)
			(stroke
				(width 0)
				(type default)
			)
			(fill no)
			(layer "F.CrtYd")
		)
		(fp_rect
			(start -0.4318 0.9525)
			(end 0.4318 -0.9525)
			(stroke
				(width 0)
				(type default)
			)
			(fill no)
			(layer "F.Fab")
		)
		(pad "1" smd custom
			(at 0 -0.4445 270)
			(size 0.1524 0.1524)
			(layers "F.Cu" "F.Mask" "F.Paste")
			(net "SSD11_CLK0_OE_R_N")
			(options
				(clearance outline)
				(anchor circle)
			)
			(primitives
				(gr_poly
					(pts
						(arc
							(start 0.3048 -0.2032)
							(mid 0.275042 -0.275042)
							(end 0.2032 -0.3048)
						)
						(arc
							(start -0.2032 -0.3048)
							(mid -0.275042 -0.275042)
							(end -0.3048 -0.2032)
						)
						(arc
							(start -0.3048 0.2032)
							(mid -0.275042 0.275042)
							(end -0.2032 0.3048)
						)
						(arc
							(start 0.2032 0.3048)
							(mid 0.275042 0.275042)
							(end 0.3048 0.2032)
						)
					)
					(width 0)
					(fill yes)
				)
			)
		)
		(pad "2" smd custom
			(at 0 0.4445 270)
			(size 0.1524 0.1524)
			(layers "F.Cu" "F.Mask" "F.Paste")
			(net "GND")
			(options
				(clearance outline)
				(anchor circle)
			)
			(primitives
				(gr_poly
					(pts
						(arc
							(start 0.3048 -0.2032)
							(mid 0.275042 -0.275042)
							(end 0.2032 -0.3048)
						)
						(arc
							(start -0.2032 -0.3048)
							(mid -0.275042 -0.275042)
							(end -0.3048 -0.2032)
						)
						(arc
							(start -0.3048 0.2032)
							(mid -0.275042 0.275042)
							(end -0.2032 0.3048)
						)
						(arc
							(start 0.2032 0.3048)
							(mid 0.275042 0.275042)
							(end 0.3048 0.2032)
						)
					)
					(width 0)
					(fill yes)
				)
			)
		)
	)
	(footprint ""
		(layer "F.Cu")
		(at 36.2712 -95.3262 -90)
		(property "Reference" "R9838"
			(at 0 0 270)
			(layer "F.SilkS")
			(hide yes)
			(effects
				(font
					(size 1.27 1.27)
				)
			)
		)
		(property "Value" "2K2R5F-GP"
			(at 0 -8.9535 270)
			(unlocked yes)
			(layer "F.Fab")
			(hide yes)
			(effects
				(font
					(size 1.27 1.016)
					(thickness 0.1524)
				)
			)
		)
		(property "Device Type" "R805H24"
			(at 0 -10.6299 270)
			(unlocked yes)
			(layer "F.Fab")
			(hide yes)
			(effects
				(font
					(size 1.27 1.016)
					(thickness 0.1524)
				)
			)
		)
		(duplicate_pad_numbers_are_jumpers no)
		(fp_line
			(start -0.889 1.7018)
			(end 0.889 1.7018)
			(stroke
				(width 0.1524)
				(type default)
			)
			(layer "F.SilkS")
		)
		(fp_line
			(start 0.889 1.7018)
			(end 0.889 -0.508)
			(stroke
				(width 0.1524)
				(type default)
			)
			(layer "F.SilkS")
		)
		(fp_line
			(start -0.889 0.0762)
			(end -0.889 1.7018)
			(stroke
				(width 0.1524)
				(type default)
			)
			(layer "F.SilkS")
		)
		(fp_line
			(start -0.889 -1.7018)
			(end -0.889 0.2794)
			(stroke
				(width 0.1524)
				(type default)
			)
			(layer "F.SilkS")
		)
		(fp_line
			(start 0.889 -1.7018)
			(end 0.889 -0.381)
			(stroke
				(width 0.1524)
				(type default)
			)
			(layer "F.SilkS")
		)
		(fp_line
			(start 0.889 -1.7018)
			(end -0.889 -1.7018)
			(stroke
				(width 0.1524)
				(type default)
			)
			(layer "F.SilkS")
		)
		(fp_poly
			(pts
				(xy 0.9652 -1.778) (xy 0.9652 1.778) (xy -0.9652 1.778) (xy -0.9652 -1.778)
			)
			(stroke
				(width 0)
				(type default)
			)
			(fill no)
			(layer "F.CrtYd")
		)
		(fp_rect
			(start -0.9652 1.778)
			(end 0.9652 -1.778)
			(stroke
				(width 0)
				(type default)
			)
			(fill no)
			(layer "F.Fab")
		)
		(pad "1" smd rect
			(at 0 -0.9652 270)
			(size 1.397 1.143)
			(layers "F.Cu" "F.Mask" "F.Paste")
			(net "P12V_SSD9")
		)
		(pad "2" smd rect
			(at 0 0.9652 270)
			(size 1.397 1.143)
			(layers "F.Cu" "F.Mask" "F.Paste")
			(net "P12V_MOST9_GATE_D")
		)
	)
	(footprint ""
		(layer "F.Cu")
		(at 70.000114 -71.000112)
		(property "Reference" "H10"
			(at 0 0 0)
			(layer "F.SilkS")
			(hide yes)
			(effects
				(font
					(size 1.27 1.27)
				)
			)
		)
		(property "Value" "GEN276X162R197X296-6-F-A-GP"
			(at -6.7183 4.1402 0)
			(unlocked yes)
			(layer "F.Fab")
			(hide yes)
			(effects
				(font
					(size 1.016 1.016)
					(thickness 0.1524)
				)
			)
		)
		(property "Device Type" "GEN276X162R197X296-6-F-A"
			(at -6.7183 2.6162 0)
			(unlocked yes)
			(layer "F.Fab")
			(hide yes)
			(effects
				(font
					(size 1.016 1.016)
					(thickness 0.1524)
				)
			)
		)
		(duplicate_pad_numbers_are_jumpers no)
		(fp_poly
			(pts
				(arc
					(start 2.723642 4.777232)
					(mid -0.000169 6.508462)
					(end -2.723896 4.776978)
				)
				(arc
					(start -2.723896 4.776978)
					(mid 0.000173 -5.499012)
					(end 2.723642 4.777232)
				)
			)
			(stroke
				(width 0)
				(type default)
			)
			(fill no)
			(layer "B.CrtYd")
		)
		(fp_poly
			(pts
				(arc
					(start 2.723642 4.777232)
					(mid -0.000169 6.508462)
					(end -2.723896 4.776978)
				)
				(arc
					(start -2.723896 4.776978)
					(mid 0.000173 -5.499012)
					(end 2.723642 4.777232)
				)
			)
			(stroke
				(width 0)
				(type default)
			)
			(fill no)
			(layer "F.CrtYd")
		)
		(fp_poly
			(pts
				(arc
					(start 2.723642 4.777232)
					(mid -0.000169 6.508462)
					(end -2.723896 4.776978)
				)
				(arc
					(start -2.723896 4.776978)
					(mid 0.000173 -5.499012)
					(end 2.723642 4.777232)
				)
			)
			(stroke
				(width 0)
				(type default)
			)
			(fill no)
			(layer "B.Fab")
		)
		(fp_poly
			(pts
				(arc
					(start 2.723642 4.777232)
					(mid -0.000169 6.508462)
					(end -2.723896 4.776978)
				)
				(arc
					(start -2.723896 4.776978)
					(mid 0.000173 -5.499012)
					(end 2.723642 4.777232)
				)
			)
			(stroke
				(width 0)
				(type default)
			)
			(fill no)
			(layer "F.Fab")
		)
		(pad "" np_thru_hole circle
			(at 0 0)
			(size 0.254 0.254)
			(drill 0.0254)
			(layers "*.Cu" "*.Mask")
			(clearance 3.135376)
			(thermal_gap 3.135376)
		)
		(pad "1" thru_hole circle
			(at 2.549906 0)
			(size 0.8636 0.8636)
			(drill 0.508)
			(layers "*.Cu" "*.Mask")
			(remove_unused_layers no)
			(net "GND")
			(clearance 0.8255)
			(thermal_gap 0.8255)
		)
		(pad "2" thru_hole circle
			(at 2.210054 -1.27)
			(size 0.8636 0.8636)
			(drill 0.508)
			(layers "*.Cu" "*.Mask")
			(remove_unused_layers no)
			(net "GND")
			(clearance 0.8255)
			(thermal_gap 0.8255)
		)
		(pad "3" thru_hole circle
			(at 1.27 -2.210054)
			(size 0.8636 0.8636)
			(drill 0.508)
			(layers "*.Cu" "*.Mask")
			(remove_unused_layers no)
			(net "GND")
			(clearance 0.8255)
			(thermal_gap 0.8255)
		)
		(pad "4" thru_hole circle
			(at -1.279906 -2.210054)
			(size 0.8636 0.8636)
			(drill 0.508)
			(layers "*.Cu" "*.Mask")
			(remove_unused_layers no)
			(net "GND")
			(clearance 0.8255)
			(thermal_gap 0.8255)
		)
		(pad "5" thru_hole circle
			(at -2.210054 -1.27)
			(size 0.8636 0.8636)
			(drill 0.508)
			(layers "*.Cu" "*.Mask")
			(remove_unused_layers no)
			(net "GND")
			(clearance 0.8255)
			(thermal_gap 0.8255)
		)
		(pad "6" thru_hole circle
			(at -2.549906 0)
			(size 0.8636 0.8636)
			(drill 0.508)
			(layers "*.Cu" "*.Mask")
			(remove_unused_layers no)
			(net "GND")
			(clearance 0.8255)
			(thermal_gap 0.8255)
		)
		(zone
			(layers "F.Cu" "B.Cu" "In1.Cu" "In2.Cu" "In3.Cu" "In4.Cu" "In5.Cu" "In6.Cu")
			(hatch none 0.5)
			(connect_pads
				(clearance 0)
			)
			(min_thickness 0.25)
			(keepout
				(tracks allowed)
				(vias not_allowed)
				(pads allowed)
				(copperpour not_allowed)
				(footprints allowed)
			)
			(placement
				(enabled no)
				(sheetname "")
			)
			(fill
				(thermal_gap 0.5)
				(thermal_bridge_width 0.5)
				(island_removal_mode 0)
			)
			(polygon
				(pts
					(arc
						(start 74.318114 -71.00316)
						(mid 65.682114 -71.00316)
						(end 74.318114 -71.00316)
					)
				)
			)
		)
		(zone
			(layers "F.Cu" "B.Cu" "In1.Cu" "In2.Cu" "In3.Cu" "In4.Cu" "In5.Cu" "In6.Cu")
			(hatch none 0.5)
			(connect_pads
				(clearance 0)
			)
			(min_thickness 0.25)
			(keepout
				(tracks not_allowed)
				(vias allowed)
				(pads allowed)
				(copperpour not_allowed)
				(footprints allowed)
			)
			(placement
				(enabled no)
				(sheetname "")
			)
			(fill
				(thermal_gap 0.5)
				(thermal_bridge_width 0.5)
				(island_removal_mode 0)
			)
			(polygon
				(pts
					(arc
						(start 72.339454 -69.390768)
						(mid 70.000194 -64.491665)
						(end 67.66052 -69.390768)
					)
					(arc
						(start 67.66052 -69.390768)
						(mid 67.906487 -69.831134)
						(end 67.991736 -70.328282)
					)
					(arc
						(start 67.991736 -71.000112)
						(mid 70.000114 -73.00849)
						(end 72.008238 -71.000112)
					)
					(arc
						(start 72.008238 -70.328282)
						(mid 72.093473 -69.831128)
						(end 72.339454 -69.390768)
					)
				)
			)
		)
	)
	(footprint ""
		(layer "F.Cu")
		(at 45.9359 -7.4549)
		(property "Reference" "R9872"
			(at 0 0 0)
			(layer "F.SilkS")
			(hide yes)
			(effects
				(font
					(size 1.27 1.27)
				)
			)
		)
		(property "Value" "47KR2J-2-GP"
			(at 0.064008 -3.993896 0)
			(unlocked yes)
			(layer "F.Fab")
			(hide yes)
			(effects
				(font
					(size 1.016 1.016)
					(thickness 0.1524)
				)
			)
		)
		(property "Device Type" "R402H16"
			(at 0.064008 -5.517896 0)
			(unlocked yes)
			(layer "F.Fab")
			(hide yes)
			(effects
				(font
					(size 1.016 1.016)
					(thickness 0.1524)
				)
			)
		)
		(duplicate_pad_numbers_are_jumpers no)
		(fp_line
			(start -0.508 -0.9398)
			(end -0.508 0.9398)
			(stroke
				(width 0.1524)
				(type default)
			)
			(layer "F.SilkS")
		)
		(fp_line
			(start 0.508 -0.9398)
			(end -0.508 -0.9398)
			(stroke
				(width 0.1524)
				(type default)
			)
			(layer "F.SilkS")
		)
		(fp_rect
			(start -0.508 0.9398)
			(end 0.508 -0.9398)
			(stroke
				(width 0)
				(type default)
			)
			(fill no)
			(layer "F.CrtYd")
		)
		(fp_rect
			(start -0.508 0.9398)
			(end 0.508 -0.9398)
			(stroke
				(width 0)
				(type default)
			)
			(fill no)
			(layer "F.Fab")
		)
		(pad "1" smd custom
			(at 0 -0.4445)
			(size 0.1397 0.1397)
			(layers "F.Cu" "F.Mask" "F.Paste")
			(net "P12V")
			(options
				(clearance outline)
				(anchor circle)
			)
			(primitives
				(gr_poly
					(pts
						(arc
							(start -0.1778 -0.2794)
							(mid -0.249642 -0.249642)
							(end -0.2794 -0.1778)
						)
						(arc
							(start -0.2794 0.1778)
							(mid -0.249642 0.249642)
							(end -0.1778 0.2794)
						)
						(arc
							(start 0.1778 0.2794)
							(mid 0.249642 0.249642)
							(end 0.2794 0.1778)
						)
						(arc
							(start 0.2794 -0.1778)
							(mid 0.249642 -0.249642)
							(end 0.1778 -0.2794)
						)
					)
					(width 0)
					(fill yes)
				)
			)
		)
		(pad "2" smd custom
			(at 0 0.4445)
			(size 0.1397 0.1397)
			(layers "F.Cu" "F.Mask" "F.Paste")
			(net "P12V_MOST14_GATE")
			(options
				(clearance outline)
				(anchor circle)
			)
			(primitives
				(gr_poly
					(pts
						(arc
							(start -0.1778 -0.2794)
							(mid -0.249642 -0.249642)
							(end -0.2794 -0.1778)
						)
						(arc
							(start -0.2794 0.1778)
							(mid -0.249642 0.249642)
							(end -0.1778 0.2794)
						)
						(arc
							(start 0.1778 0.2794)
							(mid 0.249642 0.249642)
							(end 0.2794 0.1778)
						)
						(arc
							(start 0.2794 -0.1778)
							(mid 0.249642 -0.249642)
							(end 0.1778 -0.2794)
						)
					)
					(width 0)
					(fill yes)
				)
			)
		)
	)
	(footprint ""
		(layer "F.Cu")
		(at 217.043 -390.525 -90)
		(property "Reference" "R385"
			(at 0 0 270)
			(layer "F.SilkS")
			(hide yes)
			(effects
				(font
					(size 1.27 1.27)
				)
			)
		)
		(property "Value" "0R2J-2-GP"
			(at 0.064008 -3.993896 270)
			(unlocked yes)
			(layer "F.Fab")
			(hide yes)
			(effects
				(font
					(size 1.016 1.016)
					(thickness 0.1524)
				)
			)
		)
		(property "Device Type" "R402H16"
			(at 0.064008 -5.517896 270)
			(unlocked yes)
			(layer "F.Fab")
			(hide yes)
			(effects
				(font
					(size 1.016 1.016)
					(thickness 0.1524)
				)
			)
		)
		(duplicate_pad_numbers_are_jumpers no)
		(fp_line
			(start -0.508 -0.9398)
			(end -0.508 0.9398)
			(stroke
				(width 0.1524)
				(type default)
			)
			(layer "F.SilkS")
		)
		(fp_line
			(start 0.508 -0.9398)
			(end -0.508 -0.9398)
			(stroke
				(width 0.1524)
				(type default)
			)
			(layer "F.SilkS")
		)
		(fp_rect
			(start -0.508 0.9398)
			(end 0.508 -0.9398)
			(stroke
				(width 0)
				(type default)
			)
			(fill no)
			(layer "F.CrtYd")
		)
		(fp_rect
			(start -0.508 0.9398)
			(end 0.508 -0.9398)
			(stroke
				(width 0)
				(type default)
			)
			(fill no)
			(layer "F.Fab")
		)
		(pad "1" smd custom
			(at 0 -0.4445 270)
			(size 0.1397 0.1397)
			(layers "F.Cu" "F.Mask" "F.Paste")
			(net "SCL_DR1_R")
			(options
				(clearance outline)
				(anchor circle)
			)
			(primitives
				(gr_poly
					(pts
						(arc
							(start -0.1778 -0.2794)
							(mid -0.249642 -0.249642)
							(end -0.2794 -0.1778)
						)
						(arc
							(start -0.2794 0.1778)
							(mid -0.249642 0.249642)
							(end -0.1778 0.2794)
						)
						(arc
							(start 0.1778 0.2794)
							(mid 0.249642 0.249642)
							(end 0.2794 0.1778)
						)
						(arc
							(start 0.2794 -0.1778)
							(mid 0.249642 -0.249642)
							(end 0.1778 -0.2794)
						)
					)
					(width 0)
					(fill yes)
				)
			)
		)
		(pad "2" smd custom
			(at 0 0.4445 270)
			(size 0.1397 0.1397)
			(layers "F.Cu" "F.Mask" "F.Paste")
			(net "SCL_DR1")
			(options
				(clearance outline)
				(anchor circle)
			)
			(primitives
				(gr_poly
					(pts
						(arc
							(start -0.1778 -0.2794)
							(mid -0.249642 -0.249642)
							(end -0.2794 -0.1778)
						)
						(arc
							(start -0.2794 0.1778)
							(mid -0.249642 0.249642)
							(end -0.1778 0.2794)
						)
						(arc
							(start 0.1778 0.2794)
							(mid 0.249642 0.249642)
							(end 0.2794 0.1778)
						)
						(arc
							(start 0.2794 -0.1778)
							(mid 0.249642 -0.249642)
							(end 0.1778 -0.2794)
						)
					)
					(width 0)
					(fill yes)
				)
			)
		)
	)
	(footprint ""
		(layer "F.Cu")
		(at 39.116 -308.737)
		(property "Reference" "R9752"
			(at 0 0 0)
			(layer "F.SilkS")
			(hide yes)
			(effects
				(font
					(size 1.27 1.27)
				)
			)
		)
		(property "Value" "4K7R2J-2-GP"
			(at 0.064008 -3.993896 0)
			(unlocked yes)
			(layer "F.Fab")
			(hide yes)
			(effects
				(font
					(size 1.016 1.016)
					(thickness 0.1524)
				)
			)
		)
		(property "Device Type" "R402H16"
			(at 0.064008 -5.517896 0)
			(unlocked yes)
			(layer "F.Fab")
			(hide yes)
			(effects
				(font
					(size 1.016 1.016)
					(thickness 0.1524)
				)
			)
		)
		(duplicate_pad_numbers_are_jumpers no)
		(fp_line
			(start -0.508 -0.9398)
			(end -0.508 0.9398)
			(stroke
				(width 0.1524)
				(type default)
			)
			(layer "F.SilkS")
		)
		(fp_line
			(start 0.508 -0.9398)
			(end -0.508 -0.9398)
			(stroke
				(width 0.1524)
				(type default)
			)
			(layer "F.SilkS")
		)
		(fp_rect
			(start -0.508 0.9398)
			(end 0.508 -0.9398)
			(stroke
				(width 0)
				(type default)
			)
			(fill no)
			(layer "F.CrtYd")
		)
		(fp_rect
			(start -0.508 0.9398)
			(end 0.508 -0.9398)
			(stroke
				(width 0)
				(type default)
			)
			(fill no)
			(layer "F.Fab")
		)
		(pad "1" smd custom
			(at 0 -0.4445)
			(size 0.1397 0.1397)
			(layers "F.Cu" "F.Mask" "F.Paste")
			(net "P3V3")
			(options
				(clearance outline)
				(anchor circle)
			)
			(primitives
				(gr_poly
					(pts
						(arc
							(start -0.1778 -0.2794)
							(mid -0.249642 -0.249642)
							(end -0.2794 -0.1778)
						)
						(arc
							(start -0.2794 0.1778)
							(mid -0.249642 0.249642)
							(end -0.1778 0.2794)
						)
						(arc
							(start 0.1778 0.2794)
							(mid 0.249642 0.249642)
							(end 0.2794 0.1778)
						)
						(arc
							(start 0.2794 -0.1778)
							(mid 0.249642 -0.249642)
							(end 0.1778 -0.2794)
						)
					)
					(width 0)
					(fill yes)
				)
			)
		)
		(pad "2" smd custom
			(at 0 0.4445)
			(size 0.1397 0.1397)
			(layers "F.Cu" "F.Mask" "F.Paste")
			(net "SSD11_PWREN")
			(options
				(clearance outline)
				(anchor circle)
			)
			(primitives
				(gr_poly
					(pts
						(arc
							(start -0.1778 -0.2794)
							(mid -0.249642 -0.249642)
							(end -0.2794 -0.1778)
						)
						(arc
							(start -0.2794 0.1778)
							(mid -0.249642 0.249642)
							(end -0.1778 0.2794)
						)
						(arc
							(start 0.1778 0.2794)
							(mid 0.249642 0.249642)
							(end 0.2794 0.1778)
						)
						(arc
							(start 0.2794 -0.1778)
							(mid 0.249642 -0.249642)
							(end 0.1778 -0.2794)
						)
					)
					(width 0)
					(fill yes)
				)
			)
		)
	)
	(footprint ""
		(layer "F.Cu")
		(at 7.9248 -451.8279 -90)
		(property "Reference" "C9541"
			(at 0 0 270)
			(layer "F.SilkS")
			(hide yes)
			(effects
				(font
					(size 1.27 1.27)
				)
			)
		)
		(property "Value" "SCD01U50V2KX-1GP"
			(at 1.1811 -2.7051 270)
			(unlocked yes)
			(layer "F.Fab")
			(hide yes)
			(effects
				(font
					(size 1.016 1.016)
					(thickness 0.1524)
				)
			)
		)
		(property "Device Type" "C402H22"
			(at 1.1811 -4.2291 270)
			(unlocked yes)
			(layer "F.Fab")
			(hide yes)
			(effects
				(font
					(size 1.016 1.016)
					(thickness 0.1524)
				)
			)
		)
		(duplicate_pad_numbers_are_jumpers no)
		(fp_rect
			(start -0.4318 0.9525)
			(end 0.4318 -0.9525)
			(stroke
				(width 0)
				(type default)
			)
			(fill no)
			(layer "F.CrtYd")
		)
		(fp_rect
			(start -0.4318 0.9525)
			(end 0.4318 -0.9525)
			(stroke
				(width 0)
				(type default)
			)
			(fill no)
			(layer "F.Fab")
		)
		(pad "1" smd custom
			(at 0 -0.4445 270)
			(size 0.1524 0.1524)
			(layers "F.Cu" "F.Mask" "F.Paste")
			(net "PE_100M_CLK4_N")
			(options
				(clearance outline)
				(anchor circle)
			)
			(primitives
				(gr_poly
					(pts
						(arc
							(start 0.3048 -0.2032)
							(mid 0.275042 -0.275042)
							(end 0.2032 -0.3048)
						)
						(arc
							(start -0.2032 -0.3048)
							(mid -0.275042 -0.275042)
							(end -0.3048 -0.2032)
						)
						(arc
							(start -0.3048 0.2032)
							(mid -0.275042 0.275042)
							(end -0.2032 0.3048)
						)
						(arc
							(start 0.2032 0.3048)
							(mid 0.275042 0.275042)
							(end 0.3048 0.2032)
						)
					)
					(width 0)
					(fill yes)
				)
			)
		)
		(pad "2" smd custom
			(at 0 0.4445 270)
			(size 0.1524 0.1524)
			(layers "F.Cu" "F.Mask" "F.Paste")
			(net "PE_100M_CLK4_C_N")
			(options
				(clearance outline)
				(anchor circle)
			)
			(primitives
				(gr_poly
					(pts
						(arc
							(start 0.3048 -0.2032)
							(mid 0.275042 -0.275042)
							(end 0.2032 -0.3048)
						)
						(arc
							(start -0.2032 -0.3048)
							(mid -0.275042 -0.275042)
							(end -0.3048 -0.2032)
						)
						(arc
							(start -0.3048 0.2032)
							(mid -0.275042 0.275042)
							(end -0.2032 0.3048)
						)
						(arc
							(start 0.2032 0.3048)
							(mid 0.275042 0.275042)
							(end 0.3048 0.2032)
						)
					)
					(width 0)
					(fill yes)
				)
			)
		)
	)
	(footprint ""
		(layer "F.Cu")
		(at 102.616 -311.531 90)
		(property "Reference" "R9073"
			(at 0 0 90)
			(layer "F.SilkS")
			(hide yes)
			(effects
				(font
					(size 1.27 1.27)
				)
			)
		)
		(property "Value" "27R2F-GP"
			(at 0.064008 -3.993896 90)
			(unlocked yes)
			(layer "F.Fab")
			(hide yes)
			(effects
				(font
					(size 1.016 1.016)
					(thickness 0.1524)
				)
			)
		)
		(property "Device Type" "R402H16"
			(at 0.064008 -5.517896 90)
			(unlocked yes)
			(layer "F.Fab")
			(hide yes)
			(effects
				(font
					(size 1.016 1.016)
					(thickness 0.1524)
				)
			)
		)
		(duplicate_pad_numbers_are_jumpers no)
		(fp_line
			(start 0.508 -0.9398)
			(end -0.508 -0.9398)
			(stroke
				(width 0.1524)
				(type default)
			)
			(layer "F.SilkS")
		)
		(fp_line
			(start -0.508 -0.9398)
			(end -0.508 0.9398)
			(stroke
				(width 0.1524)
				(type default)
			)
			(layer "F.SilkS")
		)
		(fp_rect
			(start -0.508 0.9398)
			(end 0.508 -0.9398)
			(stroke
				(width 0)
				(type default)
			)
			(fill no)
			(layer "F.CrtYd")
		)
		(fp_rect
			(start -0.508 0.9398)
			(end 0.508 -0.9398)
			(stroke
				(width 0)
				(type default)
			)
			(fill no)
			(layer "F.Fab")
		)
		(pad "1" smd custom
			(at 0 -0.4445 90)
			(size 0.1397 0.1397)
			(layers "F.Cu" "F.Mask" "F.Paste")
			(net "PE_CLK_100M_DR1_1_R_N")
			(options
				(clearance outline)
				(anchor circle)
			)
			(primitives
				(gr_poly
					(pts
						(arc
							(start -0.1778 -0.2794)
							(mid -0.249642 -0.249642)
							(end -0.2794 -0.1778)
						)
						(arc
							(start -0.2794 0.1778)
							(mid -0.249642 0.249642)
							(end -0.1778 0.2794)
						)
						(arc
							(start 0.1778 0.2794)
							(mid 0.249642 0.249642)
							(end 0.2794 0.1778)
						)
						(arc
							(start 0.2794 -0.1778)
							(mid 0.249642 -0.249642)
							(end 0.1778 -0.2794)
						)
					)
					(width 0)
					(fill yes)
				)
			)
		)
		(pad "2" smd custom
			(at 0 0.4445 90)
			(size 0.1397 0.1397)
			(layers "F.Cu" "F.Mask" "F.Paste")
			(net "PE_CLK100M_DR1_1_N")
			(options
				(clearance outline)
				(anchor circle)
			)
			(primitives
				(gr_poly
					(pts
						(arc
							(start -0.1778 -0.2794)
							(mid -0.249642 -0.249642)
							(end -0.2794 -0.1778)
						)
						(arc
							(start -0.2794 0.1778)
							(mid -0.249642 0.249642)
							(end -0.1778 0.2794)
						)
						(arc
							(start 0.1778 0.2794)
							(mid 0.249642 0.249642)
							(end 0.2794 0.1778)
						)
						(arc
							(start 0.2794 -0.1778)
							(mid 0.249642 -0.249642)
							(end 0.1778 -0.2794)
						)
					)
					(width 0)
					(fill yes)
				)
			)
		)
	)
	(footprint ""
		(layer "F.Cu")
		(at 21.8694 -466.4202 90)
		(property "Reference" "R9922"
			(at 0 0 90)
			(layer "F.SilkS")
			(hide yes)
			(effects
				(font
					(size 1.27 1.27)
				)
			)
		)
		(property "Value" "47KR2J-2-GP"
			(at 0.064008 -3.993896 90)
			(unlocked yes)
			(layer "F.Fab")
			(hide yes)
			(effects
				(font
					(size 1.016 1.016)
					(thickness 0.1524)
				)
			)
		)
		(property "Device Type" "R402H16"
			(at 0.064008 -5.517896 90)
			(unlocked yes)
			(layer "F.Fab")
			(hide yes)
			(effects
				(font
					(size 1.016 1.016)
					(thickness 0.1524)
				)
			)
		)
		(duplicate_pad_numbers_are_jumpers no)
		(fp_line
			(start 0.508 -0.9398)
			(end -0.508 -0.9398)
			(stroke
				(width 0.1524)
				(type default)
			)
			(layer "F.SilkS")
		)
		(fp_line
			(start -0.508 -0.9398)
			(end -0.508 0.9398)
			(stroke
				(width 0.1524)
				(type default)
			)
			(layer "F.SilkS")
		)
		(fp_rect
			(start -0.508 0.9398)
			(end 0.508 -0.9398)
			(stroke
				(width 0)
				(type default)
			)
			(fill no)
			(layer "F.CrtYd")
		)
		(fp_rect
			(start -0.508 0.9398)
			(end 0.508 -0.9398)
			(stroke
				(width 0)
				(type default)
			)
			(fill no)
			(layer "F.Fab")
		)
		(pad "1" smd custom
			(at 0 -0.4445 90)
			(size 0.1397 0.1397)
			(layers "F.Cu" "F.Mask" "F.Paste")
			(net "P3V3")
			(options
				(clearance outline)
				(anchor circle)
			)
			(primitives
				(gr_poly
					(pts
						(arc
							(start -0.1778 -0.2794)
							(mid -0.249642 -0.249642)
							(end -0.2794 -0.1778)
						)
						(arc
							(start -0.2794 0.1778)
							(mid -0.249642 0.249642)
							(end -0.1778 0.2794)
						)
						(arc
							(start 0.1778 0.2794)
							(mid 0.249642 0.249642)
							(end 0.2794 0.1778)
						)
						(arc
							(start 0.2794 -0.1778)
							(mid 0.249642 -0.249642)
							(end 0.1778 -0.2794)
						)
					)
					(width 0)
					(fill yes)
				)
			)
		)
		(pad "2" smd custom
			(at 0 0.4445 90)
			(size 0.1397 0.1397)
			(layers "F.Cu" "F.Mask" "F.Paste")
			(net "ATTN_LED_DR10_N")
			(options
				(clearance outline)
				(anchor circle)
			)
			(primitives
				(gr_poly
					(pts
						(arc
							(start -0.1778 -0.2794)
							(mid -0.249642 -0.249642)
							(end -0.2794 -0.1778)
						)
						(arc
							(start -0.2794 0.1778)
							(mid -0.249642 0.249642)
							(end -0.1778 0.2794)
						)
						(arc
							(start 0.1778 0.2794)
							(mid 0.249642 0.249642)
							(end 0.2794 0.1778)
						)
						(arc
							(start 0.2794 -0.1778)
							(mid 0.249642 -0.249642)
							(end 0.1778 -0.2794)
						)
					)
					(width 0)
					(fill yes)
				)
			)
		)
	)
	(footprint ""
		(layer "F.Cu")
		(at 100.33 -219.456 180)
		(property "Reference" "R9095"
			(at 0 0 180)
			(layer "F.SilkS")
			(hide yes)
			(effects
				(font
					(size 1.27 1.27)
				)
			)
		)
		(property "Value" "27R2F-GP"
			(at 0.064008 -3.993896 180)
			(unlocked yes)
			(layer "F.Fab")
			(hide yes)
			(effects
				(font
					(size 1.016 1.016)
					(thickness 0.1524)
				)
			)
		)
		(property "Device Type" "R402H16"
			(at 0.064008 -5.517896 180)
			(unlocked yes)
			(layer "F.Fab")
			(hide yes)
			(effects
				(font
					(size 1.016 1.016)
					(thickness 0.1524)
				)
			)
		)
		(duplicate_pad_numbers_are_jumpers no)
		(fp_line
			(start 0.508 -0.9398)
			(end -0.508 -0.9398)
			(stroke
				(width 0.1524)
				(type default)
			)
			(layer "F.SilkS")
		)
		(fp_line
			(start -0.508 -0.9398)
			(end -0.508 0.9398)
			(stroke
				(width 0.1524)
				(type default)
			)
			(layer "F.SilkS")
		)
		(fp_rect
			(start -0.508 0.9398)
			(end 0.508 -0.9398)
			(stroke
				(width 0)
				(type default)
			)
			(fill no)
			(layer "F.CrtYd")
		)
		(fp_rect
			(start -0.508 0.9398)
			(end 0.508 -0.9398)
			(stroke
				(width 0)
				(type default)
			)
			(fill no)
			(layer "F.Fab")
		)
		(pad "1" smd custom
			(at 0 -0.4445 180)
			(size 0.1397 0.1397)
			(layers "F.Cu" "F.Mask" "F.Paste")
			(net "PE_CLK_100M_DR7_2_R_P")
			(options
				(clearance outline)
				(anchor circle)
			)
			(primitives
				(gr_poly
					(pts
						(arc
							(start -0.1778 -0.2794)
							(mid -0.249642 -0.249642)
							(end -0.2794 -0.1778)
						)
						(arc
							(start -0.2794 0.1778)
							(mid -0.249642 0.249642)
							(end -0.1778 0.2794)
						)
						(arc
							(start 0.1778 0.2794)
							(mid 0.249642 0.249642)
							(end 0.2794 0.1778)
						)
						(arc
							(start 0.2794 -0.1778)
							(mid 0.249642 -0.249642)
							(end 0.1778 -0.2794)
						)
					)
					(width 0)
					(fill yes)
				)
			)
		)
		(pad "2" smd custom
			(at 0 0.4445 180)
			(size 0.1397 0.1397)
			(layers "F.Cu" "F.Mask" "F.Paste")
			(net "PE_CLK100M_DR7_2_P")
			(options
				(clearance outline)
				(anchor circle)
			)
			(primitives
				(gr_poly
					(pts
						(arc
							(start -0.1778 -0.2794)
							(mid -0.249642 -0.249642)
							(end -0.2794 -0.1778)
						)
						(arc
							(start -0.2794 0.1778)
							(mid -0.249642 0.249642)
							(end -0.1778 0.2794)
						)
						(arc
							(start 0.1778 0.2794)
							(mid 0.249642 0.249642)
							(end 0.2794 0.1778)
						)
						(arc
							(start 0.2794 -0.1778)
							(mid 0.249642 -0.249642)
							(end 0.1778 -0.2794)
						)
					)
					(width 0)
					(fill yes)
				)
			)
		)
	)
	(footprint ""
		(layer "F.Cu")
		(at 70.739 -363.601 90)
		(property "Reference" "SR979"
			(at 0 0 90)
			(layer "F.SilkS")
			(hide yes)
			(effects
				(font
					(size 1.27 1.27)
				)
			)
		)
		(property "Value" "2KR2F-3-GP"
			(at 0.064008 -3.993896 90)
			(unlocked yes)
			(layer "F.Fab")
			(hide yes)
			(effects
				(font
					(size 1.016 1.016)
					(thickness 0.1524)
				)
			)
		)
		(property "Device Type" "R402H16"
			(at 0.064008 -5.517896 90)
			(unlocked yes)
			(layer "F.Fab")
			(hide yes)
			(effects
				(font
					(size 1.016 1.016)
					(thickness 0.1524)
				)
			)
		)
		(duplicate_pad_numbers_are_jumpers no)
		(fp_line
			(start 0.508 -0.9398)
			(end -0.508 -0.9398)
			(stroke
				(width 0.1524)
				(type default)
			)
			(layer "F.SilkS")
		)
		(fp_line
			(start -0.508 -0.9398)
			(end -0.508 0.9398)
			(stroke
				(width 0.1524)
				(type default)
			)
			(layer "F.SilkS")
		)
		(fp_rect
			(start -0.508 0.9398)
			(end 0.508 -0.9398)
			(stroke
				(width 0)
				(type default)
			)
			(fill no)
			(layer "F.CrtYd")
		)
		(fp_rect
			(start -0.508 0.9398)
			(end 0.508 -0.9398)
			(stroke
				(width 0)
				(type default)
			)
			(fill no)
			(layer "F.Fab")
		)
		(pad "1" smd custom
			(at 0 -0.4445 90)
			(size 0.1397 0.1397)
			(layers "F.Cu" "F.Mask" "F.Paste")
			(net "P3V3")
			(options
				(clearance outline)
				(anchor circle)
			)
			(primitives
				(gr_poly
					(pts
						(arc
							(start -0.1778 -0.2794)
							(mid -0.249642 -0.249642)
							(end -0.2794 -0.1778)
						)
						(arc
							(start -0.2794 0.1778)
							(mid -0.249642 0.249642)
							(end -0.1778 0.2794)
						)
						(arc
							(start 0.1778 0.2794)
							(mid 0.249642 0.249642)
							(end 0.2794 0.1778)
						)
						(arc
							(start 0.2794 -0.1778)
							(mid 0.249642 -0.249642)
							(end 0.1778 -0.2794)
						)
					)
					(width 0)
					(fill yes)
				)
			)
		)
		(pad "2" smd custom
			(at 0 0.4445 90)
			(size 0.1397 0.1397)
			(layers "F.Cu" "F.Mask" "F.Paste")
			(net "SDA_DR11")
			(options
				(clearance outline)
				(anchor circle)
			)
			(primitives
				(gr_poly
					(pts
						(arc
							(start -0.1778 -0.2794)
							(mid -0.249642 -0.249642)
							(end -0.2794 -0.1778)
						)
						(arc
							(start -0.2794 0.1778)
							(mid -0.249642 0.249642)
							(end -0.1778 0.2794)
						)
						(arc
							(start 0.1778 0.2794)
							(mid 0.249642 0.249642)
							(end 0.2794 0.1778)
						)
						(arc
							(start 0.2794 -0.1778)
							(mid 0.249642 -0.249642)
							(end 0.1778 -0.2794)
						)
					)
					(width 0)
					(fill yes)
				)
			)
		)
	)
	(footprint ""
		(layer "F.Cu")
		(at 39.243 -136.144)
		(property "Reference" "TP5"
			(at 0 0 0)
			(layer "F.SilkS")
			(hide yes)
			(effects
				(font
					(size 1.27 1.27)
				)
			)
		)
		(property "Value" "TPAD32-GP"
			(at -0.0508 -1.6764 0)
			(unlocked yes)
			(layer "F.Fab")
			(hide yes)
			(effects
				(font
					(size 1.016 1.016)
					(thickness 0.1524)
				)
			)
		)
		(property "Device Type" "TPAD32"
			(at -0.0508 -3.2004 0)
			(unlocked yes)
			(layer "F.Fab")
			(hide yes)
			(effects
				(font
					(size 1.016 1.016)
					(thickness 0.1524)
				)
			)
		)
		(duplicate_pad_numbers_are_jumpers no)
		(fp_poly
			(pts
				(arc
					(start 0.4064 0)
					(mid -0.4064 0)
					(end 0.4064 0)
				)
			)
			(stroke
				(width 0)
				(type default)
			)
			(fill no)
			(layer "F.CrtYd")
		)
		(fp_poly
			(pts
				(arc
					(start 0.7112 0)
					(mid -0.7112 0)
					(end 0.7112 0)
				)
			)
			(stroke
				(width 0)
				(type default)
			)
			(fill no)
			(layer "F.Fab")
		)
		(pad "1" smd circle
			(at 0 0)
			(size 0.8128 0.8128)
			(layers "F.Cu" "F.Mask" "F.Paste")
			(net "I2C_B_TMP1_ALERT")
		)
	)
	(footprint ""
		(layer "F.Cu")
		(at 23.1648 -293.2176)
		(property "Reference" "R558"
			(at 0 0 0)
			(layer "F.SilkS")
			(hide yes)
			(effects
				(font
					(size 1.27 1.27)
				)
			)
		)
		(property "Value" "200KR2F-L-GP"
			(at 0.064008 -3.993896 0)
			(unlocked yes)
			(layer "F.Fab")
			(hide yes)
			(effects
				(font
					(size 1.016 1.016)
					(thickness 0.1524)
				)
			)
		)
		(property "Device Type" "R402H16"
			(at 0.064008 -5.517896 0)
			(unlocked yes)
			(layer "F.Fab")
			(hide yes)
			(effects
				(font
					(size 1.016 1.016)
					(thickness 0.1524)
				)
			)
		)
		(duplicate_pad_numbers_are_jumpers no)
		(fp_line
			(start -0.508 -0.9398)
			(end -0.508 0.9398)
			(stroke
				(width 0.1524)
				(type default)
			)
			(layer "F.SilkS")
		)
		(fp_line
			(start 0.508 -0.9398)
			(end -0.508 -0.9398)
			(stroke
				(width 0.1524)
				(type default)
			)
			(layer "F.SilkS")
		)
		(fp_rect
			(start -0.508 0.9398)
			(end 0.508 -0.9398)
			(stroke
				(width 0)
				(type default)
			)
			(fill no)
			(layer "F.CrtYd")
		)
		(fp_rect
			(start -0.508 0.9398)
			(end 0.508 -0.9398)
			(stroke
				(width 0)
				(type default)
			)
			(fill no)
			(layer "F.Fab")
		)
		(pad "1" smd custom
			(at 0 -0.4445)
			(size 0.1397 0.1397)
			(layers "F.Cu" "F.Mask" "F.Paste")
			(net "SW_SSD7_R")
			(options
				(clearance outline)
				(anchor circle)
			)
			(primitives
				(gr_poly
					(pts
						(arc
							(start -0.1778 -0.2794)
							(mid -0.249642 -0.249642)
							(end -0.2794 -0.1778)
						)
						(arc
							(start -0.2794 0.1778)
							(mid -0.249642 0.249642)
							(end -0.1778 0.2794)
						)
						(arc
							(start 0.1778 0.2794)
							(mid 0.249642 0.249642)
							(end 0.2794 0.1778)
						)
						(arc
							(start 0.2794 -0.1778)
							(mid 0.249642 -0.249642)
							(end 0.1778 -0.2794)
						)
					)
					(width 0)
					(fill yes)
				)
			)
		)
		(pad "2" smd custom
			(at 0 0.4445)
			(size 0.1397 0.1397)
			(layers "F.Cu" "F.Mask" "F.Paste")
			(net "SW_SSD7_N")
			(options
				(clearance outline)
				(anchor circle)
			)
			(primitives
				(gr_poly
					(pts
						(arc
							(start -0.1778 -0.2794)
							(mid -0.249642 -0.249642)
							(end -0.2794 -0.1778)
						)
						(arc
							(start -0.2794 0.1778)
							(mid -0.249642 0.249642)
							(end -0.1778 0.2794)
						)
						(arc
							(start 0.1778 0.2794)
							(mid 0.249642 0.249642)
							(end 0.2794 0.1778)
						)
						(arc
							(start 0.2794 -0.1778)
							(mid 0.249642 -0.249642)
							(end 0.1778 -0.2794)
						)
					)
					(width 0)
					(fill yes)
				)
			)
		)
	)
	(footprint ""
		(layer "F.Cu")
		(at 253.499874 -41.497504)
		(property "Reference" "H11"
			(at 0 0 0)
			(layer "F.SilkS")
			(hide yes)
			(effects
				(font
					(size 1.27 1.27)
				)
			)
		)
		(property "Value" "GEN276X162R197X296-6-F-A-GP"
			(at -6.7183 4.1402 0)
			(unlocked yes)
			(layer "F.Fab")
			(hide yes)
			(effects
				(font
					(size 1.016 1.016)
					(thickness 0.1524)
				)
			)
		)
		(property "Device Type" "GEN276X162R197X296-6-F-A"
			(at -6.7183 2.6162 0)
			(unlocked yes)
			(layer "F.Fab")
			(hide yes)
			(effects
				(font
					(size 1.016 1.016)
					(thickness 0.1524)
				)
			)
		)
		(duplicate_pad_numbers_are_jumpers no)
		(fp_poly
			(pts
				(arc
					(start 2.723642 4.777232)
					(mid -0.000169 6.508462)
					(end -2.723896 4.776978)
				)
				(arc
					(start -2.723896 4.776978)
					(mid 0.000173 -5.499012)
					(end 2.723642 4.777232)
				)
			)
			(stroke
				(width 0)
				(type default)
			)
			(fill no)
			(layer "B.CrtYd")
		)
		(fp_poly
			(pts
				(arc
					(start 2.723642 4.777232)
					(mid -0.000169 6.508462)
					(end -2.723896 4.776978)
				)
				(arc
					(start -2.723896 4.776978)
					(mid 0.000173 -5.499012)
					(end 2.723642 4.777232)
				)
			)
			(stroke
				(width 0)
				(type default)
			)
			(fill no)
			(layer "F.CrtYd")
		)
		(fp_poly
			(pts
				(arc
					(start 2.723642 4.777232)
					(mid -0.000169 6.508462)
					(end -2.723896 4.776978)
				)
				(arc
					(start -2.723896 4.776978)
					(mid 0.000173 -5.499012)
					(end 2.723642 4.777232)
				)
			)
			(stroke
				(width 0)
				(type default)
			)
			(fill no)
			(layer "B.Fab")
		)
		(fp_poly
			(pts
				(arc
					(start 2.723642 4.777232)
					(mid -0.000169 6.508462)
					(end -2.723896 4.776978)
				)
				(arc
					(start -2.723896 4.776978)
					(mid 0.000173 -5.499012)
					(end 2.723642 4.777232)
				)
			)
			(stroke
				(width 0)
				(type default)
			)
			(fill no)
			(layer "F.Fab")
		)
		(pad "" np_thru_hole circle
			(at 0 0)
			(size 0.254 0.254)
			(drill 0.0254)
			(layers "*.Cu" "*.Mask")
			(clearance 3.135376)
			(thermal_gap 3.135376)
		)
		(pad "1" thru_hole circle
			(at 2.549906 0)
			(size 0.8636 0.8636)
			(drill 0.508)
			(layers "*.Cu" "*.Mask")
			(remove_unused_layers no)
			(net "GND")
			(clearance 0.8255)
			(thermal_gap 0.8255)
		)
		(pad "2" thru_hole circle
			(at 2.210054 -1.27)
			(size 0.8636 0.8636)
			(drill 0.508)
			(layers "*.Cu" "*.Mask")
			(remove_unused_layers no)
			(net "GND")
			(clearance 0.8255)
			(thermal_gap 0.8255)
		)
		(pad "3" thru_hole circle
			(at 1.27 -2.210054)
			(size 0.8636 0.8636)
			(drill 0.508)
			(layers "*.Cu" "*.Mask")
			(remove_unused_layers no)
			(net "GND")
			(clearance 0.8255)
			(thermal_gap 0.8255)
		)
		(pad "4" thru_hole circle
			(at -1.279906 -2.210054)
			(size 0.8636 0.8636)
			(drill 0.508)
			(layers "*.Cu" "*.Mask")
			(remove_unused_layers no)
			(net "GND")
			(clearance 0.8255)
			(thermal_gap 0.8255)
		)
		(pad "5" thru_hole circle
			(at -2.210054 -1.27)
			(size 0.8636 0.8636)
			(drill 0.508)
			(layers "*.Cu" "*.Mask")
			(remove_unused_layers no)
			(net "GND")
			(clearance 0.8255)
			(thermal_gap 0.8255)
		)
		(pad "6" thru_hole circle
			(at -2.549906 0)
			(size 0.8636 0.8636)
			(drill 0.508)
			(layers "*.Cu" "*.Mask")
			(remove_unused_layers no)
			(net "GND")
			(clearance 0.8255)
			(thermal_gap 0.8255)
		)
		(zone
			(layers "F.Cu" "B.Cu" "In1.Cu" "In2.Cu" "In3.Cu" "In4.Cu" "In5.Cu" "In6.Cu")
			(hatch none 0.5)
			(connect_pads
				(clearance 0)
			)
			(min_thickness 0.25)
			(keepout
				(tracks allowed)
				(vias not_allowed)
				(pads allowed)
				(copperpour not_allowed)
				(footprints allowed)
			)
			(placement
				(enabled no)
				(sheetname "")
			)
			(fill
				(thermal_gap 0.5)
				(thermal_bridge_width 0.5)
				(island_removal_mode 0)
			)
			(polygon
				(pts
					(arc
						(start 257.817874 -41.500552)
						(mid 249.181874 -41.500552)
						(end 257.817874 -41.500552)
					)
				)
			)
		)
		(zone
			(layers "F.Cu" "B.Cu" "In1.Cu" "In2.Cu" "In3.Cu" "In4.Cu" "In5.Cu" "In6.Cu")
			(hatch none 0.5)
			(connect_pads
				(clearance 0)
			)
			(min_thickness 0.25)
			(keepout
				(tracks not_allowed)
				(vias allowed)
				(pads allowed)
				(copperpour not_allowed)
				(footprints allowed)
			)
			(placement
				(enabled no)
				(sheetname "")
			)
			(fill
				(thermal_gap 0.5)
				(thermal_bridge_width 0.5)
				(island_removal_mode 0)
			)
			(polygon
				(pts
					(arc
						(start 255.839214 -39.88816)
						(mid 253.499954 -34.989057)
						(end 251.16028 -39.88816)
					)
					(arc
						(start 251.16028 -39.88816)
						(mid 251.406247 -40.328526)
						(end 251.491496 -40.825674)
					)
					(arc
						(start 251.491496 -41.497504)
						(mid 253.499874 -43.505882)
						(end 255.507998 -41.497504)
					)
					(arc
						(start 255.507998 -40.825674)
						(mid 255.593233 -40.32852)
						(end 255.839214 -39.88816)
					)
				)
			)
		)
	)
	(footprint ""
		(layer "F.Cu")
		(at 98.552 -437.769 90)
		(property "Reference" "C8840"
			(at 0 0 90)
			(layer "F.SilkS")
			(hide yes)
			(effects
				(font
					(size 1.27 1.27)
				)
			)
		)
		(property "Value" "SCD1U16V2KX-3GP"
			(at 1.1811 -2.7051 90)
			(unlocked yes)
			(layer "F.Fab")
			(hide yes)
			(effects
				(font
					(size 1.016 1.016)
					(thickness 0.1524)
				)
			)
		)
		(property "Device Type" "C402H22"
			(at 1.1811 -4.2291 90)
			(unlocked yes)
			(layer "F.Fab")
			(hide yes)
			(effects
				(font
					(size 1.016 1.016)
					(thickness 0.1524)
				)
			)
		)
		(duplicate_pad_numbers_are_jumpers no)
		(fp_rect
			(start -0.4318 0.9525)
			(end 0.4318 -0.9525)
			(stroke
				(width 0)
				(type default)
			)
			(fill no)
			(layer "F.CrtYd")
		)
		(fp_rect
			(start -0.4318 0.9525)
			(end 0.4318 -0.9525)
			(stroke
				(width 0)
				(type default)
			)
			(fill no)
			(layer "F.Fab")
		)
		(pad "1" smd custom
			(at 0 -0.4445 90)
			(size 0.1524 0.1524)
			(layers "F.Cu" "F.Mask" "F.Paste")
			(net "VDD_IO_1")
			(options
				(clearance outline)
				(anchor circle)
			)
			(primitives
				(gr_poly
					(pts
						(arc
							(start 0.3048 -0.2032)
							(mid 0.275042 -0.275042)
							(end 0.2032 -0.3048)
						)
						(arc
							(start -0.2032 -0.3048)
							(mid -0.275042 -0.275042)
							(end -0.3048 -0.2032)
						)
						(arc
							(start -0.3048 0.2032)
							(mid -0.275042 0.275042)
							(end -0.2032 0.3048)
						)
						(arc
							(start 0.2032 0.3048)
							(mid 0.275042 0.275042)
							(end 0.3048 0.2032)
						)
					)
					(width 0)
					(fill yes)
				)
			)
		)
		(pad "2" smd custom
			(at 0 0.4445 90)
			(size 0.1524 0.1524)
			(layers "F.Cu" "F.Mask" "F.Paste")
			(net "GND")
			(options
				(clearance outline)
				(anchor circle)
			)
			(primitives
				(gr_poly
					(pts
						(arc
							(start 0.3048 -0.2032)
							(mid 0.275042 -0.275042)
							(end 0.2032 -0.3048)
						)
						(arc
							(start -0.2032 -0.3048)
							(mid -0.275042 -0.275042)
							(end -0.3048 -0.2032)
						)
						(arc
							(start -0.3048 0.2032)
							(mid -0.275042 0.275042)
							(end -0.2032 0.3048)
						)
						(arc
							(start 0.2032 0.3048)
							(mid 0.275042 0.275042)
							(end 0.3048 0.2032)
						)
					)
					(width 0)
					(fill yes)
				)
			)
		)
	)
	(footprint ""
		(layer "F.Cu")
		(at 59.817 -447.04 180)
		(property "Reference" "Q55"
			(at 0 0 180)
			(layer "F.SilkS")
			(hide yes)
			(effects
				(font
					(size 1.27 1.27)
				)
			)
		)
		(property "Value" "2N7002A-7-GP"
			(at 0.127 -8.9662 180)
			(unlocked yes)
			(layer "F.Fab")
			(hide yes)
			(effects
				(font
					(size 1.016 1.016)
					(thickness 0.1524)
				)
			)
		)
		(property "Device Type" "SOT23DGS2D4H48"
			(at 0.127 -10.4902 180)
			(unlocked yes)
			(layer "F.Fab")
			(hide yes)
			(effects
				(font
					(size 1.016 1.016)
					(thickness 0.1524)
				)
			)
		)
		(duplicate_pad_numbers_are_jumpers no)
		(fp_line
			(start 1.651 1.778)
			(end 1.651 -1.778)
			(stroke
				(width 0.1524)
				(type default)
			)
			(layer "F.SilkS")
		)
		(fp_line
			(start 1.651 -1.778)
			(end -1.651 -1.778)
			(stroke
				(width 0.1524)
				(type default)
			)
			(layer "F.SilkS")
		)
		(fp_line
			(start -1.651 1.778)
			(end 1.651 1.778)
			(stroke
				(width 0.1524)
				(type default)
			)
			(layer "F.SilkS")
		)
		(fp_line
			(start -1.651 -1.778)
			(end -1.651 1.778)
			(stroke
				(width 0.1524)
				(type default)
			)
			(layer "F.SilkS")
		)
		(fp_poly
			(pts
				(xy -1.778 1.8796) (xy -1.778 -1.8796) (xy 1.778 -1.8796) (xy 1.778 1.8796)
			)
			(stroke
				(width 0)
				(type default)
			)
			(fill no)
			(layer "F.CrtYd")
		)
		(fp_poly
			(pts
				(xy -1.778 1.8796) (xy -1.778 -1.8796) (xy 1.778 -1.8796) (xy 1.778 1.8796)
			)
			(stroke
				(width 0)
				(type default)
			)
			(fill no)
			(layer "F.Fab")
		)
		(pad "D" smd custom
			(at 0 -0.9525 180)
			(size 0.1905 0.1905)
			(layers "F.Cu" "F.Mask" "F.Paste")
			(net "ATTN_LED_DR5_MOS_N")
			(options
				(clearance outline)
				(anchor circle)
			)
			(primitives
				(gr_poly
					(pts
						(arc
							(start -0.1778 0.5715)
							(mid -0.321484 0.511984)
							(end -0.381 0.3683)
						)
						(arc
							(start -0.381 -0.3683)
							(mid -0.321484 -0.511984)
							(end -0.1778 -0.5715)
						)
						(arc
							(start 0.1778 -0.5715)
							(mid 0.321484 -0.511984)
							(end 0.381 -0.3683)
						)
						(arc
							(start 0.381 0.3683)
							(mid 0.321484 0.511984)
							(end 0.1778 0.5715)
						)
					)
					(width 0)
					(fill yes)
				)
			)
		)
		(pad "G" smd custom
			(at -0.98425 0.9525 180)
			(size 0.1905 0.1905)
			(layers "F.Cu" "F.Mask" "F.Paste")
			(net "SSD5_CLK0_OE_MOS_N")
			(options
				(clearance outline)
				(anchor circle)
			)
			(primitives
				(gr_poly
					(pts
						(arc
							(start -0.1778 0.5715)
							(mid -0.321484 0.511984)
							(end -0.381 0.3683)
						)
						(arc
							(start -0.381 -0.3683)
							(mid -0.321484 -0.511984)
							(end -0.1778 -0.5715)
						)
						(arc
							(start 0.1778 -0.5715)
							(mid 0.321484 -0.511984)
							(end 0.381 -0.3683)
						)
						(arc
							(start 0.381 0.3683)
							(mid 0.321484 0.511984)
							(end 0.1778 0.5715)
						)
					)
					(width 0)
					(fill yes)
				)
			)
		)
		(pad "S" smd custom
			(at 0.98425 0.9525 180)
			(size 0.1905 0.1905)
			(layers "F.Cu" "F.Mask" "F.Paste")
			(net "ATTN_LED_DR5_R")
			(options
				(clearance outline)
				(anchor circle)
			)
			(primitives
				(gr_poly
					(pts
						(arc
							(start -0.1778 0.5715)
							(mid -0.321484 0.511984)
							(end -0.381 0.3683)
						)
						(arc
							(start -0.381 -0.3683)
							(mid -0.321484 -0.511984)
							(end -0.1778 -0.5715)
						)
						(arc
							(start 0.1778 -0.5715)
							(mid 0.321484 -0.511984)
							(end 0.381 -0.3683)
						)
						(arc
							(start 0.381 0.3683)
							(mid 0.321484 0.511984)
							(end 0.1778 0.5715)
						)
					)
					(width 0)
					(fill yes)
				)
			)
		)
	)
	(footprint ""
		(layer "F.Cu")
		(at 24.7396 -498.5258 180)
		(property "Reference" "PC1206"
			(at 0 0 180)
			(layer "F.SilkS")
			(hide yes)
			(effects
				(font
					(size 1.27 1.27)
				)
			)
		)
		(property "Value" "SC22U25V6KX-GP-U"
			(at -2.860802 -5.279644 180)
			(unlocked yes)
			(layer "F.Fab")
			(hide yes)
			(effects
				(font
					(size 1.016 1.016)
					(thickness 0.1524)
				)
			)
		)
		(property "Device Type" "C1206-TO0D3H75"
			(at -2.860802 -6.803644 180)
			(unlocked yes)
			(layer "F.Fab")
			(hide yes)
			(effects
				(font
					(size 1.016 1.016)
					(thickness 0.1524)
				)
			)
		)
		(duplicate_pad_numbers_are_jumpers no)
		(fp_line
			(start 1.3081 2.3749)
			(end -1.3081 2.3749)
			(stroke
				(width 0.1524)
				(type default)
			)
			(layer "F.SilkS")
		)
		(fp_line
			(start 1.3081 -2.3749)
			(end 1.3081 2.3749)
			(stroke
				(width 0.1524)
				(type default)
			)
			(layer "F.SilkS")
		)
		(fp_line
			(start -1.3081 2.3749)
			(end -1.3081 -2.3749)
			(stroke
				(width 0.1524)
				(type default)
			)
			(layer "F.SilkS")
		)
		(fp_line
			(start -1.3081 -2.3749)
			(end 1.3081 -2.3749)
			(stroke
				(width 0.1524)
				(type default)
			)
			(layer "F.SilkS")
		)
		(fp_rect
			(start -0.8001 1.6002)
			(end 0.8001 -1.6002)
			(stroke
				(width 0)
				(type default)
			)
			(fill no)
			(layer "F.CrtYd")
		)
		(fp_poly
			(pts
				(xy -1.5621 2.4511) (xy -1.5621 1.6002) (xy 0.8001 1.6002) (xy 0.8001 -1.6002) (xy -0.8001 -1.6002)
				(xy -0.8001 1.5875) (xy -1.5621 1.5875) (xy -1.5621 -2.4511) (xy 1.5621 -2.4511) (xy 1.5621 2.4511)
			)
			(stroke
				(width 0)
				(type default)
			)
			(fill no)
			(layer "F.CrtYd")
		)
		(fp_rect
			(start -1.5621 2.4511)
			(end 1.5621 -2.4511)
			(stroke
				(width 0)
				(type default)
			)
			(fill no)
			(layer "F.Fab")
		)
		(pad "1" smd rect
			(at 0 -1.392936 180)
			(size 2.1082 1.4478)
			(layers "F.Cu" "F.Mask" "F.Paste")
			(net "P12V_SSD5")
		)
		(pad "2" smd rect
			(at 0 1.392936 180)
			(size 2.1082 1.4478)
			(layers "F.Cu" "F.Mask" "F.Paste")
			(net "GND")
		)
	)
	(footprint ""
		(layer "F.Cu")
		(at 33.02 -374.65)
		(property "Reference" "R339"
			(at 0 0 0)
			(layer "F.SilkS")
			(hide yes)
			(effects
				(font
					(size 1.27 1.27)
				)
			)
		)
		(property "Value" "4K7R2J-2-GP"
			(at 0.064008 -3.993896 0)
			(unlocked yes)
			(layer "F.Fab")
			(hide yes)
			(effects
				(font
					(size 1.016 1.016)
					(thickness 0.1524)
				)
			)
		)
		(property "Device Type" "R402H16"
			(at 0.064008 -5.517896 0)
			(unlocked yes)
			(layer "F.Fab")
			(hide yes)
			(effects
				(font
					(size 1.016 1.016)
					(thickness 0.1524)
				)
			)
		)
		(duplicate_pad_numbers_are_jumpers no)
		(fp_line
			(start -0.508 -0.9398)
			(end -0.508 0.9398)
			(stroke
				(width 0.1524)
				(type default)
			)
			(layer "F.SilkS")
		)
		(fp_line
			(start 0.508 -0.9398)
			(end -0.508 -0.9398)
			(stroke
				(width 0.1524)
				(type default)
			)
			(layer "F.SilkS")
		)
		(fp_rect
			(start -0.508 0.9398)
			(end 0.508 -0.9398)
			(stroke
				(width 0)
				(type default)
			)
			(fill no)
			(layer "F.CrtYd")
		)
		(fp_rect
			(start -0.508 0.9398)
			(end 0.508 -0.9398)
			(stroke
				(width 0)
				(type default)
			)
			(fill no)
			(layer "F.Fab")
		)
		(pad "1" smd custom
			(at 0 -0.4445)
			(size 0.1397 0.1397)
			(layers "F.Cu" "F.Mask" "F.Paste")
			(net "I2C_B_TMP4_A2")
			(options
				(clearance outline)
				(anchor circle)
			)
			(primitives
				(gr_poly
					(pts
						(arc
							(start -0.1778 -0.2794)
							(mid -0.249642 -0.249642)
							(end -0.2794 -0.1778)
						)
						(arc
							(start -0.2794 0.1778)
							(mid -0.249642 0.249642)
							(end -0.1778 0.2794)
						)
						(arc
							(start 0.1778 0.2794)
							(mid 0.249642 0.249642)
							(end 0.2794 0.1778)
						)
						(arc
							(start 0.2794 -0.1778)
							(mid 0.249642 -0.249642)
							(end 0.1778 -0.2794)
						)
					)
					(width 0)
					(fill yes)
				)
			)
		)
		(pad "2" smd custom
			(at 0 0.4445)
			(size 0.1397 0.1397)
			(layers "F.Cu" "F.Mask" "F.Paste")
			(net "GND")
			(options
				(clearance outline)
				(anchor circle)
			)
			(primitives
				(gr_poly
					(pts
						(arc
							(start -0.1778 -0.2794)
							(mid -0.249642 -0.249642)
							(end -0.2794 -0.1778)
						)
						(arc
							(start -0.2794 0.1778)
							(mid -0.249642 0.249642)
							(end -0.1778 0.2794)
						)
						(arc
							(start 0.1778 0.2794)
							(mid 0.249642 0.249642)
							(end 0.2794 0.1778)
						)
						(arc
							(start 0.2794 -0.1778)
							(mid 0.249642 -0.249642)
							(end 0.1778 -0.2794)
						)
					)
					(width 0)
					(fill yes)
				)
			)
		)
	)
	(footprint ""
		(layer "F.Cu")
		(at 32.2326 -421.513 180)
		(property "Reference" "SR1111"
			(at 0 0 180)
			(layer "F.SilkS")
			(hide yes)
			(effects
				(font
					(size 1.27 1.27)
				)
			)
		)
		(property "Value" "4K7R2F-GP"
			(at 0.064008 -3.993896 180)
			(unlocked yes)
			(layer "F.Fab")
			(hide yes)
			(effects
				(font
					(size 1.016 1.016)
					(thickness 0.1524)
				)
			)
		)
		(property "Device Type" "R402H16"
			(at 0.064008 -5.517896 180)
			(unlocked yes)
			(layer "F.Fab")
			(hide yes)
			(effects
				(font
					(size 1.016 1.016)
					(thickness 0.1524)
				)
			)
		)
		(duplicate_pad_numbers_are_jumpers no)
		(fp_line
			(start 0.508 -0.9398)
			(end -0.508 -0.9398)
			(stroke
				(width 0.1524)
				(type default)
			)
			(layer "F.SilkS")
		)
		(fp_line
			(start -0.508 -0.9398)
			(end -0.508 0.9398)
			(stroke
				(width 0.1524)
				(type default)
			)
			(layer "F.SilkS")
		)
		(fp_rect
			(start -0.508 0.9398)
			(end 0.508 -0.9398)
			(stroke
				(width 0)
				(type default)
			)
			(fill no)
			(layer "F.CrtYd")
		)
		(fp_rect
			(start -0.508 0.9398)
			(end 0.508 -0.9398)
			(stroke
				(width 0)
				(type default)
			)
			(fill no)
			(layer "F.Fab")
		)
		(pad "1" smd custom
			(at 0 -0.4445 180)
			(size 0.1397 0.1397)
			(layers "F.Cu" "F.Mask" "F.Paste")
			(net "P3V3")
			(options
				(clearance outline)
				(anchor circle)
			)
			(primitives
				(gr_poly
					(pts
						(arc
							(start -0.1778 -0.2794)
							(mid -0.249642 -0.249642)
							(end -0.2794 -0.1778)
						)
						(arc
							(start -0.2794 0.1778)
							(mid -0.249642 0.249642)
							(end -0.1778 0.2794)
						)
						(arc
							(start 0.1778 0.2794)
							(mid 0.249642 0.249642)
							(end 0.2794 0.1778)
						)
						(arc
							(start 0.2794 -0.1778)
							(mid 0.249642 -0.249642)
							(end 0.1778 -0.2794)
						)
					)
					(width 0)
					(fill yes)
				)
			)
		)
		(pad "2" smd custom
			(at 0 0.4445 180)
			(size 0.1397 0.1397)
			(layers "F.Cu" "F.Mask" "F.Paste")
			(net "DUALPORTEN#10")
			(options
				(clearance outline)
				(anchor circle)
			)
			(primitives
				(gr_poly
					(pts
						(arc
							(start -0.1778 -0.2794)
							(mid -0.249642 -0.249642)
							(end -0.2794 -0.1778)
						)
						(arc
							(start -0.2794 0.1778)
							(mid -0.249642 0.249642)
							(end -0.1778 0.2794)
						)
						(arc
							(start 0.1778 0.2794)
							(mid 0.249642 0.249642)
							(end 0.2794 0.1778)
						)
						(arc
							(start 0.2794 -0.1778)
							(mid 0.249642 -0.249642)
							(end 0.1778 -0.2794)
						)
					)
					(width 0)
					(fill yes)
				)
			)
		)
	)
	(footprint ""
		(layer "F.Cu")
		(at 19.4945 -368.073178 180)
		(property "Reference" "R9855"
			(at 0 0 180)
			(layer "F.SilkS")
			(hide yes)
			(effects
				(font
					(size 1.27 1.27)
				)
			)
		)
		(property "Value" "0R2J-2-GP"
			(at 0.064008 -3.993896 180)
			(unlocked yes)
			(layer "F.Fab")
			(hide yes)
			(effects
				(font
					(size 1.016 1.016)
					(thickness 0.1524)
				)
			)
		)
		(property "Device Type" "R402H16"
			(at 0.064008 -5.517896 180)
			(unlocked yes)
			(layer "F.Fab")
			(hide yes)
			(effects
				(font
					(size 1.016 1.016)
					(thickness 0.1524)
				)
			)
		)
		(duplicate_pad_numbers_are_jumpers no)
		(fp_line
			(start 0.508 -0.9398)
			(end -0.508 -0.9398)
			(stroke
				(width 0.1524)
				(type default)
			)
			(layer "F.SilkS")
		)
		(fp_line
			(start -0.508 -0.9398)
			(end -0.508 0.9398)
			(stroke
				(width 0.1524)
				(type default)
			)
			(layer "F.SilkS")
		)
		(fp_rect
			(start -0.508 0.9398)
			(end 0.508 -0.9398)
			(stroke
				(width 0)
				(type default)
			)
			(fill no)
			(layer "F.CrtYd")
		)
		(fp_rect
			(start -0.508 0.9398)
			(end 0.508 -0.9398)
			(stroke
				(width 0)
				(type default)
			)
			(fill no)
			(layer "F.Fab")
		)
		(pad "1" smd custom
			(at 0 -0.4445 180)
			(size 0.1397 0.1397)
			(layers "F.Cu" "F.Mask" "F.Paste")
			(net "SSD_ACT_DR11_R")
			(options
				(clearance outline)
				(anchor circle)
			)
			(primitives
				(gr_poly
					(pts
						(arc
							(start -0.1778 -0.2794)
							(mid -0.249642 -0.249642)
							(end -0.2794 -0.1778)
						)
						(arc
							(start -0.2794 0.1778)
							(mid -0.249642 0.249642)
							(end -0.1778 0.2794)
						)
						(arc
							(start 0.1778 0.2794)
							(mid 0.249642 0.249642)
							(end 0.2794 0.1778)
						)
						(arc
							(start 0.2794 -0.1778)
							(mid 0.249642 -0.249642)
							(end 0.1778 -0.2794)
						)
					)
					(width 0)
					(fill yes)
				)
			)
		)
		(pad "2" smd custom
			(at 0 0.4445 180)
			(size 0.1397 0.1397)
			(layers "F.Cu" "F.Mask" "F.Paste")
			(net "SSD_ACT_DR11")
			(options
				(clearance outline)
				(anchor circle)
			)
			(primitives
				(gr_poly
					(pts
						(arc
							(start -0.1778 -0.2794)
							(mid -0.249642 -0.249642)
							(end -0.2794 -0.1778)
						)
						(arc
							(start -0.2794 0.1778)
							(mid -0.249642 0.249642)
							(end -0.1778 0.2794)
						)
						(arc
							(start 0.1778 0.2794)
							(mid 0.249642 0.249642)
							(end 0.2794 0.1778)
						)
						(arc
							(start 0.2794 -0.1778)
							(mid 0.249642 -0.249642)
							(end 0.1778 -0.2794)
						)
					)
					(width 0)
					(fill yes)
				)
			)
		)
	)
	(footprint ""
		(layer "F.Cu")
		(at 30.6832 -112.4712)
		(property "Reference" "SR1118"
			(at 0 0 0)
			(layer "F.SilkS")
			(hide yes)
			(effects
				(font
					(size 1.27 1.27)
				)
			)
		)
		(property "Value" "4K7R2F-GP"
			(at 0.064008 -3.993896 0)
			(unlocked yes)
			(layer "F.Fab")
			(hide yes)
			(effects
				(font
					(size 1.016 1.016)
					(thickness 0.1524)
				)
			)
		)
		(property "Device Type" "R402H16"
			(at 0.064008 -5.517896 0)
			(unlocked yes)
			(layer "F.Fab")
			(hide yes)
			(effects
				(font
					(size 1.016 1.016)
					(thickness 0.1524)
				)
			)
		)
		(duplicate_pad_numbers_are_jumpers no)
		(fp_line
			(start -0.508 -0.9398)
			(end -0.508 0.9398)
			(stroke
				(width 0.1524)
				(type default)
			)
			(layer "F.SilkS")
		)
		(fp_line
			(start 0.508 -0.9398)
			(end -0.508 -0.9398)
			(stroke
				(width 0.1524)
				(type default)
			)
			(layer "F.SilkS")
		)
		(fp_rect
			(start -0.508 0.9398)
			(end 0.508 -0.9398)
			(stroke
				(width 0)
				(type default)
			)
			(fill no)
			(layer "F.CrtYd")
		)
		(fp_rect
			(start -0.508 0.9398)
			(end 0.508 -0.9398)
			(stroke
				(width 0)
				(type default)
			)
			(fill no)
			(layer "F.Fab")
		)
		(pad "1" smd custom
			(at 0 -0.4445)
			(size 0.1397 0.1397)
			(layers "F.Cu" "F.Mask" "F.Paste")
			(net "DUALPORTEN#13")
			(options
				(clearance outline)
				(anchor circle)
			)
			(primitives
				(gr_poly
					(pts
						(arc
							(start -0.1778 -0.2794)
							(mid -0.249642 -0.249642)
							(end -0.2794 -0.1778)
						)
						(arc
							(start -0.2794 0.1778)
							(mid -0.249642 0.249642)
							(end -0.1778 0.2794)
						)
						(arc
							(start 0.1778 0.2794)
							(mid 0.249642 0.249642)
							(end 0.2794 0.1778)
						)
						(arc
							(start 0.2794 -0.1778)
							(mid 0.249642 -0.249642)
							(end 0.1778 -0.2794)
						)
					)
					(width 0)
					(fill yes)
				)
			)
		)
		(pad "2" smd custom
			(at 0 0.4445)
			(size 0.1397 0.1397)
			(layers "F.Cu" "F.Mask" "F.Paste")
			(net "GND")
			(options
				(clearance outline)
				(anchor circle)
			)
			(primitives
				(gr_poly
					(pts
						(arc
							(start -0.1778 -0.2794)
							(mid -0.249642 -0.249642)
							(end -0.2794 -0.1778)
						)
						(arc
							(start -0.2794 0.1778)
							(mid -0.249642 0.249642)
							(end -0.1778 0.2794)
						)
						(arc
							(start 0.1778 0.2794)
							(mid 0.249642 0.249642)
							(end 0.2794 0.1778)
						)
						(arc
							(start 0.2794 -0.1778)
							(mid 0.249642 -0.249642)
							(end 0.1778 -0.2794)
						)
					)
					(width 0)
					(fill yes)
				)
			)
		)
	)
	(footprint ""
		(layer "F.Cu")
		(at 99.314 -219.456 180)
		(property "Reference" "R9098"
			(at 0 0 180)
			(layer "F.SilkS")
			(hide yes)
			(effects
				(font
					(size 1.27 1.27)
				)
			)
		)
		(property "Value" "27R2F-GP"
			(at 0.064008 -3.993896 180)
			(unlocked yes)
			(layer "F.Fab")
			(hide yes)
			(effects
				(font
					(size 1.016 1.016)
					(thickness 0.1524)
				)
			)
		)
		(property "Device Type" "R402H16"
			(at 0.064008 -5.517896 180)
			(unlocked yes)
			(layer "F.Fab")
			(hide yes)
			(effects
				(font
					(size 1.016 1.016)
					(thickness 0.1524)
				)
			)
		)
		(duplicate_pad_numbers_are_jumpers no)
		(fp_line
			(start 0.508 -0.9398)
			(end -0.508 -0.9398)
			(stroke
				(width 0.1524)
				(type default)
			)
			(layer "F.SilkS")
		)
		(fp_line
			(start -0.508 -0.9398)
			(end -0.508 0.9398)
			(stroke
				(width 0.1524)
				(type default)
			)
			(layer "F.SilkS")
		)
		(fp_rect
			(start -0.508 0.9398)
			(end 0.508 -0.9398)
			(stroke
				(width 0)
				(type default)
			)
			(fill no)
			(layer "F.CrtYd")
		)
		(fp_rect
			(start -0.508 0.9398)
			(end 0.508 -0.9398)
			(stroke
				(width 0)
				(type default)
			)
			(fill no)
			(layer "F.Fab")
		)
		(pad "1" smd custom
			(at 0 -0.4445 180)
			(size 0.1397 0.1397)
			(layers "F.Cu" "F.Mask" "F.Paste")
			(net "PE_CLK_100M_DR7_2_R_N")
			(options
				(clearance outline)
				(anchor circle)
			)
			(primitives
				(gr_poly
					(pts
						(arc
							(start -0.1778 -0.2794)
							(mid -0.249642 -0.249642)
							(end -0.2794 -0.1778)
						)
						(arc
							(start -0.2794 0.1778)
							(mid -0.249642 0.249642)
							(end -0.1778 0.2794)
						)
						(arc
							(start 0.1778 0.2794)
							(mid 0.249642 0.249642)
							(end 0.2794 0.1778)
						)
						(arc
							(start 0.2794 -0.1778)
							(mid 0.249642 -0.249642)
							(end 0.1778 -0.2794)
						)
					)
					(width 0)
					(fill yes)
				)
			)
		)
		(pad "2" smd custom
			(at 0 0.4445 180)
			(size 0.1397 0.1397)
			(layers "F.Cu" "F.Mask" "F.Paste")
			(net "PE_CLK100M_DR7_2_N")
			(options
				(clearance outline)
				(anchor circle)
			)
			(primitives
				(gr_poly
					(pts
						(arc
							(start -0.1778 -0.2794)
							(mid -0.249642 -0.249642)
							(end -0.2794 -0.1778)
						)
						(arc
							(start -0.2794 0.1778)
							(mid -0.249642 0.249642)
							(end -0.1778 0.2794)
						)
						(arc
							(start 0.1778 0.2794)
							(mid 0.249642 0.249642)
							(end 0.2794 0.1778)
						)
						(arc
							(start 0.2794 -0.1778)
							(mid 0.249642 -0.249642)
							(end 0.1778 -0.2794)
						)
					)
					(width 0)
					(fill yes)
				)
			)
		)
	)
	(footprint ""
		(layer "F.Cu")
		(at 87.503 -92.964)
		(property "Reference" "R9120"
			(at 0 0 0)
			(layer "F.SilkS")
			(hide yes)
			(effects
				(font
					(size 1.27 1.27)
				)
			)
		)
		(property "Value" "27R2F-GP"
			(at 0.064008 -3.993896 0)
			(unlocked yes)
			(layer "F.Fab")
			(hide yes)
			(effects
				(font
					(size 1.016 1.016)
					(thickness 0.1524)
				)
			)
		)
		(property "Device Type" "R402H16"
			(at 0.064008 -5.517896 0)
			(unlocked yes)
			(layer "F.Fab")
			(hide yes)
			(effects
				(font
					(size 1.016 1.016)
					(thickness 0.1524)
				)
			)
		)
		(duplicate_pad_numbers_are_jumpers no)
		(fp_line
			(start -0.508 -0.9398)
			(end -0.508 0.9398)
			(stroke
				(width 0.1524)
				(type default)
			)
			(layer "F.SilkS")
		)
		(fp_line
			(start 0.508 -0.9398)
			(end -0.508 -0.9398)
			(stroke
				(width 0.1524)
				(type default)
			)
			(layer "F.SilkS")
		)
		(fp_rect
			(start -0.508 0.9398)
			(end 0.508 -0.9398)
			(stroke
				(width 0)
				(type default)
			)
			(fill no)
			(layer "F.CrtYd")
		)
		(fp_rect
			(start -0.508 0.9398)
			(end 0.508 -0.9398)
			(stroke
				(width 0)
				(type default)
			)
			(fill no)
			(layer "F.Fab")
		)
		(pad "1" smd custom
			(at 0 -0.4445)
			(size 0.1397 0.1397)
			(layers "F.Cu" "F.Mask" "F.Paste")
			(net "PE_CLK_100M_DR9_2_R_N")
			(options
				(clearance outline)
				(anchor circle)
			)
			(primitives
				(gr_poly
					(pts
						(arc
							(start -0.1778 -0.2794)
							(mid -0.249642 -0.249642)
							(end -0.2794 -0.1778)
						)
						(arc
							(start -0.2794 0.1778)
							(mid -0.249642 0.249642)
							(end -0.1778 0.2794)
						)
						(arc
							(start 0.1778 0.2794)
							(mid 0.249642 0.249642)
							(end 0.2794 0.1778)
						)
						(arc
							(start 0.2794 -0.1778)
							(mid 0.249642 -0.249642)
							(end 0.1778 -0.2794)
						)
					)
					(width 0)
					(fill yes)
				)
			)
		)
		(pad "2" smd custom
			(at 0 0.4445)
			(size 0.1397 0.1397)
			(layers "F.Cu" "F.Mask" "F.Paste")
			(net "PE_CLK100M_DR9_2_N")
			(options
				(clearance outline)
				(anchor circle)
			)
			(primitives
				(gr_poly
					(pts
						(arc
							(start -0.1778 -0.2794)
							(mid -0.249642 -0.249642)
							(end -0.2794 -0.1778)
						)
						(arc
							(start -0.2794 0.1778)
							(mid -0.249642 0.249642)
							(end -0.1778 0.2794)
						)
						(arc
							(start 0.1778 0.2794)
							(mid 0.249642 0.249642)
							(end 0.2794 0.1778)
						)
						(arc
							(start 0.2794 -0.1778)
							(mid 0.249642 -0.249642)
							(end 0.1778 -0.2794)
						)
					)
					(width 0)
					(fill yes)
				)
			)
		)
	)
	(footprint ""
		(layer "F.Cu")
		(at 21.336 -265.303 180)
		(property "Reference" "R9924"
			(at 0 0 180)
			(layer "F.SilkS")
			(hide yes)
			(effects
				(font
					(size 1.27 1.27)
				)
			)
		)
		(property "Value" "47KR2J-2-GP"
			(at 0.064008 -3.993896 180)
			(unlocked yes)
			(layer "F.Fab")
			(hide yes)
			(effects
				(font
					(size 1.016 1.016)
					(thickness 0.1524)
				)
			)
		)
		(property "Device Type" "R402H16"
			(at 0.064008 -5.517896 180)
			(unlocked yes)
			(layer "F.Fab")
			(hide yes)
			(effects
				(font
					(size 1.016 1.016)
					(thickness 0.1524)
				)
			)
		)
		(duplicate_pad_numbers_are_jumpers no)
		(fp_line
			(start 0.508 -0.9398)
			(end -0.508 -0.9398)
			(stroke
				(width 0.1524)
				(type default)
			)
			(layer "F.SilkS")
		)
		(fp_line
			(start -0.508 -0.9398)
			(end -0.508 0.9398)
			(stroke
				(width 0.1524)
				(type default)
			)
			(layer "F.SilkS")
		)
		(fp_rect
			(start -0.508 0.9398)
			(end 0.508 -0.9398)
			(stroke
				(width 0)
				(type default)
			)
			(fill no)
			(layer "F.CrtYd")
		)
		(fp_rect
			(start -0.508 0.9398)
			(end 0.508 -0.9398)
			(stroke
				(width 0)
				(type default)
			)
			(fill no)
			(layer "F.Fab")
		)
		(pad "1" smd custom
			(at 0 -0.4445 180)
			(size 0.1397 0.1397)
			(layers "F.Cu" "F.Mask" "F.Paste")
			(net "P3V3")
			(options
				(clearance outline)
				(anchor circle)
			)
			(primitives
				(gr_poly
					(pts
						(arc
							(start -0.1778 -0.2794)
							(mid -0.249642 -0.249642)
							(end -0.2794 -0.1778)
						)
						(arc
							(start -0.2794 0.1778)
							(mid -0.249642 0.249642)
							(end -0.1778 0.2794)
						)
						(arc
							(start 0.1778 0.2794)
							(mid 0.249642 0.249642)
							(end 0.2794 0.1778)
						)
						(arc
							(start 0.2794 -0.1778)
							(mid 0.249642 -0.249642)
							(end 0.1778 -0.2794)
						)
					)
					(width 0)
					(fill yes)
				)
			)
		)
		(pad "2" smd custom
			(at 0 0.4445 180)
			(size 0.1397 0.1397)
			(layers "F.Cu" "F.Mask" "F.Paste")
			(net "ATTN_LED_DR12_N")
			(options
				(clearance outline)
				(anchor circle)
			)
			(primitives
				(gr_poly
					(pts
						(arc
							(start -0.1778 -0.2794)
							(mid -0.249642 -0.249642)
							(end -0.2794 -0.1778)
						)
						(arc
							(start -0.2794 0.1778)
							(mid -0.249642 0.249642)
							(end -0.1778 0.2794)
						)
						(arc
							(start 0.1778 0.2794)
							(mid 0.249642 0.249642)
							(end 0.2794 0.1778)
						)
						(arc
							(start 0.2794 -0.1778)
							(mid 0.249642 -0.249642)
							(end 0.1778 -0.2794)
						)
					)
					(width 0)
					(fill yes)
				)
			)
		)
	)
	(footprint ""
		(layer "F.Cu")
		(at 100.33 -313.817 180)
		(property "Reference" "R9100"
			(at 0 0 180)
			(layer "F.SilkS")
			(hide yes)
			(effects
				(font
					(size 1.27 1.27)
				)
			)
		)
		(property "Value" "27R2F-GP"
			(at 0.064008 -3.993896 180)
			(unlocked yes)
			(layer "F.Fab")
			(hide yes)
			(effects
				(font
					(size 1.016 1.016)
					(thickness 0.1524)
				)
			)
		)
		(property "Device Type" "R402H16"
			(at 0.064008 -5.517896 180)
			(unlocked yes)
			(layer "F.Fab")
			(hide yes)
			(effects
				(font
					(size 1.016 1.016)
					(thickness 0.1524)
				)
			)
		)
		(duplicate_pad_numbers_are_jumpers no)
		(fp_line
			(start 0.508 -0.9398)
			(end -0.508 -0.9398)
			(stroke
				(width 0.1524)
				(type default)
			)
			(layer "F.SilkS")
		)
		(fp_line
			(start -0.508 -0.9398)
			(end -0.508 0.9398)
			(stroke
				(width 0.1524)
				(type default)
			)
			(layer "F.SilkS")
		)
		(fp_rect
			(start -0.508 0.9398)
			(end 0.508 -0.9398)
			(stroke
				(width 0)
				(type default)
			)
			(fill no)
			(layer "F.CrtYd")
		)
		(fp_rect
			(start -0.508 0.9398)
			(end 0.508 -0.9398)
			(stroke
				(width 0)
				(type default)
			)
			(fill no)
			(layer "F.Fab")
		)
		(pad "1" smd custom
			(at 0 -0.4445 180)
			(size 0.1397 0.1397)
			(layers "F.Cu" "F.Mask" "F.Paste")
			(net "PE_CLK_100M_DR6_2_R_P")
			(options
				(clearance outline)
				(anchor circle)
			)
			(primitives
				(gr_poly
					(pts
						(arc
							(start -0.1778 -0.2794)
							(mid -0.249642 -0.249642)
							(end -0.2794 -0.1778)
						)
						(arc
							(start -0.2794 0.1778)
							(mid -0.249642 0.249642)
							(end -0.1778 0.2794)
						)
						(arc
							(start 0.1778 0.2794)
							(mid 0.249642 0.249642)
							(end 0.2794 0.1778)
						)
						(arc
							(start 0.2794 -0.1778)
							(mid 0.249642 -0.249642)
							(end 0.1778 -0.2794)
						)
					)
					(width 0)
					(fill yes)
				)
			)
		)
		(pad "2" smd custom
			(at 0 0.4445 180)
			(size 0.1397 0.1397)
			(layers "F.Cu" "F.Mask" "F.Paste")
			(net "PE_CLK100M_DR6_2_P")
			(options
				(clearance outline)
				(anchor circle)
			)
			(primitives
				(gr_poly
					(pts
						(arc
							(start -0.1778 -0.2794)
							(mid -0.249642 -0.249642)
							(end -0.2794 -0.1778)
						)
						(arc
							(start -0.2794 0.1778)
							(mid -0.249642 0.249642)
							(end -0.1778 0.2794)
						)
						(arc
							(start 0.1778 0.2794)
							(mid 0.249642 0.249642)
							(end 0.2794 0.1778)
						)
						(arc
							(start 0.2794 -0.1778)
							(mid 0.249642 -0.249642)
							(end 0.1778 -0.2794)
						)
					)
					(width 0)
					(fill yes)
				)
			)
		)
	)
	(footprint ""
		(layer "F.Cu")
		(at 43.1292 -196.9516)
		(property "Reference" "R9247"
			(at 0 0 0)
			(layer "F.SilkS")
			(hide yes)
			(effects
				(font
					(size 1.27 1.27)
				)
			)
		)
		(property "Value" "2R2010F-GP"
			(at 0.0762 -4.5466 0)
			(unlocked yes)
			(layer "F.Fab")
			(hide yes)
			(effects
				(font
					(size 1.016 1.016)
					(thickness 0.1524)
				)
			)
		)
		(property "Device Type" "R2010H26"
			(at 0.0762 -6.1468 0)
			(unlocked yes)
			(layer "F.Fab")
			(hide yes)
			(effects
				(font
					(size 1.016 1.016)
					(thickness 0.1524)
				)
			)
		)
		(duplicate_pad_numbers_are_jumpers no)
		(fp_line
			(start -3.302 -1.651)
			(end -3.302 1.651)
			(stroke
				(width 0.1524)
				(type default)
			)
			(layer "F.SilkS")
		)
		(fp_line
			(start -3.302 1.651)
			(end 3.302 1.651)
			(stroke
				(width 0.1524)
				(type default)
			)
			(layer "F.SilkS")
		)
		(fp_line
			(start 3.302 -1.651)
			(end -3.302 -1.651)
			(stroke
				(width 0.1524)
				(type default)
			)
			(layer "F.SilkS")
		)
		(fp_line
			(start 3.302 1.651)
			(end 3.302 -1.651)
			(stroke
				(width 0.1524)
				(type default)
			)
			(layer "F.SilkS")
		)
		(fp_rect
			(start -3.3782 1.7272)
			(end 3.3782 -1.7272)
			(stroke
				(width 0)
				(type default)
			)
			(fill no)
			(layer "F.CrtYd")
		)
		(fp_poly
			(pts
				(xy 3.3782 -1.7272) (xy -3.3782 -1.7272) (xy -3.3782 1.7272) (xy 3.3782 1.7272)
			)
			(stroke
				(width 0)
				(type default)
			)
			(fill no)
			(layer "F.Fab")
		)
		(pad "1" smd rect
			(at -2.3495 0)
			(size 1.143 2.794)
			(layers "F.Cu" "F.Mask" "F.Paste")
			(net "P12V_SSD8")
		)
		(pad "2" smd rect
			(at 2.3495 0)
			(size 1.143 2.794)
			(layers "F.Cu" "F.Mask" "F.Paste")
			(net "12V_PRECH_SSD8")
		)
	)
	(footprint ""
		(layer "F.Cu")
		(at 45.339 -244.729 -90)
		(property "Reference" "R9829"
			(at 0 0 270)
			(layer "F.SilkS")
			(hide yes)
			(effects
				(font
					(size 1.27 1.27)
				)
			)
		)
		(property "Value" "0R2J-2-GP"
			(at 0.064008 -3.993896 270)
			(unlocked yes)
			(layer "F.Fab")
			(hide yes)
			(effects
				(font
					(size 1.016 1.016)
					(thickness 0.1524)
				)
			)
		)
		(property "Device Type" "R402H16"
			(at 0.064008 -5.517896 270)
			(unlocked yes)
			(layer "F.Fab")
			(hide yes)
			(effects
				(font
					(size 1.016 1.016)
					(thickness 0.1524)
				)
			)
		)
		(duplicate_pad_numbers_are_jumpers no)
		(fp_line
			(start -0.508 -0.9398)
			(end -0.508 0.9398)
			(stroke
				(width 0.1524)
				(type default)
			)
			(layer "F.SilkS")
		)
		(fp_line
			(start 0.508 -0.9398)
			(end -0.508 -0.9398)
			(stroke
				(width 0.1524)
				(type default)
			)
			(layer "F.SilkS")
		)
		(fp_rect
			(start -0.508 0.9398)
			(end 0.508 -0.9398)
			(stroke
				(width 0)
				(type default)
			)
			(fill no)
			(layer "F.CrtYd")
		)
		(fp_rect
			(start -0.508 0.9398)
			(end 0.508 -0.9398)
			(stroke
				(width 0)
				(type default)
			)
			(fill no)
			(layer "F.Fab")
		)
		(pad "1" smd custom
			(at 0 -0.4445 270)
			(size 0.1397 0.1397)
			(layers "F.Cu" "F.Mask" "F.Paste")
			(net "ATTN_LED_DR7_AND")
			(options
				(clearance outline)
				(anchor circle)
			)
			(primitives
				(gr_poly
					(pts
						(arc
							(start -0.1778 -0.2794)
							(mid -0.249642 -0.249642)
							(end -0.2794 -0.1778)
						)
						(arc
							(start -0.2794 0.1778)
							(mid -0.249642 0.249642)
							(end -0.1778 0.2794)
						)
						(arc
							(start 0.1778 0.2794)
							(mid 0.249642 0.249642)
							(end 0.2794 0.1778)
						)
						(arc
							(start 0.2794 -0.1778)
							(mid 0.249642 -0.249642)
							(end 0.1778 -0.2794)
						)
					)
					(width 0)
					(fill yes)
				)
			)
		)
		(pad "2" smd custom
			(at 0 0.4445 270)
			(size 0.1397 0.1397)
			(layers "F.Cu" "F.Mask" "F.Paste")
			(net "ATTN_LED_DR7_AND_R")
			(options
				(clearance outline)
				(anchor circle)
			)
			(primitives
				(gr_poly
					(pts
						(arc
							(start -0.1778 -0.2794)
							(mid -0.249642 -0.249642)
							(end -0.2794 -0.1778)
						)
						(arc
							(start -0.2794 0.1778)
							(mid -0.249642 0.249642)
							(end -0.1778 0.2794)
						)
						(arc
							(start 0.1778 0.2794)
							(mid 0.249642 0.249642)
							(end 0.2794 0.1778)
						)
						(arc
							(start 0.2794 -0.1778)
							(mid 0.249642 -0.249642)
							(end 0.1778 -0.2794)
						)
					)
					(width 0)
					(fill yes)
				)
			)
		)
	)
	(footprint ""
		(layer "F.Cu")
		(at 90.17 -445.262)
		(property "Reference" "R9598"
			(at 0 0 0)
			(layer "F.SilkS")
			(hide yes)
			(effects
				(font
					(size 1.27 1.27)
				)
			)
		)
		(property "Value" "10R2F-L-GP"
			(at 0.064008 -3.993896 0)
			(unlocked yes)
			(layer "F.Fab")
			(hide yes)
			(effects
				(font
					(size 1.016 1.016)
					(thickness 0.1524)
				)
			)
		)
		(property "Device Type" "R402H14"
			(at 0.064008 -5.517896 0)
			(unlocked yes)
			(layer "F.Fab")
			(hide yes)
			(effects
				(font
					(size 1.016 1.016)
					(thickness 0.1524)
				)
			)
		)
		(duplicate_pad_numbers_are_jumpers no)
		(fp_line
			(start -0.508 -0.9398)
			(end -0.508 0.9398)
			(stroke
				(width 0.1524)
				(type default)
			)
			(layer "F.SilkS")
		)
		(fp_line
			(start 0.508 -0.9398)
			(end -0.508 -0.9398)
			(stroke
				(width 0.1524)
				(type default)
			)
			(layer "F.SilkS")
		)
		(fp_rect
			(start -0.508 0.9398)
			(end 0.508 -0.9398)
			(stroke
				(width 0)
				(type default)
			)
			(fill no)
			(layer "F.CrtYd")
		)
		(fp_rect
			(start -0.508 0.9398)
			(end 0.508 -0.9398)
			(stroke
				(width 0)
				(type default)
			)
			(fill no)
			(layer "F.Fab")
		)
		(pad "1" smd custom
			(at 0 -0.4445)
			(size 0.1397 0.1397)
			(layers "F.Cu" "F.Mask" "F.Paste")
			(net "SSD_PRSNT_NET5")
			(options
				(clearance outline)
				(anchor circle)
			)
			(primitives
				(gr_poly
					(pts
						(arc
							(start -0.1778 -0.2794)
							(mid -0.249642 -0.249642)
							(end -0.2794 -0.1778)
						)
						(arc
							(start -0.2794 0.1778)
							(mid -0.249642 0.249642)
							(end -0.1778 0.2794)
						)
						(arc
							(start 0.1778 0.2794)
							(mid 0.249642 0.249642)
							(end 0.2794 0.1778)
						)
						(arc
							(start 0.2794 -0.1778)
							(mid 0.249642 -0.249642)
							(end 0.1778 -0.2794)
						)
					)
					(width 0)
					(fill yes)
				)
			)
		)
		(pad "2" smd custom
			(at 0 0.4445)
			(size 0.1397 0.1397)
			(layers "F.Cu" "F.Mask" "F.Paste")
			(net "SSD_PRSNT5")
			(options
				(clearance outline)
				(anchor circle)
			)
			(primitives
				(gr_poly
					(pts
						(arc
							(start -0.1778 -0.2794)
							(mid -0.249642 -0.249642)
							(end -0.2794 -0.1778)
						)
						(arc
							(start -0.2794 0.1778)
							(mid -0.249642 0.249642)
							(end -0.1778 0.2794)
						)
						(arc
							(start 0.1778 0.2794)
							(mid 0.249642 0.249642)
							(end 0.2794 0.1778)
						)
						(arc
							(start 0.2794 -0.1778)
							(mid 0.249642 -0.249642)
							(end 0.1778 -0.2794)
						)
					)
					(width 0)
					(fill yes)
				)
			)
		)
	)
	(footprint ""
		(layer "F.Cu")
		(at 93.853 -202.184)
		(property "Reference" "R9087"
			(at 0 0 0)
			(layer "F.SilkS")
			(hide yes)
			(effects
				(font
					(size 1.27 1.27)
				)
			)
		)
		(property "Value" "27R2F-GP"
			(at 0.064008 -3.993896 0)
			(unlocked yes)
			(layer "F.Fab")
			(hide yes)
			(effects
				(font
					(size 1.016 1.016)
					(thickness 0.1524)
				)
			)
		)
		(property "Device Type" "R402H16"
			(at 0.064008 -5.517896 0)
			(unlocked yes)
			(layer "F.Fab")
			(hide yes)
			(effects
				(font
					(size 1.016 1.016)
					(thickness 0.1524)
				)
			)
		)
		(duplicate_pad_numbers_are_jumpers no)
		(fp_line
			(start -0.508 -0.9398)
			(end -0.508 0.9398)
			(stroke
				(width 0.1524)
				(type default)
			)
			(layer "F.SilkS")
		)
		(fp_line
			(start 0.508 -0.9398)
			(end -0.508 -0.9398)
			(stroke
				(width 0.1524)
				(type default)
			)
			(layer "F.SilkS")
		)
		(fp_rect
			(start -0.508 0.9398)
			(end 0.508 -0.9398)
			(stroke
				(width 0)
				(type default)
			)
			(fill no)
			(layer "F.CrtYd")
		)
		(fp_rect
			(start -0.508 0.9398)
			(end 0.508 -0.9398)
			(stroke
				(width 0)
				(type default)
			)
			(fill no)
			(layer "F.Fab")
		)
		(pad "1" smd custom
			(at 0 -0.4445)
			(size 0.1397 0.1397)
			(layers "F.Cu" "F.Mask" "F.Paste")
			(net "PE_CLK_100M_DR4_2_R_P")
			(options
				(clearance outline)
				(anchor circle)
			)
			(primitives
				(gr_poly
					(pts
						(arc
							(start -0.1778 -0.2794)
							(mid -0.249642 -0.249642)
							(end -0.2794 -0.1778)
						)
						(arc
							(start -0.2794 0.1778)
							(mid -0.249642 0.249642)
							(end -0.1778 0.2794)
						)
						(arc
							(start 0.1778 0.2794)
							(mid 0.249642 0.249642)
							(end 0.2794 0.1778)
						)
						(arc
							(start 0.2794 -0.1778)
							(mid 0.249642 -0.249642)
							(end 0.1778 -0.2794)
						)
					)
					(width 0)
					(fill yes)
				)
			)
		)
		(pad "2" smd custom
			(at 0 0.4445)
			(size 0.1397 0.1397)
			(layers "F.Cu" "F.Mask" "F.Paste")
			(net "PE_CLK100M_DR4_2_P")
			(options
				(clearance outline)
				(anchor circle)
			)
			(primitives
				(gr_poly
					(pts
						(arc
							(start -0.1778 -0.2794)
							(mid -0.249642 -0.249642)
							(end -0.2794 -0.1778)
						)
						(arc
							(start -0.2794 0.1778)
							(mid -0.249642 0.249642)
							(end -0.1778 0.2794)
						)
						(arc
							(start 0.1778 0.2794)
							(mid 0.249642 0.249642)
							(end 0.2794 0.1778)
						)
						(arc
							(start 0.2794 -0.1778)
							(mid 0.249642 -0.249642)
							(end 0.1778 -0.2794)
						)
					)
					(width 0)
					(fill yes)
				)
			)
		)
	)
	(footprint ""
		(layer "F.Cu")
		(at 94.234 -297.942)
		(property "Reference" "C8849"
			(at 0 0 0)
			(layer "F.SilkS")
			(hide yes)
			(effects
				(font
					(size 1.27 1.27)
				)
			)
		)
		(property "Value" "SCD1U16V2KX-3GP"
			(at 1.1811 -2.7051 0)
			(unlocked yes)
			(layer "F.Fab")
			(hide yes)
			(effects
				(font
					(size 1.016 1.016)
					(thickness 0.1524)
				)
			)
		)
		(property "Device Type" "C402H22"
			(at 1.1811 -4.2291 0)
			(unlocked yes)
			(layer "F.Fab")
			(hide yes)
			(effects
				(font
					(size 1.016 1.016)
					(thickness 0.1524)
				)
			)
		)
		(duplicate_pad_numbers_are_jumpers no)
		(fp_rect
			(start -0.4318 0.9525)
			(end 0.4318 -0.9525)
			(stroke
				(width 0)
				(type default)
			)
			(fill no)
			(layer "F.CrtYd")
		)
		(fp_rect
			(start -0.4318 0.9525)
			(end 0.4318 -0.9525)
			(stroke
				(width 0)
				(type default)
			)
			(fill no)
			(layer "F.Fab")
		)
		(pad "1" smd custom
			(at 0 -0.4445)
			(size 0.1524 0.1524)
			(layers "F.Cu" "F.Mask" "F.Paste")
			(net "VDD_IO_2")
			(options
				(clearance outline)
				(anchor circle)
			)
			(primitives
				(gr_poly
					(pts
						(arc
							(start 0.3048 -0.2032)
							(mid 0.275042 -0.275042)
							(end 0.2032 -0.3048)
						)
						(arc
							(start -0.2032 -0.3048)
							(mid -0.275042 -0.275042)
							(end -0.3048 -0.2032)
						)
						(arc
							(start -0.3048 0.2032)
							(mid -0.275042 0.275042)
							(end -0.2032 0.3048)
						)
						(arc
							(start 0.2032 0.3048)
							(mid 0.275042 0.275042)
							(end 0.3048 0.2032)
						)
					)
					(width 0)
					(fill yes)
				)
			)
		)
		(pad "2" smd custom
			(at 0 0.4445)
			(size 0.1524 0.1524)
			(layers "F.Cu" "F.Mask" "F.Paste")
			(net "GND")
			(options
				(clearance outline)
				(anchor circle)
			)
			(primitives
				(gr_poly
					(pts
						(arc
							(start 0.3048 -0.2032)
							(mid 0.275042 -0.275042)
							(end 0.2032 -0.3048)
						)
						(arc
							(start -0.2032 -0.3048)
							(mid -0.275042 -0.275042)
							(end -0.3048 -0.2032)
						)
						(arc
							(start -0.3048 0.2032)
							(mid -0.275042 0.275042)
							(end -0.2032 0.3048)
						)
						(arc
							(start 0.2032 0.3048)
							(mid 0.275042 0.275042)
							(end 0.3048 0.2032)
						)
					)
					(width 0)
					(fill yes)
				)
			)
		)
	)
	(footprint ""
		(layer "F.Cu")
		(at 32.2072 -215.2142 180)
		(property "Reference" "SR1115"
			(at 0 0 180)
			(layer "F.SilkS")
			(hide yes)
			(effects
				(font
					(size 1.27 1.27)
				)
			)
		)
		(property "Value" "4K7R2F-GP"
			(at 0.064008 -3.993896 180)
			(unlocked yes)
			(layer "F.Fab")
			(hide yes)
			(effects
				(font
					(size 1.016 1.016)
					(thickness 0.1524)
				)
			)
		)
		(property "Device Type" "R402H16"
			(at 0.064008 -5.517896 180)
			(unlocked yes)
			(layer "F.Fab")
			(hide yes)
			(effects
				(font
					(size 1.016 1.016)
					(thickness 0.1524)
				)
			)
		)
		(duplicate_pad_numbers_are_jumpers no)
		(fp_line
			(start 0.508 -0.9398)
			(end -0.508 -0.9398)
			(stroke
				(width 0.1524)
				(type default)
			)
			(layer "F.SilkS")
		)
		(fp_line
			(start -0.508 -0.9398)
			(end -0.508 0.9398)
			(stroke
				(width 0.1524)
				(type default)
			)
			(layer "F.SilkS")
		)
		(fp_rect
			(start -0.508 0.9398)
			(end 0.508 -0.9398)
			(stroke
				(width 0)
				(type default)
			)
			(fill no)
			(layer "F.CrtYd")
		)
		(fp_rect
			(start -0.508 0.9398)
			(end 0.508 -0.9398)
			(stroke
				(width 0)
				(type default)
			)
			(fill no)
			(layer "F.Fab")
		)
		(pad "1" smd custom
			(at 0 -0.4445 180)
			(size 0.1397 0.1397)
			(layers "F.Cu" "F.Mask" "F.Paste")
			(net "P3V3")
			(options
				(clearance outline)
				(anchor circle)
			)
			(primitives
				(gr_poly
					(pts
						(arc
							(start -0.1778 -0.2794)
							(mid -0.249642 -0.249642)
							(end -0.2794 -0.1778)
						)
						(arc
							(start -0.2794 0.1778)
							(mid -0.249642 0.249642)
							(end -0.1778 0.2794)
						)
						(arc
							(start 0.1778 0.2794)
							(mid 0.249642 0.249642)
							(end 0.2794 0.1778)
						)
						(arc
							(start 0.2794 -0.1778)
							(mid 0.249642 -0.249642)
							(end 0.1778 -0.2794)
						)
					)
					(width 0)
					(fill yes)
				)
			)
		)
		(pad "2" smd custom
			(at 0 0.4445 180)
			(size 0.1397 0.1397)
			(layers "F.Cu" "F.Mask" "F.Paste")
			(net "DUALPORTEN#12")
			(options
				(clearance outline)
				(anchor circle)
			)
			(primitives
				(gr_poly
					(pts
						(arc
							(start -0.1778 -0.2794)
							(mid -0.249642 -0.249642)
							(end -0.2794 -0.1778)
						)
						(arc
							(start -0.2794 0.1778)
							(mid -0.249642 0.249642)
							(end -0.1778 0.2794)
						)
						(arc
							(start 0.1778 0.2794)
							(mid 0.249642 0.249642)
							(end 0.2794 0.1778)
						)
						(arc
							(start 0.2794 -0.1778)
							(mid 0.249642 -0.249642)
							(end 0.1778 -0.2794)
						)
					)
					(width 0)
					(fill yes)
				)
			)
		)
	)
	(footprint ""
		(layer "F.Cu")
		(at 99.187 -115.062)
		(property "Reference" "R9604"
			(at 0 0 0)
			(layer "F.SilkS")
			(hide yes)
			(effects
				(font
					(size 1.27 1.27)
				)
			)
		)
		(property "Value" "10R2F-L-GP"
			(at 0.064008 -3.993896 0)
			(unlocked yes)
			(layer "F.Fab")
			(hide yes)
			(effects
				(font
					(size 1.016 1.016)
					(thickness 0.1524)
				)
			)
		)
		(property "Device Type" "R402H14"
			(at 0.064008 -5.517896 0)
			(unlocked yes)
			(layer "F.Fab")
			(hide yes)
			(effects
				(font
					(size 1.016 1.016)
					(thickness 0.1524)
				)
			)
		)
		(duplicate_pad_numbers_are_jumpers no)
		(fp_line
			(start -0.508 -0.9398)
			(end -0.508 0.9398)
			(stroke
				(width 0.1524)
				(type default)
			)
			(layer "F.SilkS")
		)
		(fp_line
			(start 0.508 -0.9398)
			(end -0.508 -0.9398)
			(stroke
				(width 0.1524)
				(type default)
			)
			(layer "F.SilkS")
		)
		(fp_rect
			(start -0.508 0.9398)
			(end 0.508 -0.9398)
			(stroke
				(width 0)
				(type default)
			)
			(fill no)
			(layer "F.CrtYd")
		)
		(fp_rect
			(start -0.508 0.9398)
			(end 0.508 -0.9398)
			(stroke
				(width 0)
				(type default)
			)
			(fill no)
			(layer "F.Fab")
		)
		(pad "1" smd custom
			(at 0 -0.4445)
			(size 0.1397 0.1397)
			(layers "F.Cu" "F.Mask" "F.Paste")
			(net "SSD_PRSNT_NET8")
			(options
				(clearance outline)
				(anchor circle)
			)
			(primitives
				(gr_poly
					(pts
						(arc
							(start -0.1778 -0.2794)
							(mid -0.249642 -0.249642)
							(end -0.2794 -0.1778)
						)
						(arc
							(start -0.2794 0.1778)
							(mid -0.249642 0.249642)
							(end -0.1778 0.2794)
						)
						(arc
							(start 0.1778 0.2794)
							(mid 0.249642 0.249642)
							(end 0.2794 0.1778)
						)
						(arc
							(start 0.2794 -0.1778)
							(mid 0.249642 -0.249642)
							(end 0.1778 -0.2794)
						)
					)
					(width 0)
					(fill yes)
				)
			)
		)
		(pad "2" smd custom
			(at 0 0.4445)
			(size 0.1397 0.1397)
			(layers "F.Cu" "F.Mask" "F.Paste")
			(net "SSD_PRSNT8")
			(options
				(clearance outline)
				(anchor circle)
			)
			(primitives
				(gr_poly
					(pts
						(arc
							(start -0.1778 -0.2794)
							(mid -0.249642 -0.249642)
							(end -0.2794 -0.1778)
						)
						(arc
							(start -0.2794 0.1778)
							(mid -0.249642 0.249642)
							(end -0.1778 0.2794)
						)
						(arc
							(start 0.1778 0.2794)
							(mid 0.249642 0.249642)
							(end 0.2794 0.1778)
						)
						(arc
							(start 0.2794 -0.1778)
							(mid 0.249642 -0.249642)
							(end 0.1778 -0.2794)
						)
					)
					(width 0)
					(fill yes)
				)
			)
		)
	)
	(footprint ""
		(layer "F.Cu")
		(at 229.67696 -138.11885)
		(property "Reference" "C9521"
			(at 0 0 0)
			(layer "F.SilkS")
			(hide yes)
			(effects
				(font
					(size 1.27 1.27)
				)
			)
		)
		(property "Value" "SCD1U16V2KX-3GP"
			(at 1.1811 -2.7051 0)
			(unlocked yes)
			(layer "F.Fab")
			(hide yes)
			(effects
				(font
					(size 1.016 1.016)
					(thickness 0.1524)
				)
			)
		)
		(property "Device Type" "C402H22"
			(at 1.1811 -4.2291 0)
			(unlocked yes)
			(layer "F.Fab")
			(hide yes)
			(effects
				(font
					(size 1.016 1.016)
					(thickness 0.1524)
				)
			)
		)
		(duplicate_pad_numbers_are_jumpers no)
		(fp_rect
			(start -0.4318 0.9525)
			(end 0.4318 -0.9525)
			(stroke
				(width 0)
				(type default)
			)
			(fill no)
			(layer "F.CrtYd")
		)
		(fp_rect
			(start -0.4318 0.9525)
			(end 0.4318 -0.9525)
			(stroke
				(width 0)
				(type default)
			)
			(fill no)
			(layer "F.Fab")
		)
		(pad "1" smd custom
			(at 0 -0.4445)
			(size 0.1524 0.1524)
			(layers "F.Cu" "F.Mask" "F.Paste")
			(net "P3V3")
			(options
				(clearance outline)
				(anchor circle)
			)
			(primitives
				(gr_poly
					(pts
						(arc
							(start 0.3048 -0.2032)
							(mid 0.275042 -0.275042)
							(end 0.2032 -0.3048)
						)
						(arc
							(start -0.2032 -0.3048)
							(mid -0.275042 -0.275042)
							(end -0.3048 -0.2032)
						)
						(arc
							(start -0.3048 0.2032)
							(mid -0.275042 0.275042)
							(end -0.2032 0.3048)
						)
						(arc
							(start 0.2032 0.3048)
							(mid 0.275042 0.275042)
							(end 0.3048 0.2032)
						)
					)
					(width 0)
					(fill yes)
				)
			)
		)
		(pad "2" smd custom
			(at 0 0.4445)
			(size 0.1524 0.1524)
			(layers "F.Cu" "F.Mask" "F.Paste")
			(net "GND")
			(options
				(clearance outline)
				(anchor circle)
			)
			(primitives
				(gr_poly
					(pts
						(arc
							(start 0.3048 -0.2032)
							(mid 0.275042 -0.275042)
							(end 0.2032 -0.3048)
						)
						(arc
							(start -0.2032 -0.3048)
							(mid -0.275042 -0.275042)
							(end -0.3048 -0.2032)
						)
						(arc
							(start -0.3048 0.2032)
							(mid -0.275042 0.275042)
							(end -0.2032 0.3048)
						)
						(arc
							(start 0.2032 0.3048)
							(mid 0.275042 0.275042)
							(end 0.3048 0.2032)
						)
					)
					(width 0)
					(fill yes)
				)
			)
		)
	)
	(footprint ""
		(layer "F.Cu")
		(at 106.045 -205.994 180)
		(property "Reference" "C9351"
			(at 0 0 180)
			(layer "F.SilkS")
			(hide yes)
			(effects
				(font
					(size 1.27 1.27)
				)
			)
		)
		(property "Value" "SC1KP50V2KX-1GP"
			(at 1.1811 -2.7051 180)
			(unlocked yes)
			(layer "F.Fab")
			(hide yes)
			(effects
				(font
					(size 1.016 1.016)
					(thickness 0.1524)
				)
			)
		)
		(property "Device Type" "C402H22"
			(at 1.1811 -4.2291 180)
			(unlocked yes)
			(layer "F.Fab")
			(hide yes)
			(effects
				(font
					(size 1.016 1.016)
					(thickness 0.1524)
				)
			)
		)
		(duplicate_pad_numbers_are_jumpers no)
		(fp_rect
			(start -0.4318 0.9525)
			(end 0.4318 -0.9525)
			(stroke
				(width 0)
				(type default)
			)
			(fill no)
			(layer "F.CrtYd")
		)
		(fp_rect
			(start -0.4318 0.9525)
			(end 0.4318 -0.9525)
			(stroke
				(width 0)
				(type default)
			)
			(fill no)
			(layer "F.Fab")
		)
		(pad "1" smd custom
			(at 0 -0.4445 180)
			(size 0.1524 0.1524)
			(layers "F.Cu" "F.Mask" "F.Paste")
			(net "SSD_PRSNT3")
			(options
				(clearance outline)
				(anchor circle)
			)
			(primitives
				(gr_poly
					(pts
						(arc
							(start 0.3048 -0.2032)
							(mid 0.275042 -0.275042)
							(end 0.2032 -0.3048)
						)
						(arc
							(start -0.2032 -0.3048)
							(mid -0.275042 -0.275042)
							(end -0.3048 -0.2032)
						)
						(arc
							(start -0.3048 0.2032)
							(mid -0.275042 0.275042)
							(end -0.2032 0.3048)
						)
						(arc
							(start 0.2032 0.3048)
							(mid 0.275042 0.275042)
							(end 0.3048 0.2032)
						)
					)
					(width 0)
					(fill yes)
				)
			)
		)
		(pad "2" smd custom
			(at 0 0.4445 180)
			(size 0.1524 0.1524)
			(layers "F.Cu" "F.Mask" "F.Paste")
			(net "GND")
			(options
				(clearance outline)
				(anchor circle)
			)
			(primitives
				(gr_poly
					(pts
						(arc
							(start 0.3048 -0.2032)
							(mid 0.275042 -0.275042)
							(end 0.2032 -0.3048)
						)
						(arc
							(start -0.2032 -0.3048)
							(mid -0.275042 -0.275042)
							(end -0.3048 -0.2032)
						)
						(arc
							(start -0.3048 0.2032)
							(mid -0.275042 0.275042)
							(end -0.2032 0.3048)
						)
						(arc
							(start 0.2032 0.3048)
							(mid 0.275042 0.275042)
							(end 0.3048 0.2032)
						)
					)
					(width 0)
					(fill yes)
				)
			)
		)
	)
	(footprint ""
		(layer "F.Cu")
		(at 232.029 -431.546 -90)
		(property "Reference" "PC1288"
			(at 0 0 270)
			(layer "F.SilkS")
			(hide yes)
			(effects
				(font
					(size 1.27 1.27)
				)
			)
		)
		(property "Value" "SC1U10V2KX-7-GP"
			(at 1.1811 -2.7051 270)
			(unlocked yes)
			(layer "F.Fab")
			(hide yes)
			(effects
				(font
					(size 1.016 1.016)
					(thickness 0.1524)
				)
			)
		)
		(property "Device Type" "C402H22"
			(at 1.1811 -4.2291 270)
			(unlocked yes)
			(layer "F.Fab")
			(hide yes)
			(effects
				(font
					(size 1.016 1.016)
					(thickness 0.1524)
				)
			)
		)
		(duplicate_pad_numbers_are_jumpers no)
		(fp_rect
			(start -0.4318 0.9525)
			(end 0.4318 -0.9525)
			(stroke
				(width 0)
				(type default)
			)
			(fill no)
			(layer "F.CrtYd")
		)
		(fp_rect
			(start -0.4318 0.9525)
			(end 0.4318 -0.9525)
			(stroke
				(width 0)
				(type default)
			)
			(fill no)
			(layer "F.Fab")
		)
		(pad "1" smd custom
			(at 0 -0.4445 270)
			(size 0.1524 0.1524)
			(layers "F.Cu" "F.Mask" "F.Paste")
			(net "P3V3_CC_R")
			(options
				(clearance outline)
				(anchor circle)
			)
			(primitives
				(gr_poly
					(pts
						(arc
							(start 0.3048 -0.2032)
							(mid 0.275042 -0.275042)
							(end 0.2032 -0.3048)
						)
						(arc
							(start -0.2032 -0.3048)
							(mid -0.275042 -0.275042)
							(end -0.3048 -0.2032)
						)
						(arc
							(start -0.3048 0.2032)
							(mid -0.275042 0.275042)
							(end -0.2032 0.3048)
						)
						(arc
							(start 0.2032 0.3048)
							(mid 0.275042 0.275042)
							(end 0.3048 0.2032)
						)
					)
					(width 0)
					(fill yes)
				)
			)
		)
		(pad "2" smd custom
			(at 0 0.4445 270)
			(size 0.1524 0.1524)
			(layers "F.Cu" "F.Mask" "F.Paste")
			(net "P3V3_VFB")
			(options
				(clearance outline)
				(anchor circle)
			)
			(primitives
				(gr_poly
					(pts
						(arc
							(start 0.3048 -0.2032)
							(mid 0.275042 -0.275042)
							(end 0.2032 -0.3048)
						)
						(arc
							(start -0.2032 -0.3048)
							(mid -0.275042 -0.275042)
							(end -0.3048 -0.2032)
						)
						(arc
							(start -0.3048 0.2032)
							(mid -0.275042 0.275042)
							(end -0.2032 0.3048)
						)
						(arc
							(start 0.2032 0.3048)
							(mid 0.275042 0.275042)
							(end 0.3048 0.2032)
						)
					)
					(width 0)
					(fill yes)
				)
			)
		)
	)
	(footprint ""
		(layer "F.Cu")
		(at 16.160242 -155.66898 180)
		(property "Reference" "R9954"
			(at 0 0 180)
			(layer "F.SilkS")
			(hide yes)
			(effects
				(font
					(size 1.27 1.27)
				)
			)
		)
		(property "Value" "4K7R2J-2-GP"
			(at 0.064008 -3.993896 180)
			(unlocked yes)
			(layer "F.Fab")
			(hide yes)
			(effects
				(font
					(size 1.016 1.016)
					(thickness 0.1524)
				)
			)
		)
		(property "Device Type" "R402H16"
			(at 0.064008 -5.517896 180)
			(unlocked yes)
			(layer "F.Fab")
			(hide yes)
			(effects
				(font
					(size 1.016 1.016)
					(thickness 0.1524)
				)
			)
		)
		(duplicate_pad_numbers_are_jumpers no)
		(fp_line
			(start 0.508 -0.9398)
			(end -0.508 -0.9398)
			(stroke
				(width 0.1524)
				(type default)
			)
			(layer "F.SilkS")
		)
		(fp_line
			(start -0.508 -0.9398)
			(end -0.508 0.9398)
			(stroke
				(width 0.1524)
				(type default)
			)
			(layer "F.SilkS")
		)
		(fp_rect
			(start -0.508 0.9398)
			(end 0.508 -0.9398)
			(stroke
				(width 0)
				(type default)
			)
			(fill no)
			(layer "F.CrtYd")
		)
		(fp_rect
			(start -0.508 0.9398)
			(end 0.508 -0.9398)
			(stroke
				(width 0)
				(type default)
			)
			(fill no)
			(layer "F.Fab")
		)
		(pad "1" smd custom
			(at 0 -0.4445 180)
			(size 0.1397 0.1397)
			(layers "F.Cu" "F.Mask" "F.Paste")
			(net "P3V3")
			(options
				(clearance outline)
				(anchor circle)
			)
			(primitives
				(gr_poly
					(pts
						(arc
							(start -0.1778 -0.2794)
							(mid -0.249642 -0.249642)
							(end -0.2794 -0.1778)
						)
						(arc
							(start -0.2794 0.1778)
							(mid -0.249642 0.249642)
							(end -0.1778 0.2794)
						)
						(arc
							(start 0.1778 0.2794)
							(mid 0.249642 0.249642)
							(end 0.2794 0.1778)
						)
						(arc
							(start 0.2794 -0.1778)
							(mid 0.249642 -0.249642)
							(end 0.1778 -0.2794)
						)
					)
					(width 0)
					(fill yes)
				)
			)
		)
		(pad "2" smd custom
			(at 0 0.4445 180)
			(size 0.1397 0.1397)
			(layers "F.Cu" "F.Mask" "F.Paste")
			(net "SSD_ACT_DR13_MOS_N")
			(options
				(clearance outline)
				(anchor circle)
			)
			(primitives
				(gr_poly
					(pts
						(arc
							(start -0.1778 -0.2794)
							(mid -0.249642 -0.249642)
							(end -0.2794 -0.1778)
						)
						(arc
							(start -0.2794 0.1778)
							(mid -0.249642 0.249642)
							(end -0.1778 0.2794)
						)
						(arc
							(start 0.1778 0.2794)
							(mid 0.249642 0.249642)
							(end 0.2794 0.1778)
						)
						(arc
							(start 0.2794 -0.1778)
							(mid 0.249642 -0.249642)
							(end 0.1778 -0.2794)
						)
					)
					(width 0)
					(fill yes)
				)
			)
		)
	)
	(footprint ""
		(layer "F.Cu")
		(at 210.947 -403.9616 -90)
		(property "Reference" "Q31"
			(at 0 0 270)
			(layer "F.SilkS")
			(hide yes)
			(effects
				(font
					(size 1.27 1.27)
				)
			)
		)
		(property "Value" "2N7002A-7-GP"
			(at 0.127 -8.9662 270)
			(unlocked yes)
			(layer "F.Fab")
			(hide yes)
			(effects
				(font
					(size 1.016 1.016)
					(thickness 0.1524)
				)
			)
		)
		(property "Device Type" "SOT23DGS2D4H48"
			(at 0.127 -10.4902 270)
			(unlocked yes)
			(layer "F.Fab")
			(hide yes)
			(effects
				(font
					(size 1.016 1.016)
					(thickness 0.1524)
				)
			)
		)
		(duplicate_pad_numbers_are_jumpers no)
		(fp_line
			(start -1.651 1.778)
			(end 1.651 1.778)
			(stroke
				(width 0.1524)
				(type default)
			)
			(layer "F.SilkS")
		)
		(fp_line
			(start 1.651 1.778)
			(end 1.651 -1.778)
			(stroke
				(width 0.1524)
				(type default)
			)
			(layer "F.SilkS")
		)
		(fp_line
			(start -1.651 -1.778)
			(end -1.651 1.778)
			(stroke
				(width 0.1524)
				(type default)
			)
			(layer "F.SilkS")
		)
		(fp_line
			(start 1.651 -1.778)
			(end -1.651 -1.778)
			(stroke
				(width 0.1524)
				(type default)
			)
			(layer "F.SilkS")
		)
		(fp_poly
			(pts
				(xy -1.778 1.8796) (xy -1.778 -1.8796) (xy 1.778 -1.8796) (xy 1.778 1.8796)
			)
			(stroke
				(width 0)
				(type default)
			)
			(fill no)
			(layer "F.CrtYd")
		)
		(fp_poly
			(pts
				(xy -1.778 1.8796) (xy -1.778 -1.8796) (xy 1.778 -1.8796) (xy 1.778 1.8796)
			)
			(stroke
				(width 0)
				(type default)
			)
			(fill no)
			(layer "F.Fab")
		)
		(pad "D" smd custom
			(at 0 -0.9525 270)
			(size 0.1905 0.1905)
			(layers "F.Cu" "F.Mask" "F.Paste")
			(net "P12V_MOST1_GATE")
			(options
				(clearance outline)
				(anchor circle)
			)
			(primitives
				(gr_poly
					(pts
						(arc
							(start -0.1778 0.5715)
							(mid -0.321484 0.511984)
							(end -0.381 0.3683)
						)
						(arc
							(start -0.381 -0.3683)
							(mid -0.321484 -0.511984)
							(end -0.1778 -0.5715)
						)
						(arc
							(start 0.1778 -0.5715)
							(mid 0.321484 -0.511984)
							(end 0.381 -0.3683)
						)
						(arc
							(start 0.381 0.3683)
							(mid 0.321484 0.511984)
							(end 0.1778 0.5715)
						)
					)
					(width 0)
					(fill yes)
				)
			)
		)
		(pad "G" smd custom
			(at -0.98425 0.9525 270)
			(size 0.1905 0.1905)
			(layers "F.Cu" "F.Mask" "F.Paste")
			(net "SSD1_PWREN_R")
			(options
				(clearance outline)
				(anchor circle)
			)
			(primitives
				(gr_poly
					(pts
						(arc
							(start -0.1778 0.5715)
							(mid -0.321484 0.511984)
							(end -0.381 0.3683)
						)
						(arc
							(start -0.381 -0.3683)
							(mid -0.321484 -0.511984)
							(end -0.1778 -0.5715)
						)
						(arc
							(start 0.1778 -0.5715)
							(mid 0.321484 -0.511984)
							(end 0.381 -0.3683)
						)
						(arc
							(start 0.381 0.3683)
							(mid 0.321484 0.511984)
							(end 0.1778 0.5715)
						)
					)
					(width 0)
					(fill yes)
				)
			)
		)
		(pad "S" smd custom
			(at 0.98425 0.9525 270)
			(size 0.1905 0.1905)
			(layers "F.Cu" "F.Mask" "F.Paste")
			(net "GND")
			(options
				(clearance outline)
				(anchor circle)
			)
			(primitives
				(gr_poly
					(pts
						(arc
							(start -0.1778 0.5715)
							(mid -0.321484 0.511984)
							(end -0.381 0.3683)
						)
						(arc
							(start -0.381 -0.3683)
							(mid -0.321484 -0.511984)
							(end -0.1778 -0.5715)
						)
						(arc
							(start 0.1778 -0.5715)
							(mid 0.321484 -0.511984)
							(end 0.381 -0.3683)
						)
						(arc
							(start 0.381 0.3683)
							(mid 0.321484 0.511984)
							(end 0.1778 0.5715)
						)
					)
					(width 0)
					(fill yes)
				)
			)
		)
	)
	(footprint ""
		(layer "F.Cu")
		(at 20.066 -270.379952 -90)
		(property "Reference" "R9861"
			(at 0 0 270)
			(layer "F.SilkS")
			(hide yes)
			(effects
				(font
					(size 1.27 1.27)
				)
			)
		)
		(property "Value" "0R2J-2-GP"
			(at 0.064008 -3.993896 270)
			(unlocked yes)
			(layer "F.Fab")
			(hide yes)
			(effects
				(font
					(size 1.016 1.016)
					(thickness 0.1524)
				)
			)
		)
		(property "Device Type" "R402H16"
			(at 0.064008 -5.517896 270)
			(unlocked yes)
			(layer "F.Fab")
			(hide yes)
			(effects
				(font
					(size 1.016 1.016)
					(thickness 0.1524)
				)
			)
		)
		(duplicate_pad_numbers_are_jumpers no)
		(fp_line
			(start -0.508 -0.9398)
			(end -0.508 0.9398)
			(stroke
				(width 0.1524)
				(type default)
			)
			(layer "F.SilkS")
		)
		(fp_line
			(start 0.508 -0.9398)
			(end -0.508 -0.9398)
			(stroke
				(width 0.1524)
				(type default)
			)
			(layer "F.SilkS")
		)
		(fp_rect
			(start -0.508 0.9398)
			(end 0.508 -0.9398)
			(stroke
				(width 0)
				(type default)
			)
			(fill no)
			(layer "F.CrtYd")
		)
		(fp_rect
			(start -0.508 0.9398)
			(end 0.508 -0.9398)
			(stroke
				(width 0)
				(type default)
			)
			(fill no)
			(layer "F.Fab")
		)
		(pad "1" smd custom
			(at 0 -0.4445 270)
			(size 0.1397 0.1397)
			(layers "F.Cu" "F.Mask" "F.Paste")
			(net "ATTN_LED_DR12_AND")
			(options
				(clearance outline)
				(anchor circle)
			)
			(primitives
				(gr_poly
					(pts
						(arc
							(start -0.1778 -0.2794)
							(mid -0.249642 -0.249642)
							(end -0.2794 -0.1778)
						)
						(arc
							(start -0.2794 0.1778)
							(mid -0.249642 0.249642)
							(end -0.1778 0.2794)
						)
						(arc
							(start 0.1778 0.2794)
							(mid 0.249642 0.249642)
							(end 0.2794 0.1778)
						)
						(arc
							(start 0.2794 -0.1778)
							(mid 0.249642 -0.249642)
							(end 0.1778 -0.2794)
						)
					)
					(width 0)
					(fill yes)
				)
			)
		)
		(pad "2" smd custom
			(at 0 0.4445 270)
			(size 0.1397 0.1397)
			(layers "F.Cu" "F.Mask" "F.Paste")
			(net "ATTN_LED_DR12_AND_R")
			(options
				(clearance outline)
				(anchor circle)
			)
			(primitives
				(gr_poly
					(pts
						(arc
							(start -0.1778 -0.2794)
							(mid -0.249642 -0.249642)
							(end -0.2794 -0.1778)
						)
						(arc
							(start -0.2794 0.1778)
							(mid -0.249642 0.249642)
							(end -0.1778 0.2794)
						)
						(arc
							(start 0.1778 0.2794)
							(mid 0.249642 0.249642)
							(end 0.2794 0.1778)
						)
						(arc
							(start 0.2794 -0.1778)
							(mid 0.249642 -0.249642)
							(end 0.1778 -0.2794)
						)
					)
					(width 0)
					(fill yes)
				)
			)
		)
	)
	(footprint ""
		(layer "F.Cu")
		(at 90.043 -419.735 90)
		(property "Reference" "C132"
			(at 0 0 90)
			(layer "F.SilkS")
			(hide yes)
			(effects
				(font
					(size 1.27 1.27)
				)
			)
		)
		(property "Value" "SC1KP50V2KX-1GP"
			(at 1.1811 -2.7051 90)
			(unlocked yes)
			(layer "F.Fab")
			(hide yes)
			(effects
				(font
					(size 1.016 1.016)
					(thickness 0.1524)
				)
			)
		)
		(property "Device Type" "C402H22"
			(at 1.1811 -4.2291 90)
			(unlocked yes)
			(layer "F.Fab")
			(hide yes)
			(effects
				(font
					(size 1.016 1.016)
					(thickness 0.1524)
				)
			)
		)
		(duplicate_pad_numbers_are_jumpers no)
		(fp_rect
			(start -0.4318 0.9525)
			(end 0.4318 -0.9525)
			(stroke
				(width 0)
				(type default)
			)
			(fill no)
			(layer "F.CrtYd")
		)
		(fp_rect
			(start -0.4318 0.9525)
			(end 0.4318 -0.9525)
			(stroke
				(width 0)
				(type default)
			)
			(fill no)
			(layer "F.Fab")
		)
		(pad "1" smd custom
			(at 0 -0.4445 90)
			(size 0.1524 0.1524)
			(layers "F.Cu" "F.Mask" "F.Paste")
			(net "SSD10_CLK0_OE_R_N")
			(options
				(clearance outline)
				(anchor circle)
			)
			(primitives
				(gr_poly
					(pts
						(arc
							(start 0.3048 -0.2032)
							(mid 0.275042 -0.275042)
							(end 0.2032 -0.3048)
						)
						(arc
							(start -0.2032 -0.3048)
							(mid -0.275042 -0.275042)
							(end -0.3048 -0.2032)
						)
						(arc
							(start -0.3048 0.2032)
							(mid -0.275042 0.275042)
							(end -0.2032 0.3048)
						)
						(arc
							(start 0.2032 0.3048)
							(mid 0.275042 0.275042)
							(end 0.3048 0.2032)
						)
					)
					(width 0)
					(fill yes)
				)
			)
		)
		(pad "2" smd custom
			(at 0 0.4445 90)
			(size 0.1524 0.1524)
			(layers "F.Cu" "F.Mask" "F.Paste")
			(net "GND")
			(options
				(clearance outline)
				(anchor circle)
			)
			(primitives
				(gr_poly
					(pts
						(arc
							(start 0.3048 -0.2032)
							(mid 0.275042 -0.275042)
							(end 0.2032 -0.3048)
						)
						(arc
							(start -0.2032 -0.3048)
							(mid -0.275042 -0.275042)
							(end -0.3048 -0.2032)
						)
						(arc
							(start -0.3048 0.2032)
							(mid -0.275042 0.275042)
							(end -0.2032 0.3048)
						)
						(arc
							(start 0.2032 0.3048)
							(mid 0.275042 0.275042)
							(end 0.3048 0.2032)
						)
					)
					(width 0)
					(fill yes)
				)
			)
		)
	)
	(footprint ""
		(layer "F.Cu")
		(at 82.0674 -148.1836 90)
		(property "Reference" "C9322"
			(at 0 0 90)
			(layer "F.SilkS")
			(hide yes)
			(effects
				(font
					(size 1.27 1.27)
				)
			)
		)
		(property "Value" "SCD1U25V3KX-GP"
			(at 0 -2.8194 90)
			(unlocked yes)
			(layer "F.Fab")
			(hide yes)
			(effects
				(font
					(size 1.016 1.016)
					(thickness 0.1524)
				)
			)
		)
		(property "Device Type" "C603H36"
			(at 0 -4.3434 90)
			(unlocked yes)
			(layer "F.Fab")
			(hide yes)
			(effects
				(font
					(size 1.016 1.016)
					(thickness 0.1524)
				)
			)
		)
		(duplicate_pad_numbers_are_jumpers no)
		(fp_line
			(start 0.508 0)
			(end -0.508 0)
			(stroke
				(width 0.2032)
				(type default)
			)
			(layer "F.SilkS")
		)
		(fp_rect
			(start -0.5842 1.3335)
			(end 0.5842 -1.3335)
			(stroke
				(width 0)
				(type default)
			)
			(fill no)
			(layer "F.CrtYd")
		)
		(fp_rect
			(start -0.5842 1.3335)
			(end 0.5842 -1.3335)
			(stroke
				(width 0)
				(type default)
			)
			(fill no)
			(layer "F.Fab")
		)
		(pad "1" smd custom
			(at 0 -0.762 90)
			(size 0.2159 0.2159)
			(layers "F.Cu" "F.Mask" "F.Paste")
			(net "P3V3")
			(options
				(clearance outline)
				(anchor circle)
			)
			(primitives
				(gr_poly
					(pts
						(arc
							(start -0.3302 -0.4318)
							(mid -0.402042 -0.402042)
							(end -0.4318 -0.3302)
						)
						(arc
							(start -0.4318 0.3302)
							(mid -0.402042 0.402042)
							(end -0.3302 0.4318)
						)
						(arc
							(start 0.3302 0.4318)
							(mid 0.402042 0.402042)
							(end 0.4318 0.3302)
						)
						(arc
							(start 0.4318 -0.3302)
							(mid 0.402042 -0.402042)
							(end 0.3302 -0.4318)
						)
					)
					(width 0)
					(fill yes)
				)
			)
		)
		(pad "2" smd custom
			(at 0 0.762 90)
			(size 0.2159 0.2159)
			(layers "F.Cu" "F.Mask" "F.Paste")
			(net "GND")
			(options
				(clearance outline)
				(anchor circle)
			)
			(primitives
				(gr_poly
					(pts
						(arc
							(start -0.3302 -0.4318)
							(mid -0.402042 -0.402042)
							(end -0.4318 -0.3302)
						)
						(arc
							(start -0.4318 0.3302)
							(mid -0.402042 0.402042)
							(end -0.3302 0.4318)
						)
						(arc
							(start 0.3302 0.4318)
							(mid 0.402042 0.402042)
							(end 0.4318 0.3302)
						)
						(arc
							(start 0.4318 -0.3302)
							(mid 0.402042 -0.402042)
							(end 0.3302 -0.4318)
						)
					)
					(width 0)
					(fill yes)
				)
			)
		)
	)
	(footprint ""
		(layer "F.Cu")
		(at 91.186 -29.718 -90)
		(property "Reference" "C363"
			(at 0 0 270)
			(layer "F.SilkS")
			(hide yes)
			(effects
				(font
					(size 1.27 1.27)
				)
			)
		)
		(property "Value" "SC1U10V2KX-7-GP"
			(at 1.1811 -2.7051 270)
			(unlocked yes)
			(layer "F.Fab")
			(hide yes)
			(effects
				(font
					(size 1.016 1.016)
					(thickness 0.1524)
				)
			)
		)
		(property "Device Type" "C402H22"
			(at 1.1811 -4.2291 270)
			(unlocked yes)
			(layer "F.Fab")
			(hide yes)
			(effects
				(font
					(size 1.016 1.016)
					(thickness 0.1524)
				)
			)
		)
		(duplicate_pad_numbers_are_jumpers no)
		(fp_rect
			(start -0.4318 0.9525)
			(end 0.4318 -0.9525)
			(stroke
				(width 0)
				(type default)
			)
			(fill no)
			(layer "F.CrtYd")
		)
		(fp_rect
			(start -0.4318 0.9525)
			(end 0.4318 -0.9525)
			(stroke
				(width 0)
				(type default)
			)
			(fill no)
			(layer "F.Fab")
		)
		(pad "1" smd custom
			(at 0 -0.4445 270)
			(size 0.1524 0.1524)
			(layers "F.Cu" "F.Mask" "F.Paste")
			(net "P3V3")
			(options
				(clearance outline)
				(anchor circle)
			)
			(primitives
				(gr_poly
					(pts
						(arc
							(start 0.3048 -0.2032)
							(mid 0.275042 -0.275042)
							(end 0.2032 -0.3048)
						)
						(arc
							(start -0.2032 -0.3048)
							(mid -0.275042 -0.275042)
							(end -0.3048 -0.2032)
						)
						(arc
							(start -0.3048 0.2032)
							(mid -0.275042 0.275042)
							(end -0.2032 0.3048)
						)
						(arc
							(start 0.2032 0.3048)
							(mid 0.275042 0.275042)
							(end 0.3048 0.2032)
						)
					)
					(width 0)
					(fill yes)
				)
			)
		)
		(pad "2" smd custom
			(at 0 0.4445 270)
			(size 0.1524 0.1524)
			(layers "F.Cu" "F.Mask" "F.Paste")
			(net "GND")
			(options
				(clearance outline)
				(anchor circle)
			)
			(primitives
				(gr_poly
					(pts
						(arc
							(start 0.3048 -0.2032)
							(mid 0.275042 -0.275042)
							(end 0.2032 -0.3048)
						)
						(arc
							(start -0.2032 -0.3048)
							(mid -0.275042 -0.275042)
							(end -0.3048 -0.2032)
						)
						(arc
							(start -0.3048 0.2032)
							(mid -0.275042 0.275042)
							(end -0.2032 0.3048)
						)
						(arc
							(start 0.2032 0.3048)
							(mid 0.275042 0.275042)
							(end 0.3048 0.2032)
						)
					)
					(width 0)
					(fill yes)
				)
			)
		)
	)
	(footprint ""
		(layer "F.Cu")
		(at 77.343 -209.3722)
		(property "Reference" "R9971"
			(at 0 0 0)
			(layer "F.SilkS")
			(hide yes)
			(effects
				(font
					(size 1.27 1.27)
				)
			)
		)
		(property "Value" "56R2F-1-GP"
			(at 0.064008 -3.993896 0)
			(unlocked yes)
			(layer "F.Fab")
			(hide yes)
			(effects
				(font
					(size 1.016 1.016)
					(thickness 0.1524)
				)
			)
		)
		(property "Device Type" "R402H16"
			(at 0.064008 -5.517896 0)
			(unlocked yes)
			(layer "F.Fab")
			(hide yes)
			(effects
				(font
					(size 1.016 1.016)
					(thickness 0.1524)
				)
			)
		)
		(duplicate_pad_numbers_are_jumpers no)
		(fp_line
			(start -0.508 -0.9398)
			(end -0.508 0.9398)
			(stroke
				(width 0.1524)
				(type default)
			)
			(layer "F.SilkS")
		)
		(fp_line
			(start 0.508 -0.9398)
			(end -0.508 -0.9398)
			(stroke
				(width 0.1524)
				(type default)
			)
			(layer "F.SilkS")
		)
		(fp_rect
			(start -0.508 0.9398)
			(end 0.508 -0.9398)
			(stroke
				(width 0)
				(type default)
			)
			(fill no)
			(layer "F.CrtYd")
		)
		(fp_rect
			(start -0.508 0.9398)
			(end 0.508 -0.9398)
			(stroke
				(width 0)
				(type default)
			)
			(fill no)
			(layer "F.Fab")
		)
		(pad "1" smd custom
			(at 0 -0.4445)
			(size 0.1397 0.1397)
			(layers "F.Cu" "F.Mask" "F.Paste")
			(net "PE_100M_CLK2_N")
			(options
				(clearance outline)
				(anchor circle)
			)
			(primitives
				(gr_poly
					(pts
						(arc
							(start -0.1778 -0.2794)
							(mid -0.249642 -0.249642)
							(end -0.2794 -0.1778)
						)
						(arc
							(start -0.2794 0.1778)
							(mid -0.249642 0.249642)
							(end -0.1778 0.2794)
						)
						(arc
							(start 0.1778 0.2794)
							(mid 0.249642 0.249642)
							(end 0.2794 0.1778)
						)
						(arc
							(start 0.2794 -0.1778)
							(mid 0.249642 -0.249642)
							(end 0.1778 -0.2794)
						)
					)
					(width 0)
					(fill yes)
				)
			)
		)
		(pad "2" smd custom
			(at 0 0.4445)
			(size 0.1397 0.1397)
			(layers "F.Cu" "F.Mask" "F.Paste")
			(net "GND")
			(options
				(clearance outline)
				(anchor circle)
			)
			(primitives
				(gr_poly
					(pts
						(arc
							(start -0.1778 -0.2794)
							(mid -0.249642 -0.249642)
							(end -0.2794 -0.1778)
						)
						(arc
							(start -0.2794 0.1778)
							(mid -0.249642 0.249642)
							(end -0.1778 0.2794)
						)
						(arc
							(start 0.1778 0.2794)
							(mid 0.249642 0.249642)
							(end 0.2794 0.1778)
						)
						(arc
							(start 0.2794 -0.1778)
							(mid 0.249642 -0.249642)
							(end 0.1778 -0.2794)
						)
					)
					(width 0)
					(fill yes)
				)
			)
		)
	)
	(footprint ""
		(layer "F.Cu")
		(at 96.774 -116.586 90)
		(property "Reference" "R9505"
			(at 0 0 90)
			(layer "F.SilkS")
			(hide yes)
			(effects
				(font
					(size 1.27 1.27)
				)
			)
		)
		(property "Value" "4K7R2J-2-GP"
			(at 0.064008 -3.993896 90)
			(unlocked yes)
			(layer "F.Fab")
			(hide yes)
			(effects
				(font
					(size 1.016 1.016)
					(thickness 0.1524)
				)
			)
		)
		(property "Device Type" "R402H16"
			(at 0.064008 -5.517896 90)
			(unlocked yes)
			(layer "F.Fab")
			(hide yes)
			(effects
				(font
					(size 1.016 1.016)
					(thickness 0.1524)
				)
			)
		)
		(duplicate_pad_numbers_are_jumpers no)
		(fp_line
			(start 0.508 -0.9398)
			(end -0.508 -0.9398)
			(stroke
				(width 0.1524)
				(type default)
			)
			(layer "F.SilkS")
		)
		(fp_line
			(start -0.508 -0.9398)
			(end -0.508 0.9398)
			(stroke
				(width 0.1524)
				(type default)
			)
			(layer "F.SilkS")
		)
		(fp_rect
			(start -0.508 0.9398)
			(end 0.508 -0.9398)
			(stroke
				(width 0)
				(type default)
			)
			(fill no)
			(layer "F.CrtYd")
		)
		(fp_rect
			(start -0.508 0.9398)
			(end 0.508 -0.9398)
			(stroke
				(width 0)
				(type default)
			)
			(fill no)
			(layer "F.Fab")
		)
		(pad "1" smd custom
			(at 0 -0.4445 90)
			(size 0.1397 0.1397)
			(layers "F.Cu" "F.Mask" "F.Paste")
			(net "P3V3")
			(options
				(clearance outline)
				(anchor circle)
			)
			(primitives
				(gr_poly
					(pts
						(arc
							(start -0.1778 -0.2794)
							(mid -0.249642 -0.249642)
							(end -0.2794 -0.1778)
						)
						(arc
							(start -0.2794 0.1778)
							(mid -0.249642 0.249642)
							(end -0.1778 0.2794)
						)
						(arc
							(start 0.1778 0.2794)
							(mid 0.249642 0.249642)
							(end 0.2794 0.1778)
						)
						(arc
							(start 0.2794 -0.1778)
							(mid 0.249642 -0.249642)
							(end 0.1778 -0.2794)
						)
					)
					(width 0)
					(fill yes)
				)
			)
		)
		(pad "2" smd custom
			(at 0 0.4445 90)
			(size 0.1397 0.1397)
			(layers "F.Cu" "F.Mask" "F.Paste")
			(net "SSD8_CLK0_OE_N")
			(options
				(clearance outline)
				(anchor circle)
			)
			(primitives
				(gr_poly
					(pts
						(arc
							(start -0.1778 -0.2794)
							(mid -0.249642 -0.249642)
							(end -0.2794 -0.1778)
						)
						(arc
							(start -0.2794 0.1778)
							(mid -0.249642 0.249642)
							(end -0.1778 0.2794)
						)
						(arc
							(start 0.1778 0.2794)
							(mid 0.249642 0.249642)
							(end 0.2794 0.1778)
						)
						(arc
							(start 0.2794 -0.1778)
							(mid 0.249642 -0.249642)
							(end 0.1778 -0.2794)
						)
					)
					(width 0)
					(fill yes)
				)
			)
		)
	)
	(footprint ""
		(layer "F.Cu")
		(at 35.56 -308.0004 90)
		(property "Reference" "Q82"
			(at 0 0 90)
			(layer "F.SilkS")
			(hide yes)
			(effects
				(font
					(size 1.27 1.27)
				)
			)
		)
		(property "Value" "2N7002A-7-GP"
			(at 0.127 -8.9662 90)
			(unlocked yes)
			(layer "F.Fab")
			(hide yes)
			(effects
				(font
					(size 1.016 1.016)
					(thickness 0.1524)
				)
			)
		)
		(property "Device Type" "SOT23DGS2D4H48"
			(at 0.127 -10.4902 90)
			(unlocked yes)
			(layer "F.Fab")
			(hide yes)
			(effects
				(font
					(size 1.016 1.016)
					(thickness 0.1524)
				)
			)
		)
		(duplicate_pad_numbers_are_jumpers no)
		(fp_line
			(start 1.651 -1.778)
			(end -1.651 -1.778)
			(stroke
				(width 0.1524)
				(type default)
			)
			(layer "F.SilkS")
		)
		(fp_line
			(start -1.651 -1.778)
			(end -1.651 1.778)
			(stroke
				(width 0.1524)
				(type default)
			)
			(layer "F.SilkS")
		)
		(fp_line
			(start 1.651 1.778)
			(end 1.651 -1.778)
			(stroke
				(width 0.1524)
				(type default)
			)
			(layer "F.SilkS")
		)
		(fp_line
			(start -1.651 1.778)
			(end 1.651 1.778)
			(stroke
				(width 0.1524)
				(type default)
			)
			(layer "F.SilkS")
		)
		(fp_poly
			(pts
				(xy -1.778 1.8796) (xy -1.778 -1.8796) (xy 1.778 -1.8796) (xy 1.778 1.8796)
			)
			(stroke
				(width 0)
				(type default)
			)
			(fill no)
			(layer "F.CrtYd")
		)
		(fp_poly
			(pts
				(xy -1.778 1.8796) (xy -1.778 -1.8796) (xy 1.778 -1.8796) (xy 1.778 1.8796)
			)
			(stroke
				(width 0)
				(type default)
			)
			(fill no)
			(layer "F.Fab")
		)
		(pad "D" smd custom
			(at 0 -0.9525 90)
			(size 0.1905 0.1905)
			(layers "F.Cu" "F.Mask" "F.Paste")
			(net "P12V_MOST11_GATE")
			(options
				(clearance outline)
				(anchor circle)
			)
			(primitives
				(gr_poly
					(pts
						(arc
							(start -0.1778 0.5715)
							(mid -0.321484 0.511984)
							(end -0.381 0.3683)
						)
						(arc
							(start -0.381 -0.3683)
							(mid -0.321484 -0.511984)
							(end -0.1778 -0.5715)
						)
						(arc
							(start 0.1778 -0.5715)
							(mid 0.321484 -0.511984)
							(end 0.381 -0.3683)
						)
						(arc
							(start 0.381 0.3683)
							(mid 0.321484 0.511984)
							(end 0.1778 0.5715)
						)
					)
					(width 0)
					(fill yes)
				)
			)
		)
		(pad "G" smd custom
			(at -0.98425 0.9525 90)
			(size 0.1905 0.1905)
			(layers "F.Cu" "F.Mask" "F.Paste")
			(net "SSD11_PWREN_R")
			(options
				(clearance outline)
				(anchor circle)
			)
			(primitives
				(gr_poly
					(pts
						(arc
							(start -0.1778 0.5715)
							(mid -0.321484 0.511984)
							(end -0.381 0.3683)
						)
						(arc
							(start -0.381 -0.3683)
							(mid -0.321484 -0.511984)
							(end -0.1778 -0.5715)
						)
						(arc
							(start 0.1778 -0.5715)
							(mid 0.321484 -0.511984)
							(end 0.381 -0.3683)
						)
						(arc
							(start 0.381 0.3683)
							(mid 0.321484 0.511984)
							(end 0.1778 0.5715)
						)
					)
					(width 0)
					(fill yes)
				)
			)
		)
		(pad "S" smd custom
			(at 0.98425 0.9525 90)
			(size 0.1905 0.1905)
			(layers "F.Cu" "F.Mask" "F.Paste")
			(net "GND")
			(options
				(clearance outline)
				(anchor circle)
			)
			(primitives
				(gr_poly
					(pts
						(arc
							(start -0.1778 0.5715)
							(mid -0.321484 0.511984)
							(end -0.381 0.3683)
						)
						(arc
							(start -0.381 -0.3683)
							(mid -0.321484 -0.511984)
							(end -0.1778 -0.5715)
						)
						(arc
							(start 0.1778 -0.5715)
							(mid 0.321484 -0.511984)
							(end 0.381 -0.3683)
						)
						(arc
							(start 0.381 0.3683)
							(mid 0.321484 0.511984)
							(end 0.1778 0.5715)
						)
					)
					(width 0)
					(fill yes)
				)
			)
		)
	)
	(footprint ""
		(layer "F.Cu")
		(at 26.16835 -402.08835 180)
		(property "Reference" "R9820"
			(at 0 0 180)
			(layer "F.SilkS")
			(hide yes)
			(effects
				(font
					(size 1.27 1.27)
				)
			)
		)
		(property "Value" "47KR2J-2-GP"
			(at 0.064008 -3.993896 180)
			(unlocked yes)
			(layer "F.Fab")
			(hide yes)
			(effects
				(font
					(size 1.016 1.016)
					(thickness 0.1524)
				)
			)
		)
		(property "Device Type" "R402H16"
			(at 0.064008 -5.517896 180)
			(unlocked yes)
			(layer "F.Fab")
			(hide yes)
			(effects
				(font
					(size 1.016 1.016)
					(thickness 0.1524)
				)
			)
		)
		(duplicate_pad_numbers_are_jumpers no)
		(fp_line
			(start 0.508 -0.9398)
			(end -0.508 -0.9398)
			(stroke
				(width 0.1524)
				(type default)
			)
			(layer "F.SilkS")
		)
		(fp_line
			(start -0.508 -0.9398)
			(end -0.508 0.9398)
			(stroke
				(width 0.1524)
				(type default)
			)
			(layer "F.SilkS")
		)
		(fp_rect
			(start -0.508 0.9398)
			(end 0.508 -0.9398)
			(stroke
				(width 0)
				(type default)
			)
			(fill no)
			(layer "F.CrtYd")
		)
		(fp_rect
			(start -0.508 0.9398)
			(end 0.508 -0.9398)
			(stroke
				(width 0)
				(type default)
			)
			(fill no)
			(layer "F.Fab")
		)
		(pad "1" smd custom
			(at 0 -0.4445 180)
			(size 0.1397 0.1397)
			(layers "F.Cu" "F.Mask" "F.Paste")
			(net "P12V")
			(options
				(clearance outline)
				(anchor circle)
			)
			(primitives
				(gr_poly
					(pts
						(arc
							(start -0.1778 -0.2794)
							(mid -0.249642 -0.249642)
							(end -0.2794 -0.1778)
						)
						(arc
							(start -0.2794 0.1778)
							(mid -0.249642 0.249642)
							(end -0.1778 0.2794)
						)
						(arc
							(start 0.1778 0.2794)
							(mid 0.249642 0.249642)
							(end 0.2794 0.1778)
						)
						(arc
							(start 0.2794 -0.1778)
							(mid 0.249642 -0.249642)
							(end 0.1778 -0.2794)
						)
					)
					(width 0)
					(fill yes)
				)
			)
		)
		(pad "2" smd custom
			(at 0 0.4445 180)
			(size 0.1397 0.1397)
			(layers "F.Cu" "F.Mask" "F.Paste")
			(net "P12V_MOST6_GATE")
			(options
				(clearance outline)
				(anchor circle)
			)
			(primitives
				(gr_poly
					(pts
						(arc
							(start -0.1778 -0.2794)
							(mid -0.249642 -0.249642)
							(end -0.2794 -0.1778)
						)
						(arc
							(start -0.2794 0.1778)
							(mid -0.249642 0.249642)
							(end -0.1778 0.2794)
						)
						(arc
							(start 0.1778 0.2794)
							(mid 0.249642 0.249642)
							(end 0.2794 0.1778)
						)
						(arc
							(start 0.2794 -0.1778)
							(mid 0.249642 -0.249642)
							(end 0.1778 -0.2794)
						)
					)
					(width 0)
					(fill yes)
				)
			)
		)
	)
	(footprint ""
		(layer "F.Cu")
		(at 224.964752 -347.9038 90)
		(property "Reference" "R9913"
			(at 0 0 90)
			(layer "F.SilkS")
			(hide yes)
			(effects
				(font
					(size 1.27 1.27)
				)
			)
		)
		(property "Value" "47KR2J-2-GP"
			(at 0.064008 -3.993896 90)
			(unlocked yes)
			(layer "F.Fab")
			(hide yes)
			(effects
				(font
					(size 1.016 1.016)
					(thickness 0.1524)
				)
			)
		)
		(property "Device Type" "R402H16"
			(at 0.064008 -5.517896 90)
			(unlocked yes)
			(layer "F.Fab")
			(hide yes)
			(effects
				(font
					(size 1.016 1.016)
					(thickness 0.1524)
				)
			)
		)
		(duplicate_pad_numbers_are_jumpers no)
		(fp_line
			(start 0.508 -0.9398)
			(end -0.508 -0.9398)
			(stroke
				(width 0.1524)
				(type default)
			)
			(layer "F.SilkS")
		)
		(fp_line
			(start -0.508 -0.9398)
			(end -0.508 0.9398)
			(stroke
				(width 0.1524)
				(type default)
			)
			(layer "F.SilkS")
		)
		(fp_rect
			(start -0.508 0.9398)
			(end 0.508 -0.9398)
			(stroke
				(width 0)
				(type default)
			)
			(fill no)
			(layer "F.CrtYd")
		)
		(fp_rect
			(start -0.508 0.9398)
			(end 0.508 -0.9398)
			(stroke
				(width 0)
				(type default)
			)
			(fill no)
			(layer "F.Fab")
		)
		(pad "1" smd custom
			(at 0 -0.4445 90)
			(size 0.1397 0.1397)
			(layers "F.Cu" "F.Mask" "F.Paste")
			(net "P3V3")
			(options
				(clearance outline)
				(anchor circle)
			)
			(primitives
				(gr_poly
					(pts
						(arc
							(start -0.1778 -0.2794)
							(mid -0.249642 -0.249642)
							(end -0.2794 -0.1778)
						)
						(arc
							(start -0.2794 0.1778)
							(mid -0.249642 0.249642)
							(end -0.1778 0.2794)
						)
						(arc
							(start 0.1778 0.2794)
							(mid 0.249642 0.249642)
							(end 0.2794 0.1778)
						)
						(arc
							(start 0.2794 -0.1778)
							(mid 0.249642 -0.249642)
							(end 0.1778 -0.2794)
						)
					)
					(width 0)
					(fill yes)
				)
			)
		)
		(pad "2" smd custom
			(at 0 0.4445 90)
			(size 0.1397 0.1397)
			(layers "F.Cu" "F.Mask" "F.Paste")
			(net "ATTN_LED_DR1_N")
			(options
				(clearance outline)
				(anchor circle)
			)
			(primitives
				(gr_poly
					(pts
						(arc
							(start -0.1778 -0.2794)
							(mid -0.249642 -0.249642)
							(end -0.2794 -0.1778)
						)
						(arc
							(start -0.2794 0.1778)
							(mid -0.249642 0.249642)
							(end -0.1778 0.2794)
						)
						(arc
							(start 0.1778 0.2794)
							(mid 0.249642 0.249642)
							(end 0.2794 0.1778)
						)
						(arc
							(start 0.2794 -0.1778)
							(mid 0.249642 -0.249642)
							(end 0.1778 -0.2794)
						)
					)
					(width 0)
					(fill yes)
				)
			)
		)
	)
	(footprint ""
		(layer "F.Cu")
		(at 69.215 -435.864 180)
		(property "Reference" "PR9058"
			(at 0 0 180)
			(layer "F.SilkS")
			(hide yes)
			(effects
				(font
					(size 1.27 1.27)
				)
			)
		)
		(property "Value" "0R2J-2-GP"
			(at 0.064008 -3.993896 180)
			(unlocked yes)
			(layer "F.Fab")
			(hide yes)
			(effects
				(font
					(size 1.016 1.016)
					(thickness 0.1524)
				)
			)
		)
		(property "Device Type" "R402H16"
			(at 0.064008 -5.517896 180)
			(unlocked yes)
			(layer "F.Fab")
			(hide yes)
			(effects
				(font
					(size 1.016 1.016)
					(thickness 0.1524)
				)
			)
		)
		(duplicate_pad_numbers_are_jumpers no)
		(fp_line
			(start 0.508 -0.9398)
			(end -0.508 -0.9398)
			(stroke
				(width 0.1524)
				(type default)
			)
			(layer "F.SilkS")
		)
		(fp_line
			(start -0.508 -0.9398)
			(end -0.508 0.9398)
			(stroke
				(width 0.1524)
				(type default)
			)
			(layer "F.SilkS")
		)
		(fp_rect
			(start -0.508 0.9398)
			(end 0.508 -0.9398)
			(stroke
				(width 0)
				(type default)
			)
			(fill no)
			(layer "F.CrtYd")
		)
		(fp_rect
			(start -0.508 0.9398)
			(end 0.508 -0.9398)
			(stroke
				(width 0)
				(type default)
			)
			(fill no)
			(layer "F.Fab")
		)
		(pad "1" smd custom
			(at 0 -0.4445 180)
			(size 0.1397 0.1397)
			(layers "F.Cu" "F.Mask" "F.Paste")
			(net "SAS_I2C_B_BUF_SDA_R")
			(options
				(clearance outline)
				(anchor circle)
			)
			(primitives
				(gr_poly
					(pts
						(arc
							(start -0.1778 -0.2794)
							(mid -0.249642 -0.249642)
							(end -0.2794 -0.1778)
						)
						(arc
							(start -0.2794 0.1778)
							(mid -0.249642 0.249642)
							(end -0.1778 0.2794)
						)
						(arc
							(start 0.1778 0.2794)
							(mid 0.249642 0.249642)
							(end 0.2794 0.1778)
						)
						(arc
							(start 0.2794 -0.1778)
							(mid 0.249642 -0.249642)
							(end 0.1778 -0.2794)
						)
					)
					(width 0)
					(fill yes)
				)
			)
		)
		(pad "2" smd custom
			(at 0 0.4445 180)
			(size 0.1397 0.1397)
			(layers "F.Cu" "F.Mask" "F.Paste")
			(net "I2C_B_SDA")
			(options
				(clearance outline)
				(anchor circle)
			)
			(primitives
				(gr_poly
					(pts
						(arc
							(start -0.1778 -0.2794)
							(mid -0.249642 -0.249642)
							(end -0.2794 -0.1778)
						)
						(arc
							(start -0.2794 0.1778)
							(mid -0.249642 0.249642)
							(end -0.1778 0.2794)
						)
						(arc
							(start 0.1778 0.2794)
							(mid 0.249642 0.249642)
							(end 0.2794 0.1778)
						)
						(arc
							(start 0.2794 -0.1778)
							(mid 0.249642 -0.249642)
							(end 0.1778 -0.2794)
						)
					)
					(width 0)
					(fill yes)
				)
			)
		)
	)
	(footprint ""
		(layer "F.Cu")
		(at 78.994 -309.245 -90)
		(property "Reference" "C8914"
			(at 0 0 270)
			(layer "F.SilkS")
			(hide yes)
			(effects
				(font
					(size 1.27 1.27)
				)
			)
		)
		(property "Value" "SC10U25V3MX-GP"
			(at 0 -2.8194 270)
			(unlocked yes)
			(layer "F.Fab")
			(hide yes)
			(effects
				(font
					(size 1.016 1.016)
					(thickness 0.1524)
				)
			)
		)
		(property "Device Type" "C603H40"
			(at 0 -4.3434 270)
			(unlocked yes)
			(layer "F.Fab")
			(hide yes)
			(effects
				(font
					(size 1.016 1.016)
					(thickness 0.1524)
				)
			)
		)
		(duplicate_pad_numbers_are_jumpers no)
		(fp_line
			(start 0.508 0)
			(end -0.508 0)
			(stroke
				(width 0.2032)
				(type default)
			)
			(layer "F.SilkS")
		)
		(fp_rect
			(start -0.5842 1.3335)
			(end 0.5842 -1.3335)
			(stroke
				(width 0)
				(type default)
			)
			(fill no)
			(layer "F.CrtYd")
		)
		(fp_rect
			(start -0.5842 1.3335)
			(end 0.5842 -1.3335)
			(stroke
				(width 0)
				(type default)
			)
			(fill no)
			(layer "F.Fab")
		)
		(pad "1" smd custom
			(at 0 -0.762 270)
			(size 0.2159 0.2159)
			(layers "F.Cu" "F.Mask" "F.Paste")
			(net "VDD_DIFF_2")
			(options
				(clearance outline)
				(anchor circle)
			)
			(primitives
				(gr_poly
					(pts
						(arc
							(start -0.3302 -0.4318)
							(mid -0.402042 -0.402042)
							(end -0.4318 -0.3302)
						)
						(arc
							(start -0.4318 0.3302)
							(mid -0.402042 0.402042)
							(end -0.3302 0.4318)
						)
						(arc
							(start 0.3302 0.4318)
							(mid 0.402042 0.402042)
							(end 0.4318 0.3302)
						)
						(arc
							(start 0.4318 -0.3302)
							(mid 0.402042 -0.402042)
							(end 0.3302 -0.4318)
						)
					)
					(width 0)
					(fill yes)
				)
			)
		)
		(pad "2" smd custom
			(at 0 0.762 270)
			(size 0.2159 0.2159)
			(layers "F.Cu" "F.Mask" "F.Paste")
			(net "GND")
			(options
				(clearance outline)
				(anchor circle)
			)
			(primitives
				(gr_poly
					(pts
						(arc
							(start -0.3302 -0.4318)
							(mid -0.402042 -0.402042)
							(end -0.4318 -0.3302)
						)
						(arc
							(start -0.4318 0.3302)
							(mid -0.402042 0.402042)
							(end -0.3302 0.4318)
						)
						(arc
							(start 0.3302 0.4318)
							(mid 0.402042 0.402042)
							(end 0.4318 0.3302)
						)
						(arc
							(start 0.4318 -0.3302)
							(mid 0.402042 -0.402042)
							(end 0.3302 -0.4318)
						)
					)
					(width 0)
					(fill yes)
				)
			)
		)
	)
	(footprint ""
		(layer "F.Cu")
		(at 99.314 -313.817 180)
		(property "Reference" "R9101"
			(at 0 0 180)
			(layer "F.SilkS")
			(hide yes)
			(effects
				(font
					(size 1.27 1.27)
				)
			)
		)
		(property "Value" "27R2F-GP"
			(at 0.064008 -3.993896 180)
			(unlocked yes)
			(layer "F.Fab")
			(hide yes)
			(effects
				(font
					(size 1.016 1.016)
					(thickness 0.1524)
				)
			)
		)
		(property "Device Type" "R402H16"
			(at 0.064008 -5.517896 180)
			(unlocked yes)
			(layer "F.Fab")
			(hide yes)
			(effects
				(font
					(size 1.016 1.016)
					(thickness 0.1524)
				)
			)
		)
		(duplicate_pad_numbers_are_jumpers no)
		(fp_line
			(start 0.508 -0.9398)
			(end -0.508 -0.9398)
			(stroke
				(width 0.1524)
				(type default)
			)
			(layer "F.SilkS")
		)
		(fp_line
			(start -0.508 -0.9398)
			(end -0.508 0.9398)
			(stroke
				(width 0.1524)
				(type default)
			)
			(layer "F.SilkS")
		)
		(fp_rect
			(start -0.508 0.9398)
			(end 0.508 -0.9398)
			(stroke
				(width 0)
				(type default)
			)
			(fill no)
			(layer "F.CrtYd")
		)
		(fp_rect
			(start -0.508 0.9398)
			(end 0.508 -0.9398)
			(stroke
				(width 0)
				(type default)
			)
			(fill no)
			(layer "F.Fab")
		)
		(pad "1" smd custom
			(at 0 -0.4445 180)
			(size 0.1397 0.1397)
			(layers "F.Cu" "F.Mask" "F.Paste")
			(net "PE_CLK_100M_DR6_2_R_N")
			(options
				(clearance outline)
				(anchor circle)
			)
			(primitives
				(gr_poly
					(pts
						(arc
							(start -0.1778 -0.2794)
							(mid -0.249642 -0.249642)
							(end -0.2794 -0.1778)
						)
						(arc
							(start -0.2794 0.1778)
							(mid -0.249642 0.249642)
							(end -0.1778 0.2794)
						)
						(arc
							(start 0.1778 0.2794)
							(mid 0.249642 0.249642)
							(end 0.2794 0.1778)
						)
						(arc
							(start 0.2794 -0.1778)
							(mid 0.249642 -0.249642)
							(end 0.1778 -0.2794)
						)
					)
					(width 0)
					(fill yes)
				)
			)
		)
		(pad "2" smd custom
			(at 0 0.4445 180)
			(size 0.1397 0.1397)
			(layers "F.Cu" "F.Mask" "F.Paste")
			(net "PE_CLK100M_DR6_2_N")
			(options
				(clearance outline)
				(anchor circle)
			)
			(primitives
				(gr_poly
					(pts
						(arc
							(start -0.1778 -0.2794)
							(mid -0.249642 -0.249642)
							(end -0.2794 -0.1778)
						)
						(arc
							(start -0.2794 0.1778)
							(mid -0.249642 0.249642)
							(end -0.1778 0.2794)
						)
						(arc
							(start 0.1778 0.2794)
							(mid 0.249642 0.249642)
							(end 0.2794 0.1778)
						)
						(arc
							(start 0.2794 -0.1778)
							(mid 0.249642 -0.249642)
							(end 0.1778 -0.2794)
						)
					)
					(width 0)
					(fill yes)
				)
			)
		)
	)
	(footprint ""
		(layer "F.Cu")
		(at 24.003 -380.238 90)
		(property "Reference" "R330"
			(at 0 0 90)
			(layer "F.SilkS")
			(hide yes)
			(effects
				(font
					(size 1.27 1.27)
				)
			)
		)
		(property "Value" "0R2J-2-GP"
			(at 0.064008 -3.993896 90)
			(unlocked yes)
			(layer "F.Fab")
			(hide yes)
			(effects
				(font
					(size 1.016 1.016)
					(thickness 0.1524)
				)
			)
		)
		(property "Device Type" "R402H16"
			(at 0.064008 -5.517896 90)
			(unlocked yes)
			(layer "F.Fab")
			(hide yes)
			(effects
				(font
					(size 1.016 1.016)
					(thickness 0.1524)
				)
			)
		)
		(duplicate_pad_numbers_are_jumpers no)
		(fp_line
			(start 0.508 -0.9398)
			(end -0.508 -0.9398)
			(stroke
				(width 0.1524)
				(type default)
			)
			(layer "F.SilkS")
		)
		(fp_line
			(start -0.508 -0.9398)
			(end -0.508 0.9398)
			(stroke
				(width 0.1524)
				(type default)
			)
			(layer "F.SilkS")
		)
		(fp_rect
			(start -0.508 0.9398)
			(end 0.508 -0.9398)
			(stroke
				(width 0)
				(type default)
			)
			(fill no)
			(layer "F.CrtYd")
		)
		(fp_rect
			(start -0.508 0.9398)
			(end 0.508 -0.9398)
			(stroke
				(width 0)
				(type default)
			)
			(fill no)
			(layer "F.Fab")
		)
		(pad "1" smd custom
			(at 0 -0.4445 90)
			(size 0.1397 0.1397)
			(layers "F.Cu" "F.Mask" "F.Paste")
			(net "I2C_B_SDA")
			(options
				(clearance outline)
				(anchor circle)
			)
			(primitives
				(gr_poly
					(pts
						(arc
							(start -0.1778 -0.2794)
							(mid -0.249642 -0.249642)
							(end -0.2794 -0.1778)
						)
						(arc
							(start -0.2794 0.1778)
							(mid -0.249642 0.249642)
							(end -0.1778 0.2794)
						)
						(arc
							(start 0.1778 0.2794)
							(mid 0.249642 0.249642)
							(end 0.2794 0.1778)
						)
						(arc
							(start 0.2794 -0.1778)
							(mid 0.249642 -0.249642)
							(end 0.1778 -0.2794)
						)
					)
					(width 0)
					(fill yes)
				)
			)
		)
		(pad "2" smd custom
			(at 0 0.4445 90)
			(size 0.1397 0.1397)
			(layers "F.Cu" "F.Mask" "F.Paste")
			(net "TMP4_SDA")
			(options
				(clearance outline)
				(anchor circle)
			)
			(primitives
				(gr_poly
					(pts
						(arc
							(start -0.1778 -0.2794)
							(mid -0.249642 -0.249642)
							(end -0.2794 -0.1778)
						)
						(arc
							(start -0.2794 0.1778)
							(mid -0.249642 0.249642)
							(end -0.1778 0.2794)
						)
						(arc
							(start 0.1778 0.2794)
							(mid 0.249642 0.249642)
							(end 0.2794 0.1778)
						)
						(arc
							(start 0.2794 -0.1778)
							(mid 0.249642 -0.249642)
							(end 0.1778 -0.2794)
						)
					)
					(width 0)
					(fill yes)
				)
			)
		)
	)
	(footprint ""
		(layer "F.Cu")
		(at 217.043 -82.804 -90)
		(property "Reference" "R396"
			(at 0 0 270)
			(layer "F.SilkS")
			(hide yes)
			(effects
				(font
					(size 1.27 1.27)
				)
			)
		)
		(property "Value" "0R2J-2-GP"
			(at 0.064008 -3.993896 270)
			(unlocked yes)
			(layer "F.Fab")
			(hide yes)
			(effects
				(font
					(size 1.016 1.016)
					(thickness 0.1524)
				)
			)
		)
		(property "Device Type" "R402H16"
			(at 0.064008 -5.517896 270)
			(unlocked yes)
			(layer "F.Fab")
			(hide yes)
			(effects
				(font
					(size 1.016 1.016)
					(thickness 0.1524)
				)
			)
		)
		(duplicate_pad_numbers_are_jumpers no)
		(fp_line
			(start -0.508 -0.9398)
			(end -0.508 0.9398)
			(stroke
				(width 0.1524)
				(type default)
			)
			(layer "F.SilkS")
		)
		(fp_line
			(start 0.508 -0.9398)
			(end -0.508 -0.9398)
			(stroke
				(width 0.1524)
				(type default)
			)
			(layer "F.SilkS")
		)
		(fp_rect
			(start -0.508 0.9398)
			(end 0.508 -0.9398)
			(stroke
				(width 0)
				(type default)
			)
			(fill no)
			(layer "F.CrtYd")
		)
		(fp_rect
			(start -0.508 0.9398)
			(end 0.508 -0.9398)
			(stroke
				(width 0)
				(type default)
			)
			(fill no)
			(layer "F.Fab")
		)
		(pad "1" smd custom
			(at 0 -0.4445 270)
			(size 0.1397 0.1397)
			(layers "F.Cu" "F.Mask" "F.Paste")
			(net "SDA_DR4_R")
			(options
				(clearance outline)
				(anchor circle)
			)
			(primitives
				(gr_poly
					(pts
						(arc
							(start -0.1778 -0.2794)
							(mid -0.249642 -0.249642)
							(end -0.2794 -0.1778)
						)
						(arc
							(start -0.2794 0.1778)
							(mid -0.249642 0.249642)
							(end -0.1778 0.2794)
						)
						(arc
							(start 0.1778 0.2794)
							(mid 0.249642 0.249642)
							(end 0.2794 0.1778)
						)
						(arc
							(start 0.2794 -0.1778)
							(mid 0.249642 -0.249642)
							(end 0.1778 -0.2794)
						)
					)
					(width 0)
					(fill yes)
				)
			)
		)
		(pad "2" smd custom
			(at 0 0.4445 270)
			(size 0.1397 0.1397)
			(layers "F.Cu" "F.Mask" "F.Paste")
			(net "SDA_DR4")
			(options
				(clearance outline)
				(anchor circle)
			)
			(primitives
				(gr_poly
					(pts
						(arc
							(start -0.1778 -0.2794)
							(mid -0.249642 -0.249642)
							(end -0.2794 -0.1778)
						)
						(arc
							(start -0.2794 0.1778)
							(mid -0.249642 0.249642)
							(end -0.1778 0.2794)
						)
						(arc
							(start 0.1778 0.2794)
							(mid 0.249642 0.249642)
							(end 0.2794 0.1778)
						)
						(arc
							(start 0.2794 -0.1778)
							(mid 0.249642 -0.249642)
							(end 0.1778 -0.2794)
						)
					)
					(width 0)
					(fill yes)
				)
			)
		)
	)
	(footprint ""
		(layer "F.Cu")
		(at 37.0586 -418.8714 180)
		(property "Reference" "C392"
			(at 0 0 180)
			(layer "F.SilkS")
			(hide yes)
			(effects
				(font
					(size 1.27 1.27)
				)
			)
		)
		(property "Value" "SCD1U25V2KX-2-GP"
			(at 1.1811 -2.7051 180)
			(unlocked yes)
			(layer "F.Fab")
			(hide yes)
			(effects
				(font
					(size 1.016 1.016)
					(thickness 0.1524)
				)
			)
		)
		(property "Device Type" "C402H22"
			(at 1.1811 -4.2291 180)
			(unlocked yes)
			(layer "F.Fab")
			(hide yes)
			(effects
				(font
					(size 1.016 1.016)
					(thickness 0.1524)
				)
			)
		)
		(duplicate_pad_numbers_are_jumpers no)
		(fp_rect
			(start -0.4318 0.9525)
			(end 0.4318 -0.9525)
			(stroke
				(width 0)
				(type default)
			)
			(fill no)
			(layer "F.CrtYd")
		)
		(fp_rect
			(start -0.4318 0.9525)
			(end 0.4318 -0.9525)
			(stroke
				(width 0)
				(type default)
			)
			(fill no)
			(layer "F.Fab")
		)
		(pad "1" smd custom
			(at 0 -0.4445 180)
			(size 0.1524 0.1524)
			(layers "F.Cu" "F.Mask" "F.Paste")
			(net "P12V")
			(options
				(clearance outline)
				(anchor circle)
			)
			(primitives
				(gr_poly
					(pts
						(arc
							(start 0.3048 -0.2032)
							(mid 0.275042 -0.275042)
							(end 0.2032 -0.3048)
						)
						(arc
							(start -0.2032 -0.3048)
							(mid -0.275042 -0.275042)
							(end -0.3048 -0.2032)
						)
						(arc
							(start -0.3048 0.2032)
							(mid -0.275042 0.275042)
							(end -0.2032 0.3048)
						)
						(arc
							(start 0.2032 0.3048)
							(mid 0.275042 0.275042)
							(end 0.3048 0.2032)
						)
					)
					(width 0)
					(fill yes)
				)
			)
		)
		(pad "2" smd custom
			(at 0 0.4445 180)
			(size 0.1524 0.1524)
			(layers "F.Cu" "F.Mask" "F.Paste")
			(net "SW_SSD10_N")
			(options
				(clearance outline)
				(anchor circle)
			)
			(primitives
				(gr_poly
					(pts
						(arc
							(start 0.3048 -0.2032)
							(mid 0.275042 -0.275042)
							(end 0.2032 -0.3048)
						)
						(arc
							(start -0.2032 -0.3048)
							(mid -0.275042 -0.275042)
							(end -0.3048 -0.2032)
						)
						(arc
							(start -0.3048 0.2032)
							(mid -0.275042 0.275042)
							(end -0.2032 0.3048)
						)
						(arc
							(start 0.2032 0.3048)
							(mid 0.275042 0.275042)
							(end 0.3048 0.2032)
						)
					)
					(width 0)
					(fill yes)
				)
			)
		)
	)
	(footprint ""
		(layer "F.Cu")
		(at 208.534 -197.231)
		(property "Reference" "R9763"
			(at 0 0 0)
			(layer "F.SilkS")
			(hide yes)
			(effects
				(font
					(size 1.27 1.27)
				)
			)
		)
		(property "Value" "4K7R2J-2-GP"
			(at 0.064008 -3.993896 0)
			(unlocked yes)
			(layer "F.Fab")
			(hide yes)
			(effects
				(font
					(size 1.016 1.016)
					(thickness 0.1524)
				)
			)
		)
		(property "Device Type" "R402H16"
			(at 0.064008 -5.517896 0)
			(unlocked yes)
			(layer "F.Fab")
			(hide yes)
			(effects
				(font
					(size 1.016 1.016)
					(thickness 0.1524)
				)
			)
		)
		(duplicate_pad_numbers_are_jumpers no)
		(fp_line
			(start -0.508 -0.9398)
			(end -0.508 0.9398)
			(stroke
				(width 0.1524)
				(type default)
			)
			(layer "F.SilkS")
		)
		(fp_line
			(start 0.508 -0.9398)
			(end -0.508 -0.9398)
			(stroke
				(width 0.1524)
				(type default)
			)
			(layer "F.SilkS")
		)
		(fp_rect
			(start -0.508 0.9398)
			(end 0.508 -0.9398)
			(stroke
				(width 0)
				(type default)
			)
			(fill no)
			(layer "F.CrtYd")
		)
		(fp_rect
			(start -0.508 0.9398)
			(end 0.508 -0.9398)
			(stroke
				(width 0)
				(type default)
			)
			(fill no)
			(layer "F.Fab")
		)
		(pad "1" smd custom
			(at 0 -0.4445)
			(size 0.1397 0.1397)
			(layers "F.Cu" "F.Mask" "F.Paste")
			(net "SSD3_PWREN")
			(options
				(clearance outline)
				(anchor circle)
			)
			(primitives
				(gr_poly
					(pts
						(arc
							(start -0.1778 -0.2794)
							(mid -0.249642 -0.249642)
							(end -0.2794 -0.1778)
						)
						(arc
							(start -0.2794 0.1778)
							(mid -0.249642 0.249642)
							(end -0.1778 0.2794)
						)
						(arc
							(start 0.1778 0.2794)
							(mid 0.249642 0.249642)
							(end 0.2794 0.1778)
						)
						(arc
							(start 0.2794 -0.1778)
							(mid 0.249642 -0.249642)
							(end 0.1778 -0.2794)
						)
					)
					(width 0)
					(fill yes)
				)
			)
		)
		(pad "2" smd custom
			(at 0 0.4445)
			(size 0.1397 0.1397)
			(layers "F.Cu" "F.Mask" "F.Paste")
			(net "GND")
			(options
				(clearance outline)
				(anchor circle)
			)
			(primitives
				(gr_poly
					(pts
						(arc
							(start -0.1778 -0.2794)
							(mid -0.249642 -0.249642)
							(end -0.2794 -0.1778)
						)
						(arc
							(start -0.2794 0.1778)
							(mid -0.249642 0.249642)
							(end -0.1778 0.2794)
						)
						(arc
							(start 0.1778 0.2794)
							(mid 0.249642 0.249642)
							(end 0.2794 0.1778)
						)
						(arc
							(start 0.2794 -0.1778)
							(mid 0.249642 -0.249642)
							(end 0.1778 -0.2794)
						)
					)
					(width 0)
					(fill yes)
				)
			)
		)
	)
	(footprint ""
		(layer "F.Cu")
		(at 20.16125 -401.79625 180)
		(property "Reference" "R9516"
			(at 0 0 180)
			(layer "F.SilkS")
			(hide yes)
			(effects
				(font
					(size 1.27 1.27)
				)
			)
		)
		(property "Value" "4K7R2J-2-GP"
			(at 0.064008 -3.993896 180)
			(unlocked yes)
			(layer "F.Fab")
			(hide yes)
			(effects
				(font
					(size 1.016 1.016)
					(thickness 0.1524)
				)
			)
		)
		(property "Device Type" "R402H16"
			(at 0.064008 -5.517896 180)
			(unlocked yes)
			(layer "F.Fab")
			(hide yes)
			(effects
				(font
					(size 1.016 1.016)
					(thickness 0.1524)
				)
			)
		)
		(duplicate_pad_numbers_are_jumpers no)
		(fp_line
			(start 0.508 -0.9398)
			(end -0.508 -0.9398)
			(stroke
				(width 0.1524)
				(type default)
			)
			(layer "F.SilkS")
		)
		(fp_line
			(start -0.508 -0.9398)
			(end -0.508 0.9398)
			(stroke
				(width 0.1524)
				(type default)
			)
			(layer "F.SilkS")
		)
		(fp_rect
			(start -0.508 0.9398)
			(end 0.508 -0.9398)
			(stroke
				(width 0)
				(type default)
			)
			(fill no)
			(layer "F.CrtYd")
		)
		(fp_rect
			(start -0.508 0.9398)
			(end 0.508 -0.9398)
			(stroke
				(width 0)
				(type default)
			)
			(fill no)
			(layer "F.Fab")
		)
		(pad "1" smd custom
			(at 0 -0.4445 180)
			(size 0.1397 0.1397)
			(layers "F.Cu" "F.Mask" "F.Paste")
			(net "P3V3")
			(options
				(clearance outline)
				(anchor circle)
			)
			(primitives
				(gr_poly
					(pts
						(arc
							(start -0.1778 -0.2794)
							(mid -0.249642 -0.249642)
							(end -0.2794 -0.1778)
						)
						(arc
							(start -0.2794 0.1778)
							(mid -0.249642 0.249642)
							(end -0.1778 0.2794)
						)
						(arc
							(start 0.1778 0.2794)
							(mid 0.249642 0.249642)
							(end 0.2794 0.1778)
						)
						(arc
							(start 0.2794 -0.1778)
							(mid 0.249642 -0.249642)
							(end 0.1778 -0.2794)
						)
					)
					(width 0)
					(fill yes)
				)
			)
		)
		(pad "2" smd custom
			(at 0 0.4445 180)
			(size 0.1397 0.1397)
			(layers "F.Cu" "F.Mask" "F.Paste")
			(net "SSD6_PWREN")
			(options
				(clearance outline)
				(anchor circle)
			)
			(primitives
				(gr_poly
					(pts
						(arc
							(start -0.1778 -0.2794)
							(mid -0.249642 -0.249642)
							(end -0.2794 -0.1778)
						)
						(arc
							(start -0.2794 0.1778)
							(mid -0.249642 0.249642)
							(end -0.1778 0.2794)
						)
						(arc
							(start 0.1778 0.2794)
							(mid 0.249642 0.249642)
							(end 0.2794 0.1778)
						)
						(arc
							(start 0.2794 -0.1778)
							(mid 0.249642 -0.249642)
							(end 0.1778 -0.2794)
						)
					)
					(width 0)
					(fill yes)
				)
			)
		)
	)
	(footprint ""
		(layer "F.Cu")
		(at 25.7302 -471.6526)
		(property "Reference" "Q78"
			(at 0 0 0)
			(layer "F.SilkS")
			(hide yes)
			(effects
				(font
					(size 1.27 1.27)
				)
			)
		)
		(property "Value" "2N7002A-7-GP"
			(at 0.127 -8.9662 0)
			(unlocked yes)
			(layer "F.Fab")
			(hide yes)
			(effects
				(font
					(size 1.016 1.016)
					(thickness 0.1524)
				)
			)
		)
		(property "Device Type" "SOT23DGS2D4H48"
			(at 0.127 -10.4902 0)
			(unlocked yes)
			(layer "F.Fab")
			(hide yes)
			(effects
				(font
					(size 1.016 1.016)
					(thickness 0.1524)
				)
			)
		)
		(duplicate_pad_numbers_are_jumpers no)
		(fp_line
			(start -1.651 -1.778)
			(end -1.651 1.778)
			(stroke
				(width 0.1524)
				(type default)
			)
			(layer "F.SilkS")
		)
		(fp_line
			(start -1.651 1.778)
			(end 1.651 1.778)
			(stroke
				(width 0.1524)
				(type default)
			)
			(layer "F.SilkS")
		)
		(fp_line
			(start 1.651 -1.778)
			(end -1.651 -1.778)
			(stroke
				(width 0.1524)
				(type default)
			)
			(layer "F.SilkS")
		)
		(fp_line
			(start 1.651 1.778)
			(end 1.651 -1.778)
			(stroke
				(width 0.1524)
				(type default)
			)
			(layer "F.SilkS")
		)
		(fp_poly
			(pts
				(xy -1.778 1.8796) (xy -1.778 -1.8796) (xy 1.778 -1.8796) (xy 1.778 1.8796)
			)
			(stroke
				(width 0)
				(type default)
			)
			(fill no)
			(layer "F.CrtYd")
		)
		(fp_poly
			(pts
				(xy -1.778 1.8796) (xy -1.778 -1.8796) (xy 1.778 -1.8796) (xy 1.778 1.8796)
			)
			(stroke
				(width 0)
				(type default)
			)
			(fill no)
			(layer "F.Fab")
		)
		(pad "D" smd custom
			(at 0 -0.9525)
			(size 0.1905 0.1905)
			(layers "F.Cu" "F.Mask" "F.Paste")
			(net "SSD_ACT_DR10_MOS_N")
			(options
				(clearance outline)
				(anchor circle)
			)
			(primitives
				(gr_poly
					(pts
						(arc
							(start -0.1778 0.5715)
							(mid -0.321484 0.511984)
							(end -0.381 0.3683)
						)
						(arc
							(start -0.381 -0.3683)
							(mid -0.321484 -0.511984)
							(end -0.1778 -0.5715)
						)
						(arc
							(start 0.1778 -0.5715)
							(mid 0.321484 -0.511984)
							(end 0.381 -0.3683)
						)
						(arc
							(start 0.381 0.3683)
							(mid 0.321484 0.511984)
							(end 0.1778 0.5715)
						)
					)
					(width 0)
					(fill yes)
				)
			)
		)
		(pad "G" smd custom
			(at -0.98425 0.9525)
			(size 0.1905 0.1905)
			(layers "F.Cu" "F.Mask" "F.Paste")
			(net "ATTN_LED_DR10_AND_R")
			(options
				(clearance outline)
				(anchor circle)
			)
			(primitives
				(gr_poly
					(pts
						(arc
							(start -0.1778 0.5715)
							(mid -0.321484 0.511984)
							(end -0.381 0.3683)
						)
						(arc
							(start -0.381 -0.3683)
							(mid -0.321484 -0.511984)
							(end -0.1778 -0.5715)
						)
						(arc
							(start 0.1778 -0.5715)
							(mid 0.321484 -0.511984)
							(end 0.381 -0.3683)
						)
						(arc
							(start 0.381 0.3683)
							(mid 0.321484 0.511984)
							(end 0.1778 0.5715)
						)
					)
					(width 0)
					(fill yes)
				)
			)
		)
		(pad "S" smd custom
			(at 0.98425 0.9525)
			(size 0.1905 0.1905)
			(layers "F.Cu" "F.Mask" "F.Paste")
			(net "SSD_ACT_DR10_R")
			(options
				(clearance outline)
				(anchor circle)
			)
			(primitives
				(gr_poly
					(pts
						(arc
							(start -0.1778 0.5715)
							(mid -0.321484 0.511984)
							(end -0.381 0.3683)
						)
						(arc
							(start -0.381 -0.3683)
							(mid -0.321484 -0.511984)
							(end -0.1778 -0.5715)
						)
						(arc
							(start 0.1778 -0.5715)
							(mid 0.321484 -0.511984)
							(end 0.381 -0.3683)
						)
						(arc
							(start 0.381 0.3683)
							(mid 0.321484 0.511984)
							(end 0.1778 0.5715)
						)
					)
					(width 0)
					(fill yes)
				)
			)
		)
	)
	(footprint ""
		(layer "F.Cu")
		(at 24.892 -159.887158 90)
		(property "Reference" "Q94"
			(at 0 0 90)
			(layer "F.SilkS")
			(hide yes)
			(effects
				(font
					(size 1.27 1.27)
				)
			)
		)
		(property "Value" "2N7002A-7-GP"
			(at 0.127 -8.9662 90)
			(unlocked yes)
			(layer "F.Fab")
			(hide yes)
			(effects
				(font
					(size 1.016 1.016)
					(thickness 0.1524)
				)
			)
		)
		(property "Device Type" "SOT23DGS2D4H48"
			(at 0.127 -10.4902 90)
			(unlocked yes)
			(layer "F.Fab")
			(hide yes)
			(effects
				(font
					(size 1.016 1.016)
					(thickness 0.1524)
				)
			)
		)
		(duplicate_pad_numbers_are_jumpers no)
		(fp_line
			(start 1.651 -1.778)
			(end -1.651 -1.778)
			(stroke
				(width 0.1524)
				(type default)
			)
			(layer "F.SilkS")
		)
		(fp_line
			(start -1.651 -1.778)
			(end -1.651 1.778)
			(stroke
				(width 0.1524)
				(type default)
			)
			(layer "F.SilkS")
		)
		(fp_line
			(start 1.651 1.778)
			(end 1.651 -1.778)
			(stroke
				(width 0.1524)
				(type default)
			)
			(layer "F.SilkS")
		)
		(fp_line
			(start -1.651 1.778)
			(end 1.651 1.778)
			(stroke
				(width 0.1524)
				(type default)
			)
			(layer "F.SilkS")
		)
		(fp_poly
			(pts
				(xy -1.778 1.8796) (xy -1.778 -1.8796) (xy 1.778 -1.8796) (xy 1.778 1.8796)
			)
			(stroke
				(width 0)
				(type default)
			)
			(fill no)
			(layer "F.CrtYd")
		)
		(fp_poly
			(pts
				(xy -1.778 1.8796) (xy -1.778 -1.8796) (xy 1.778 -1.8796) (xy 1.778 1.8796)
			)
			(stroke
				(width 0)
				(type default)
			)
			(fill no)
			(layer "F.Fab")
		)
		(pad "D" smd custom
			(at 0 -0.9525 90)
			(size 0.1905 0.1905)
			(layers "F.Cu" "F.Mask" "F.Paste")
			(net "SSD13_CLK0_OE_MOS_N")
			(options
				(clearance outline)
				(anchor circle)
			)
			(primitives
				(gr_poly
					(pts
						(arc
							(start -0.1778 0.5715)
							(mid -0.321484 0.511984)
							(end -0.381 0.3683)
						)
						(arc
							(start -0.381 -0.3683)
							(mid -0.321484 -0.511984)
							(end -0.1778 -0.5715)
						)
						(arc
							(start 0.1778 -0.5715)
							(mid 0.321484 -0.511984)
							(end 0.381 -0.3683)
						)
						(arc
							(start 0.381 0.3683)
							(mid 0.321484 0.511984)
							(end 0.1778 0.5715)
						)
					)
					(width 0)
					(fill yes)
				)
			)
		)
		(pad "G" smd custom
			(at -0.98425 0.9525 90)
			(size 0.1905 0.1905)
			(layers "F.Cu" "F.Mask" "F.Paste")
			(net "SSD13_CLK0_OE_R_N")
			(options
				(clearance outline)
				(anchor circle)
			)
			(primitives
				(gr_poly
					(pts
						(arc
							(start -0.1778 0.5715)
							(mid -0.321484 0.511984)
							(end -0.381 0.3683)
						)
						(arc
							(start -0.381 -0.3683)
							(mid -0.321484 -0.511984)
							(end -0.1778 -0.5715)
						)
						(arc
							(start 0.1778 -0.5715)
							(mid 0.321484 -0.511984)
							(end 0.381 -0.3683)
						)
						(arc
							(start 0.381 0.3683)
							(mid 0.321484 0.511984)
							(end 0.1778 0.5715)
						)
					)
					(width 0)
					(fill yes)
				)
			)
		)
		(pad "S" smd custom
			(at 0.98425 0.9525 90)
			(size 0.1905 0.1905)
			(layers "F.Cu" "F.Mask" "F.Paste")
			(net "GND")
			(options
				(clearance outline)
				(anchor circle)
			)
			(primitives
				(gr_poly
					(pts
						(arc
							(start -0.1778 0.5715)
							(mid -0.321484 0.511984)
							(end -0.381 0.3683)
						)
						(arc
							(start -0.381 -0.3683)
							(mid -0.321484 -0.511984)
							(end -0.1778 -0.5715)
						)
						(arc
							(start 0.1778 -0.5715)
							(mid 0.321484 -0.511984)
							(end 0.381 -0.3683)
						)
						(arc
							(start 0.381 0.3683)
							(mid 0.321484 0.511984)
							(end 0.1778 0.5715)
						)
					)
					(width 0)
					(fill yes)
				)
			)
		)
	)
	(footprint ""
		(layer "F.Cu")
		(at 222.758 -431.292)
		(property "Reference" "PC1274"
			(at 0 0 0)
			(layer "F.SilkS")
			(hide yes)
			(effects
				(font
					(size 1.27 1.27)
				)
			)
		)
		(property "Value" "SCD1U50V3KX-GP"
			(at 0 -2.8194 0)
			(unlocked yes)
			(layer "F.Fab")
			(hide yes)
			(effects
				(font
					(size 1.016 1.016)
					(thickness 0.1524)
				)
			)
		)
		(property "Device Type" "C603H36"
			(at 0 -4.3434 0)
			(unlocked yes)
			(layer "F.Fab")
			(hide yes)
			(effects
				(font
					(size 1.016 1.016)
					(thickness 0.1524)
				)
			)
		)
		(duplicate_pad_numbers_are_jumpers no)
		(fp_line
			(start 0.508 0)
			(end -0.508 0)
			(stroke
				(width 0.2032)
				(type default)
			)
			(layer "F.SilkS")
		)
		(fp_rect
			(start -0.5842 1.3335)
			(end 0.5842 -1.3335)
			(stroke
				(width 0)
				(type default)
			)
			(fill no)
			(layer "F.CrtYd")
		)
		(fp_rect
			(start -0.5842 1.3335)
			(end 0.5842 -1.3335)
			(stroke
				(width 0)
				(type default)
			)
			(fill no)
			(layer "F.Fab")
		)
		(pad "1" smd custom
			(at 0 -0.762)
			(size 0.2159 0.2159)
			(layers "F.Cu" "F.Mask" "F.Paste")
			(net "P3V3_SW")
			(options
				(clearance outline)
				(anchor circle)
			)
			(primitives
				(gr_poly
					(pts
						(arc
							(start -0.3302 -0.4318)
							(mid -0.402042 -0.402042)
							(end -0.4318 -0.3302)
						)
						(arc
							(start -0.4318 0.3302)
							(mid -0.402042 0.402042)
							(end -0.3302 0.4318)
						)
						(arc
							(start 0.3302 0.4318)
							(mid 0.402042 0.402042)
							(end 0.4318 0.3302)
						)
						(arc
							(start 0.4318 -0.3302)
							(mid 0.402042 -0.402042)
							(end 0.3302 -0.4318)
						)
					)
					(width 0)
					(fill yes)
				)
			)
		)
		(pad "2" smd custom
			(at 0 0.762)
			(size 0.2159 0.2159)
			(layers "F.Cu" "F.Mask" "F.Paste")
			(net "P3V3_VBST_RR")
			(options
				(clearance outline)
				(anchor circle)
			)
			(primitives
				(gr_poly
					(pts
						(arc
							(start -0.3302 -0.4318)
							(mid -0.402042 -0.402042)
							(end -0.4318 -0.3302)
						)
						(arc
							(start -0.4318 0.3302)
							(mid -0.402042 0.402042)
							(end -0.3302 0.4318)
						)
						(arc
							(start 0.3302 0.4318)
							(mid 0.402042 0.402042)
							(end 0.4318 0.3302)
						)
						(arc
							(start 0.4318 -0.3302)
							(mid 0.402042 -0.402042)
							(end 0.3302 -0.4318)
						)
					)
					(width 0)
					(fill yes)
				)
			)
		)
	)
	(footprint ""
		(layer "F.Cu")
		(at 42.926 -141.30782 90)
		(property "Reference" "R9835"
			(at 0 0 90)
			(layer "F.SilkS")
			(hide yes)
			(effects
				(font
					(size 1.27 1.27)
				)
			)
		)
		(property "Value" "0R2J-2-GP"
			(at 0.064008 -3.993896 90)
			(unlocked yes)
			(layer "F.Fab")
			(hide yes)
			(effects
				(font
					(size 1.016 1.016)
					(thickness 0.1524)
				)
			)
		)
		(property "Device Type" "R402H16"
			(at 0.064008 -5.517896 90)
			(unlocked yes)
			(layer "F.Fab")
			(hide yes)
			(effects
				(font
					(size 1.016 1.016)
					(thickness 0.1524)
				)
			)
		)
		(duplicate_pad_numbers_are_jumpers no)
		(fp_line
			(start 0.508 -0.9398)
			(end -0.508 -0.9398)
			(stroke
				(width 0.1524)
				(type default)
			)
			(layer "F.SilkS")
		)
		(fp_line
			(start -0.508 -0.9398)
			(end -0.508 0.9398)
			(stroke
				(width 0.1524)
				(type default)
			)
			(layer "F.SilkS")
		)
		(fp_rect
			(start -0.508 0.9398)
			(end 0.508 -0.9398)
			(stroke
				(width 0)
				(type default)
			)
			(fill no)
			(layer "F.CrtYd")
		)
		(fp_rect
			(start -0.508 0.9398)
			(end 0.508 -0.9398)
			(stroke
				(width 0)
				(type default)
			)
			(fill no)
			(layer "F.Fab")
		)
		(pad "1" smd custom
			(at 0 -0.4445 90)
			(size 0.1397 0.1397)
			(layers "F.Cu" "F.Mask" "F.Paste")
			(net "ATTN_LED_DR8_AND")
			(options
				(clearance outline)
				(anchor circle)
			)
			(primitives
				(gr_poly
					(pts
						(arc
							(start -0.1778 -0.2794)
							(mid -0.249642 -0.249642)
							(end -0.2794 -0.1778)
						)
						(arc
							(start -0.2794 0.1778)
							(mid -0.249642 0.249642)
							(end -0.1778 0.2794)
						)
						(arc
							(start 0.1778 0.2794)
							(mid 0.249642 0.249642)
							(end 0.2794 0.1778)
						)
						(arc
							(start 0.2794 -0.1778)
							(mid 0.249642 -0.249642)
							(end 0.1778 -0.2794)
						)
					)
					(width 0)
					(fill yes)
				)
			)
		)
		(pad "2" smd custom
			(at 0 0.4445 90)
			(size 0.1397 0.1397)
			(layers "F.Cu" "F.Mask" "F.Paste")
			(net "ATTN_LED_DR8_AND_R")
			(options
				(clearance outline)
				(anchor circle)
			)
			(primitives
				(gr_poly
					(pts
						(arc
							(start -0.1778 -0.2794)
							(mid -0.249642 -0.249642)
							(end -0.2794 -0.1778)
						)
						(arc
							(start -0.2794 0.1778)
							(mid -0.249642 0.249642)
							(end -0.1778 0.2794)
						)
						(arc
							(start 0.1778 0.2794)
							(mid 0.249642 0.249642)
							(end 0.2794 0.1778)
						)
						(arc
							(start 0.2794 -0.1778)
							(mid 0.249642 -0.249642)
							(end 0.1778 -0.2794)
						)
					)
					(width 0)
					(fill yes)
				)
			)
		)
	)
	(footprint ""
		(layer "F.Cu")
		(at 70.739 -437.388 -90)
		(property "Reference" "R367"
			(at 0 0 270)
			(layer "F.SilkS")
			(hide yes)
			(effects
				(font
					(size 1.27 1.27)
				)
			)
		)
		(property "Value" "4K7R2J-2-GP"
			(at 0.064008 -3.993896 270)
			(unlocked yes)
			(layer "F.Fab")
			(hide yes)
			(effects
				(font
					(size 1.016 1.016)
					(thickness 0.1524)
				)
			)
		)
		(property "Device Type" "R402H16"
			(at 0.064008 -5.517896 270)
			(unlocked yes)
			(layer "F.Fab")
			(hide yes)
			(effects
				(font
					(size 1.016 1.016)
					(thickness 0.1524)
				)
			)
		)
		(duplicate_pad_numbers_are_jumpers no)
		(fp_line
			(start -0.508 -0.9398)
			(end -0.508 0.9398)
			(stroke
				(width 0.1524)
				(type default)
			)
			(layer "F.SilkS")
		)
		(fp_line
			(start 0.508 -0.9398)
			(end -0.508 -0.9398)
			(stroke
				(width 0.1524)
				(type default)
			)
			(layer "F.SilkS")
		)
		(fp_rect
			(start -0.508 0.9398)
			(end 0.508 -0.9398)
			(stroke
				(width 0)
				(type default)
			)
			(fill no)
			(layer "F.CrtYd")
		)
		(fp_rect
			(start -0.508 0.9398)
			(end 0.508 -0.9398)
			(stroke
				(width 0)
				(type default)
			)
			(fill no)
			(layer "F.Fab")
		)
		(pad "1" smd custom
			(at 0 -0.4445 270)
			(size 0.1397 0.1397)
			(layers "F.Cu" "F.Mask" "F.Paste")
			(net "P3V3")
			(options
				(clearance outline)
				(anchor circle)
			)
			(primitives
				(gr_poly
					(pts
						(arc
							(start -0.1778 -0.2794)
							(mid -0.249642 -0.249642)
							(end -0.2794 -0.1778)
						)
						(arc
							(start -0.2794 0.1778)
							(mid -0.249642 0.249642)
							(end -0.1778 0.2794)
						)
						(arc
							(start 0.1778 0.2794)
							(mid 0.249642 0.249642)
							(end 0.2794 0.1778)
						)
						(arc
							(start 0.2794 -0.1778)
							(mid 0.249642 -0.249642)
							(end 0.1778 -0.2794)
						)
					)
					(width 0)
					(fill yes)
				)
			)
		)
		(pad "2" smd custom
			(at 0 0.4445 270)
			(size 0.1397 0.1397)
			(layers "F.Cu" "F.Mask" "F.Paste")
			(net "I2C_B_SCL")
			(options
				(clearance outline)
				(anchor circle)
			)
			(primitives
				(gr_poly
					(pts
						(arc
							(start -0.1778 -0.2794)
							(mid -0.249642 -0.249642)
							(end -0.2794 -0.1778)
						)
						(arc
							(start -0.2794 0.1778)
							(mid -0.249642 0.249642)
							(end -0.1778 0.2794)
						)
						(arc
							(start 0.1778 0.2794)
							(mid 0.249642 0.249642)
							(end 0.2794 0.1778)
						)
						(arc
							(start 0.2794 -0.1778)
							(mid 0.249642 -0.249642)
							(end 0.1778 -0.2794)
						)
					)
					(width 0)
					(fill yes)
				)
			)
		)
	)
	(footprint ""
		(layer "F.Cu")
		(at 85.471 -429.514 90)
		(property "Reference" "PR9009"
			(at 0 0 90)
			(layer "F.SilkS")
			(hide yes)
			(effects
				(font
					(size 1.27 1.27)
				)
			)
		)
		(property "Value" "4K7R2F-GP"
			(at 0.064008 -3.993896 90)
			(unlocked yes)
			(layer "F.Fab")
			(hide yes)
			(effects
				(font
					(size 1.016 1.016)
					(thickness 0.1524)
				)
			)
		)
		(property "Device Type" "R402H16"
			(at 0.064008 -5.517896 90)
			(unlocked yes)
			(layer "F.Fab")
			(hide yes)
			(effects
				(font
					(size 1.016 1.016)
					(thickness 0.1524)
				)
			)
		)
		(duplicate_pad_numbers_are_jumpers no)
		(fp_line
			(start 0.508 -0.9398)
			(end -0.508 -0.9398)
			(stroke
				(width 0.1524)
				(type default)
			)
			(layer "F.SilkS")
		)
		(fp_line
			(start -0.508 -0.9398)
			(end -0.508 0.9398)
			(stroke
				(width 0.1524)
				(type default)
			)
			(layer "F.SilkS")
		)
		(fp_rect
			(start -0.508 0.9398)
			(end 0.508 -0.9398)
			(stroke
				(width 0)
				(type default)
			)
			(fill no)
			(layer "F.CrtYd")
		)
		(fp_rect
			(start -0.508 0.9398)
			(end 0.508 -0.9398)
			(stroke
				(width 0)
				(type default)
			)
			(fill no)
			(layer "F.Fab")
		)
		(pad "1" smd custom
			(at 0 -0.4445 90)
			(size 0.1397 0.1397)
			(layers "F.Cu" "F.Mask" "F.Paste")
			(net "VDD_DIFF_1")
			(options
				(clearance outline)
				(anchor circle)
			)
			(primitives
				(gr_poly
					(pts
						(arc
							(start -0.1778 -0.2794)
							(mid -0.249642 -0.249642)
							(end -0.2794 -0.1778)
						)
						(arc
							(start -0.2794 0.1778)
							(mid -0.249642 0.249642)
							(end -0.1778 0.2794)
						)
						(arc
							(start 0.1778 0.2794)
							(mid 0.249642 0.249642)
							(end 0.2794 0.1778)
						)
						(arc
							(start 0.2794 -0.1778)
							(mid 0.249642 -0.249642)
							(end 0.1778 -0.2794)
						)
					)
					(width 0)
					(fill yes)
				)
			)
		)
		(pad "2" smd custom
			(at 0 0.4445 90)
			(size 0.1397 0.1397)
			(layers "F.Cu" "F.Mask" "F.Paste")
			(net "CLK_BUF_EU1_SMB_A0_TRI")
			(options
				(clearance outline)
				(anchor circle)
			)
			(primitives
				(gr_poly
					(pts
						(arc
							(start -0.1778 -0.2794)
							(mid -0.249642 -0.249642)
							(end -0.2794 -0.1778)
						)
						(arc
							(start -0.2794 0.1778)
							(mid -0.249642 0.249642)
							(end -0.1778 0.2794)
						)
						(arc
							(start 0.1778 0.2794)
							(mid 0.249642 0.249642)
							(end 0.2794 0.1778)
						)
						(arc
							(start 0.2794 -0.1778)
							(mid 0.249642 -0.249642)
							(end 0.1778 -0.2794)
						)
					)
					(width 0)
					(fill yes)
				)
			)
		)
	)
	(footprint ""
		(layer "F.Cu")
		(at 34.9504 -395.3002)
		(property "Reference" "PC1241"
			(at 0 0 0)
			(layer "F.SilkS")
			(hide yes)
			(effects
				(font
					(size 1.27 1.27)
				)
			)
		)
		(property "Value" "SC22U25V6KX-GP-U"
			(at -2.860802 -5.279644 0)
			(unlocked yes)
			(layer "F.Fab")
			(hide yes)
			(effects
				(font
					(size 1.016 1.016)
					(thickness 0.1524)
				)
			)
		)
		(property "Device Type" "C1206-TO0D3H75"
			(at -2.860802 -6.803644 0)
			(unlocked yes)
			(layer "F.Fab")
			(hide yes)
			(effects
				(font
					(size 1.016 1.016)
					(thickness 0.1524)
				)
			)
		)
		(duplicate_pad_numbers_are_jumpers no)
		(fp_line
			(start -1.3081 -2.3749)
			(end 1.3081 -2.3749)
			(stroke
				(width 0.1524)
				(type default)
			)
			(layer "F.SilkS")
		)
		(fp_line
			(start -1.3081 2.3749)
			(end -1.3081 -2.3749)
			(stroke
				(width 0.1524)
				(type default)
			)
			(layer "F.SilkS")
		)
		(fp_line
			(start 1.3081 -2.3749)
			(end 1.3081 2.3749)
			(stroke
				(width 0.1524)
				(type default)
			)
			(layer "F.SilkS")
		)
		(fp_line
			(start 1.3081 2.3749)
			(end -1.3081 2.3749)
			(stroke
				(width 0.1524)
				(type default)
			)
			(layer "F.SilkS")
		)
		(fp_rect
			(start -0.8001 1.6002)
			(end 0.8001 -1.6002)
			(stroke
				(width 0)
				(type default)
			)
			(fill no)
			(layer "F.CrtYd")
		)
		(fp_poly
			(pts
				(xy -1.5621 2.4511) (xy -1.5621 1.6002) (xy 0.8001 1.6002) (xy 0.8001 -1.6002) (xy -0.8001 -1.6002)
				(xy -0.8001 1.5875) (xy -1.5621 1.5875) (xy -1.5621 -2.4511) (xy 1.5621 -2.4511) (xy 1.5621 2.4511)
			)
			(stroke
				(width 0)
				(type default)
			)
			(fill no)
			(layer "F.CrtYd")
		)
		(fp_rect
			(start -1.5621 2.4511)
			(end 1.5621 -2.4511)
			(stroke
				(width 0)
				(type default)
			)
			(fill no)
			(layer "F.Fab")
		)
		(pad "1" smd rect
			(at 0 -1.392936)
			(size 2.1082 1.4478)
			(layers "F.Cu" "F.Mask" "F.Paste")
			(net "P12V_SSD6")
		)
		(pad "2" smd rect
			(at 0 1.392936)
			(size 2.1082 1.4478)
			(layers "F.Cu" "F.Mask" "F.Paste")
			(net "GND")
		)
	)
	(footprint ""
		(layer "F.Cu")
		(at 206.502 -295.529)
		(property "Reference" "D20"
			(at 0 0 0)
			(layer "F.SilkS")
			(hide yes)
			(effects
				(font
					(size 1.27 1.27)
				)
			)
		)
		(property "Value" "RB551V30-1-GP"
			(at 0 -6.7818 0)
			(unlocked yes)
			(layer "F.Fab")
			(hide yes)
			(effects
				(font
					(size 1.016 1.016)
					(thickness 0.1524)
				)
			)
		)
		(property "Device Type" "SOD323AKH44"
			(at 0 -8.6868 0)
			(unlocked yes)
			(layer "F.Fab")
			(hide yes)
			(effects
				(font
					(size 1.016 1.016)
					(thickness 0.1524)
				)
			)
		)
		(duplicate_pad_numbers_are_jumpers no)
		(fp_line
			(start -0.889 -1.9304)
			(end 0.889 -1.9304)
			(stroke
				(width 0.1524)
				(type default)
			)
			(layer "F.SilkS")
		)
		(fp_line
			(start -0.889 2.159)
			(end -0.889 -1.9304)
			(stroke
				(width 0.1524)
				(type default)
			)
			(layer "F.SilkS")
		)
		(fp_line
			(start 0.762 2.0574)
			(end -0.762 2.0574)
			(stroke
				(width 0.508)
				(type default)
			)
			(layer "F.SilkS")
		)
		(fp_line
			(start 0.889 -1.9304)
			(end 0.889 2.159)
			(stroke
				(width 0.1524)
				(type default)
			)
			(layer "F.SilkS")
		)
		(fp_line
			(start 0.889 2.159)
			(end -0.889 2.159)
			(stroke
				(width 0.1524)
				(type default)
			)
			(layer "F.SilkS")
		)
		(fp_rect
			(start -1.016 2.3114)
			(end 1.016 -2.0066)
			(stroke
				(width 0)
				(type default)
			)
			(fill no)
			(layer "F.CrtYd")
		)
		(fp_poly
			(pts
				(xy -1.016 -2.0066) (xy 1.016 -2.0066) (xy 1.016 2.3114) (xy -1.016 2.3114)
			)
			(stroke
				(width 0)
				(type default)
			)
			(fill no)
			(layer "F.Fab")
		)
		(pad "A" smd rect
			(at 0 -1.143)
			(size 0.5588 1.016)
			(layers "F.Cu" "F.Mask" "F.Paste")
			(net "SW_SSD2_R")
		)
		(pad "K" smd rect
			(at 0 1.143)
			(size 0.5588 1.016)
			(layers "F.Cu" "F.Mask" "F.Paste")
			(net "SW_SSD2_N")
		)
	)
	(footprint ""
		(layer "F.Cu")
		(at 70.993 -454.66 180)
		(property "Reference" "R349"
			(at 0 0 180)
			(layer "F.SilkS")
			(hide yes)
			(effects
				(font
					(size 1.27 1.27)
				)
			)
		)
		(property "Value" "4K7R2J-2-GP"
			(at 0.064008 -3.993896 180)
			(unlocked yes)
			(layer "F.Fab")
			(hide yes)
			(effects
				(font
					(size 1.016 1.016)
					(thickness 0.1524)
				)
			)
		)
		(property "Device Type" "R402H16"
			(at 0.064008 -5.517896 180)
			(unlocked yes)
			(layer "F.Fab")
			(hide yes)
			(effects
				(font
					(size 1.016 1.016)
					(thickness 0.1524)
				)
			)
		)
		(duplicate_pad_numbers_are_jumpers no)
		(fp_line
			(start 0.508 -0.9398)
			(end -0.508 -0.9398)
			(stroke
				(width 0.1524)
				(type default)
			)
			(layer "F.SilkS")
		)
		(fp_line
			(start -0.508 -0.9398)
			(end -0.508 0.9398)
			(stroke
				(width 0.1524)
				(type default)
			)
			(layer "F.SilkS")
		)
		(fp_rect
			(start -0.508 0.9398)
			(end 0.508 -0.9398)
			(stroke
				(width 0)
				(type default)
			)
			(fill no)
			(layer "F.CrtYd")
		)
		(fp_rect
			(start -0.508 0.9398)
			(end 0.508 -0.9398)
			(stroke
				(width 0)
				(type default)
			)
			(fill no)
			(layer "F.Fab")
		)
		(pad "1" smd custom
			(at 0 -0.4445 180)
			(size 0.1397 0.1397)
			(layers "F.Cu" "F.Mask" "F.Paste")
			(net "EEPROM_A1")
			(options
				(clearance outline)
				(anchor circle)
			)
			(primitives
				(gr_poly
					(pts
						(arc
							(start -0.1778 -0.2794)
							(mid -0.249642 -0.249642)
							(end -0.2794 -0.1778)
						)
						(arc
							(start -0.2794 0.1778)
							(mid -0.249642 0.249642)
							(end -0.1778 0.2794)
						)
						(arc
							(start 0.1778 0.2794)
							(mid 0.249642 0.249642)
							(end 0.2794 0.1778)
						)
						(arc
							(start 0.2794 -0.1778)
							(mid 0.249642 -0.249642)
							(end 0.1778 -0.2794)
						)
					)
					(width 0)
					(fill yes)
				)
			)
		)
		(pad "2" smd custom
			(at 0 0.4445 180)
			(size 0.1397 0.1397)
			(layers "F.Cu" "F.Mask" "F.Paste")
			(net "GND")
			(options
				(clearance outline)
				(anchor circle)
			)
			(primitives
				(gr_poly
					(pts
						(arc
							(start -0.1778 -0.2794)
							(mid -0.249642 -0.249642)
							(end -0.2794 -0.1778)
						)
						(arc
							(start -0.2794 0.1778)
							(mid -0.249642 0.249642)
							(end -0.1778 0.2794)
						)
						(arc
							(start 0.1778 0.2794)
							(mid 0.249642 0.249642)
							(end 0.2794 0.1778)
						)
						(arc
							(start 0.2794 -0.1778)
							(mid 0.249642 -0.249642)
							(end 0.1778 -0.2794)
						)
					)
					(width 0)
					(fill yes)
				)
			)
		)
	)
	(footprint ""
		(layer "F.Cu")
		(at 21.5138 -89.535)
		(property "Reference" "D27"
			(at 0 0 0)
			(layer "F.SilkS")
			(hide yes)
			(effects
				(font
					(size 1.27 1.27)
				)
			)
		)
		(property "Value" "RB551V30-1-GP"
			(at 0 -6.7818 0)
			(unlocked yes)
			(layer "F.Fab")
			(hide yes)
			(effects
				(font
					(size 1.016 1.016)
					(thickness 0.1524)
				)
			)
		)
		(property "Device Type" "SOD323AKH44"
			(at 0 -8.6868 0)
			(unlocked yes)
			(layer "F.Fab")
			(hide yes)
			(effects
				(font
					(size 1.016 1.016)
					(thickness 0.1524)
				)
			)
		)
		(duplicate_pad_numbers_are_jumpers no)
		(fp_line
			(start -0.889 -1.9304)
			(end 0.889 -1.9304)
			(stroke
				(width 0.1524)
				(type default)
			)
			(layer "F.SilkS")
		)
		(fp_line
			(start -0.889 2.159)
			(end -0.889 -1.9304)
			(stroke
				(width 0.1524)
				(type default)
			)
			(layer "F.SilkS")
		)
		(fp_line
			(start 0.762 2.0574)
			(end -0.762 2.0574)
			(stroke
				(width 0.508)
				(type default)
			)
			(layer "F.SilkS")
		)
		(fp_line
			(start 0.889 -1.9304)
			(end 0.889 2.159)
			(stroke
				(width 0.1524)
				(type default)
			)
			(layer "F.SilkS")
		)
		(fp_line
			(start 0.889 2.159)
			(end -0.889 2.159)
			(stroke
				(width 0.1524)
				(type default)
			)
			(layer "F.SilkS")
		)
		(fp_rect
			(start -1.016 2.3114)
			(end 1.016 -2.0066)
			(stroke
				(width 0)
				(type default)
			)
			(fill no)
			(layer "F.CrtYd")
		)
		(fp_poly
			(pts
				(xy -1.016 -2.0066) (xy 1.016 -2.0066) (xy 1.016 2.3114) (xy -1.016 2.3114)
			)
			(stroke
				(width 0)
				(type default)
			)
			(fill no)
			(layer "F.Fab")
		)
		(pad "A" smd rect
			(at 0 -1.143)
			(size 0.5588 1.016)
			(layers "F.Cu" "F.Mask" "F.Paste")
			(net "SW_SSD9_R")
		)
		(pad "K" smd rect
			(at 0 1.143)
			(size 0.5588 1.016)
			(layers "F.Cu" "F.Mask" "F.Paste")
			(net "SW_SSD9_N")
		)
	)
	(footprint ""
		(layer "F.Cu")
		(at 34.0868 -499.1608)
		(property "Reference" "R9245"
			(at 0 0 0)
			(layer "F.SilkS")
			(hide yes)
			(effects
				(font
					(size 1.27 1.27)
				)
			)
		)
		(property "Value" "2R2010F-GP"
			(at 0.0762 -4.5466 0)
			(unlocked yes)
			(layer "F.Fab")
			(hide yes)
			(effects
				(font
					(size 1.016 1.016)
					(thickness 0.1524)
				)
			)
		)
		(property "Device Type" "R2010H26"
			(at 0.0762 -6.1468 0)
			(unlocked yes)
			(layer "F.Fab")
			(hide yes)
			(effects
				(font
					(size 1.016 1.016)
					(thickness 0.1524)
				)
			)
		)
		(duplicate_pad_numbers_are_jumpers no)
		(fp_line
			(start -3.302 -1.651)
			(end -3.302 1.651)
			(stroke
				(width 0.1524)
				(type default)
			)
			(layer "F.SilkS")
		)
		(fp_line
			(start -3.302 1.651)
			(end 3.302 1.651)
			(stroke
				(width 0.1524)
				(type default)
			)
			(layer "F.SilkS")
		)
		(fp_line
			(start 3.302 -1.651)
			(end -3.302 -1.651)
			(stroke
				(width 0.1524)
				(type default)
			)
			(layer "F.SilkS")
		)
		(fp_line
			(start 3.302 1.651)
			(end 3.302 -1.651)
			(stroke
				(width 0.1524)
				(type default)
			)
			(layer "F.SilkS")
		)
		(fp_rect
			(start -3.3782 1.7272)
			(end 3.3782 -1.7272)
			(stroke
				(width 0)
				(type default)
			)
			(fill no)
			(layer "F.CrtYd")
		)
		(fp_poly
			(pts
				(xy 3.3782 -1.7272) (xy -3.3782 -1.7272) (xy -3.3782 1.7272) (xy 3.3782 1.7272)
			)
			(stroke
				(width 0)
				(type default)
			)
			(fill no)
			(layer "F.Fab")
		)
		(pad "1" smd rect
			(at -2.3495 0)
			(size 1.143 2.794)
			(layers "F.Cu" "F.Mask" "F.Paste")
			(net "P12V_SSD5")
		)
		(pad "2" smd rect
			(at 2.3495 0)
			(size 1.143 2.794)
			(layers "F.Cu" "F.Mask" "F.Paste")
			(net "12V_PRECH_SSD5")
		)
	)
	(footprint ""
		(layer "F.Cu")
		(at 206.502 -192.532)
		(property "Reference" "D21"
			(at 0 0 0)
			(layer "F.SilkS")
			(hide yes)
			(effects
				(font
					(size 1.27 1.27)
				)
			)
		)
		(property "Value" "RB551V30-1-GP"
			(at 0 -6.7818 0)
			(unlocked yes)
			(layer "F.Fab")
			(hide yes)
			(effects
				(font
					(size 1.016 1.016)
					(thickness 0.1524)
				)
			)
		)
		(property "Device Type" "SOD323AKH44"
			(at 0 -8.6868 0)
			(unlocked yes)
			(layer "F.Fab")
			(hide yes)
			(effects
				(font
					(size 1.016 1.016)
					(thickness 0.1524)
				)
			)
		)
		(duplicate_pad_numbers_are_jumpers no)
		(fp_line
			(start -0.889 -1.9304)
			(end 0.889 -1.9304)
			(stroke
				(width 0.1524)
				(type default)
			)
			(layer "F.SilkS")
		)
		(fp_line
			(start -0.889 2.159)
			(end -0.889 -1.9304)
			(stroke
				(width 0.1524)
				(type default)
			)
			(layer "F.SilkS")
		)
		(fp_line
			(start 0.762 2.0574)
			(end -0.762 2.0574)
			(stroke
				(width 0.508)
				(type default)
			)
			(layer "F.SilkS")
		)
		(fp_line
			(start 0.889 -1.9304)
			(end 0.889 2.159)
			(stroke
				(width 0.1524)
				(type default)
			)
			(layer "F.SilkS")
		)
		(fp_line
			(start 0.889 2.159)
			(end -0.889 2.159)
			(stroke
				(width 0.1524)
				(type default)
			)
			(layer "F.SilkS")
		)
		(fp_rect
			(start -1.016 2.3114)
			(end 1.016 -2.0066)
			(stroke
				(width 0)
				(type default)
			)
			(fill no)
			(layer "F.CrtYd")
		)
		(fp_poly
			(pts
				(xy -1.016 -2.0066) (xy 1.016 -2.0066) (xy 1.016 2.3114) (xy -1.016 2.3114)
			)
			(stroke
				(width 0)
				(type default)
			)
			(fill no)
			(layer "F.Fab")
		)
		(pad "A" smd rect
			(at 0 -1.143)
			(size 0.5588 1.016)
			(layers "F.Cu" "F.Mask" "F.Paste")
			(net "SW_SSD3_R")
		)
		(pad "K" smd rect
			(at 0 1.143)
			(size 0.5588 1.016)
			(layers "F.Cu" "F.Mask" "F.Paste")
			(net "SW_SSD3_N")
		)
	)
	(footprint ""
		(layer "F.Cu")
		(at 17.77365 -463.126074 -90)
		(property "Reference" "R9948"
			(at 0 0 270)
			(layer "F.SilkS")
			(hide yes)
			(effects
				(font
					(size 1.27 1.27)
				)
			)
		)
		(property "Value" "4K7R2J-2-GP"
			(at 0.064008 -3.993896 270)
			(unlocked yes)
			(layer "F.Fab")
			(hide yes)
			(effects
				(font
					(size 1.016 1.016)
					(thickness 0.1524)
				)
			)
		)
		(property "Device Type" "R402H16"
			(at 0.064008 -5.517896 270)
			(unlocked yes)
			(layer "F.Fab")
			(hide yes)
			(effects
				(font
					(size 1.016 1.016)
					(thickness 0.1524)
				)
			)
		)
		(duplicate_pad_numbers_are_jumpers no)
		(fp_line
			(start -0.508 -0.9398)
			(end -0.508 0.9398)
			(stroke
				(width 0.1524)
				(type default)
			)
			(layer "F.SilkS")
		)
		(fp_line
			(start 0.508 -0.9398)
			(end -0.508 -0.9398)
			(stroke
				(width 0.1524)
				(type default)
			)
			(layer "F.SilkS")
		)
		(fp_rect
			(start -0.508 0.9398)
			(end 0.508 -0.9398)
			(stroke
				(width 0)
				(type default)
			)
			(fill no)
			(layer "F.CrtYd")
		)
		(fp_rect
			(start -0.508 0.9398)
			(end 0.508 -0.9398)
			(stroke
				(width 0)
				(type default)
			)
			(fill no)
			(layer "F.Fab")
		)
		(pad "1" smd custom
			(at 0 -0.4445 270)
			(size 0.1397 0.1397)
			(layers "F.Cu" "F.Mask" "F.Paste")
			(net "P3V3")
			(options
				(clearance outline)
				(anchor circle)
			)
			(primitives
				(gr_poly
					(pts
						(arc
							(start -0.1778 -0.2794)
							(mid -0.249642 -0.249642)
							(end -0.2794 -0.1778)
						)
						(arc
							(start -0.2794 0.1778)
							(mid -0.249642 0.249642)
							(end -0.1778 0.2794)
						)
						(arc
							(start 0.1778 0.2794)
							(mid 0.249642 0.249642)
							(end 0.2794 0.1778)
						)
						(arc
							(start 0.2794 -0.1778)
							(mid 0.249642 -0.249642)
							(end 0.1778 -0.2794)
						)
					)
					(width 0)
					(fill yes)
				)
			)
		)
		(pad "2" smd custom
			(at 0 0.4445 270)
			(size 0.1397 0.1397)
			(layers "F.Cu" "F.Mask" "F.Paste")
			(net "SSD_ACT_DR10_MOS_N")
			(options
				(clearance outline)
				(anchor circle)
			)
			(primitives
				(gr_poly
					(pts
						(arc
							(start -0.1778 -0.2794)
							(mid -0.249642 -0.249642)
							(end -0.2794 -0.1778)
						)
						(arc
							(start -0.2794 0.1778)
							(mid -0.249642 0.249642)
							(end -0.1778 0.2794)
						)
						(arc
							(start 0.1778 0.2794)
							(mid 0.249642 0.249642)
							(end 0.2794 0.1778)
						)
						(arc
							(start 0.2794 -0.1778)
							(mid 0.249642 -0.249642)
							(end 0.1778 -0.2794)
						)
					)
					(width 0)
					(fill yes)
				)
			)
		)
	)
	(footprint ""
		(layer "F.Cu")
		(at 30.999938 -379.000004 -90)
		(property "Reference" "U49"
			(at 0 0 270)
			(layer "F.SilkS")
			(hide yes)
			(effects
				(font
					(size 1.27 1.27)
				)
			)
		)
		(property "Value" "TMP75AIDGKR-GP"
			(at -0.1143 -9.1948 270)
			(unlocked yes)
			(layer "F.Fab")
			(hide yes)
			(effects
				(font
					(size 1.016 1.016)
					(thickness 0.1524)
				)
			)
		)
		(property "Device Type" "MSOP8-1H44"
			(at -0.1143 -10.795 270)
			(unlocked yes)
			(layer "F.Fab")
			(hide yes)
			(effects
				(font
					(size 1.016 1.016)
					(thickness 0.1524)
				)
			)
		)
		(duplicate_pad_numbers_are_jumpers no)
		(fp_line
			(start -1.778 1.0922)
			(end -1.778 3.048)
			(stroke
				(width 0.508)
				(type default)
			)
			(layer "F.SilkS")
		)
		(fp_line
			(start -1.9558 1.016)
			(end 1.0795 1.016)
			(stroke
				(width 0.1524)
				(type default)
			)
			(layer "F.SilkS")
		)
		(fp_line
			(start 1.0795 1.016)
			(end 1.0795 -1.016)
			(stroke
				(width 0.1524)
				(type default)
			)
			(layer "F.SilkS")
		)
		(fp_line
			(start -1.4478 -0.0381)
			(end -1.9558 0.4699)
			(stroke
				(width 0.1524)
				(type default)
			)
			(layer "F.SilkS")
		)
		(fp_line
			(start -1.9558 -0.5461)
			(end -1.4478 -0.0381)
			(stroke
				(width 0.1524)
				(type default)
			)
			(layer "F.SilkS")
		)
		(fp_line
			(start -1.9558 -1.016)
			(end -1.9558 1.016)
			(stroke
				(width 0.1524)
				(type default)
			)
			(layer "F.SilkS")
		)
		(fp_line
			(start 1.0795 -1.016)
			(end -1.9558 -1.016)
			(stroke
				(width 0.1524)
				(type default)
			)
			(layer "F.SilkS")
		)
		(fp_poly
			(pts
				(xy -1.1557 -1.016) (xy -1.1557 1.016) (xy 1.1557 1.016) (xy 1.1557 -1.016)
			)
			(stroke
				(width 0)
				(type default)
			)
			(fill yes)
			(layer "F.SilkS")
		)
		(fp_rect
			(start -1.4986 2.4511)
			(end 1.4986 -2.4511)
			(stroke
				(width 0)
				(type default)
			)
			(fill no)
			(layer "F.CrtYd")
		)
		(fp_poly
			(pts
				(xy -2.032 3.302) (xy -2.032 -3.302) (xy 2.032 -3.302) (xy 2.032 -2.1209) (xy 1.4986 -2.1209) (xy 1.4986 -2.4511)
				(xy -1.4986 -2.4511) (xy -1.4986 2.4511) (xy 1.4986 2.4511) (xy 1.4986 -2.1082) (xy 2.032 -2.1082)
				(xy 2.032 3.302)
			)
			(stroke
				(width 0)
				(type default)
			)
			(fill no)
			(layer "F.CrtYd")
		)
		(fp_rect
			(start -2.032 3.302)
			(end 2.032 -3.302)
			(stroke
				(width 0)
				(type default)
			)
			(fill no)
			(layer "F.Fab")
		)
		(pad "1" smd rect
			(at -0.97536 2.05486 270)
			(size 0.3556 1.524)
			(layers "F.Cu" "F.Mask" "F.Paste")
			(net "TMP4_SDA")
		)
		(pad "2" smd rect
			(at -0.32512 2.05486 270)
			(size 0.3556 1.524)
			(layers "F.Cu" "F.Mask" "F.Paste")
			(net "TMP4_SCL")
		)
		(pad "3" smd rect
			(at 0.32512 2.05486 270)
			(size 0.3556 1.524)
			(layers "F.Cu" "F.Mask" "F.Paste")
			(net "I2C_B_TMP4_ALERT")
		)
		(pad "4" smd rect
			(at 0.97536 2.05486 270)
			(size 0.3556 1.524)
			(layers "F.Cu" "F.Mask" "F.Paste")
			(net "GND")
		)
		(pad "5" smd rect
			(at 0.97536 -2.05486 270)
			(size 0.3556 1.524)
			(layers "F.Cu" "F.Mask" "F.Paste")
			(net "I2C_B_TMP4_A2")
		)
		(pad "6" smd rect
			(at 0.32512 -2.05486 270)
			(size 0.3556 1.524)
			(layers "F.Cu" "F.Mask" "F.Paste")
			(net "I2C_B_TMP4_A1")
		)
		(pad "7" smd rect
			(at -0.32512 -2.05486 270)
			(size 0.3556 1.524)
			(layers "F.Cu" "F.Mask" "F.Paste")
			(net "I2C_B_TMP4_A0")
		)
		(pad "8" smd rect
			(at -0.97536 -2.05486 270)
			(size 0.3556 1.524)
			(layers "F.Cu" "F.Mask" "F.Paste")
			(net "P3V3")
		)
	)
	(footprint ""
		(layer "F.Cu")
		(at 234.061 -349.631 -90)
		(property "Reference" "R9450"
			(at 0 0 270)
			(layer "F.SilkS")
			(hide yes)
			(effects
				(font
					(size 1.27 1.27)
				)
			)
		)
		(property "Value" "100R2J-2-GP"
			(at 0.064008 -3.993896 270)
			(unlocked yes)
			(layer "F.Fab")
			(hide yes)
			(effects
				(font
					(size 1.016 1.016)
					(thickness 0.1524)
				)
			)
		)
		(property "Device Type" "R402H14"
			(at 0.064008 -5.517896 270)
			(unlocked yes)
			(layer "F.Fab")
			(hide yes)
			(effects
				(font
					(size 1.016 1.016)
					(thickness 0.1524)
				)
			)
		)
		(duplicate_pad_numbers_are_jumpers no)
		(fp_line
			(start -0.508 -0.9398)
			(end -0.508 0.9398)
			(stroke
				(width 0.1524)
				(type default)
			)
			(layer "F.SilkS")
		)
		(fp_line
			(start 0.508 -0.9398)
			(end -0.508 -0.9398)
			(stroke
				(width 0.1524)
				(type default)
			)
			(layer "F.SilkS")
		)
		(fp_rect
			(start -0.508 0.9398)
			(end 0.508 -0.9398)
			(stroke
				(width 0)
				(type default)
			)
			(fill no)
			(layer "F.CrtYd")
		)
		(fp_rect
			(start -0.508 0.9398)
			(end 0.508 -0.9398)
			(stroke
				(width 0)
				(type default)
			)
			(fill no)
			(layer "F.Fab")
		)
		(pad "1" smd custom
			(at 0 -0.4445 270)
			(size 0.1397 0.1397)
			(layers "F.Cu" "F.Mask" "F.Paste")
			(net "P3V3")
			(options
				(clearance outline)
				(anchor circle)
			)
			(primitives
				(gr_poly
					(pts
						(arc
							(start -0.1778 -0.2794)
							(mid -0.249642 -0.249642)
							(end -0.2794 -0.1778)
						)
						(arc
							(start -0.2794 0.1778)
							(mid -0.249642 0.249642)
							(end -0.1778 0.2794)
						)
						(arc
							(start 0.1778 0.2794)
							(mid 0.249642 0.249642)
							(end 0.2794 0.1778)
						)
						(arc
							(start 0.2794 -0.1778)
							(mid 0.249642 -0.249642)
							(end 0.1778 -0.2794)
						)
					)
					(width 0)
					(fill yes)
				)
			)
		)
		(pad "2" smd custom
			(at 0 0.4445 270)
			(size 0.1397 0.1397)
			(layers "F.Cu" "F.Mask" "F.Paste")
			(net "DRV_ACT_1")
			(options
				(clearance outline)
				(anchor circle)
			)
			(primitives
				(gr_poly
					(pts
						(arc
							(start -0.1778 -0.2794)
							(mid -0.249642 -0.249642)
							(end -0.2794 -0.1778)
						)
						(arc
							(start -0.2794 0.1778)
							(mid -0.249642 0.249642)
							(end -0.1778 0.2794)
						)
						(arc
							(start 0.1778 0.2794)
							(mid 0.249642 0.249642)
							(end 0.2794 0.1778)
						)
						(arc
							(start 0.2794 -0.1778)
							(mid 0.249642 -0.249642)
							(end 0.1778 -0.2794)
						)
					)
					(width 0)
					(fill yes)
				)
			)
		)
	)
	(footprint ""
		(layer "F.Cu")
		(at 81.661 -356.9716 -90)
		(property "Reference" "SR992"
			(at 0 0 270)
			(layer "F.SilkS")
			(hide yes)
			(effects
				(font
					(size 1.27 1.27)
				)
			)
		)
		(property "Value" "2KR2F-3-GP"
			(at 0.064008 -3.993896 270)
			(unlocked yes)
			(layer "F.Fab")
			(hide yes)
			(effects
				(font
					(size 1.016 1.016)
					(thickness 0.1524)
				)
			)
		)
		(property "Device Type" "R402H16"
			(at 0.064008 -5.517896 270)
			(unlocked yes)
			(layer "F.Fab")
			(hide yes)
			(effects
				(font
					(size 1.016 1.016)
					(thickness 0.1524)
				)
			)
		)
		(duplicate_pad_numbers_are_jumpers no)
		(fp_line
			(start -0.508 -0.9398)
			(end -0.508 0.9398)
			(stroke
				(width 0.1524)
				(type default)
			)
			(layer "F.SilkS")
		)
		(fp_line
			(start 0.508 -0.9398)
			(end -0.508 -0.9398)
			(stroke
				(width 0.1524)
				(type default)
			)
			(layer "F.SilkS")
		)
		(fp_rect
			(start -0.508 0.9398)
			(end 0.508 -0.9398)
			(stroke
				(width 0)
				(type default)
			)
			(fill no)
			(layer "F.CrtYd")
		)
		(fp_rect
			(start -0.508 0.9398)
			(end 0.508 -0.9398)
			(stroke
				(width 0)
				(type default)
			)
			(fill no)
			(layer "F.Fab")
		)
		(pad "1" smd custom
			(at 0 -0.4445 270)
			(size 0.1397 0.1397)
			(layers "F.Cu" "F.Mask" "F.Paste")
			(net "P3V3")
			(options
				(clearance outline)
				(anchor circle)
			)
			(primitives
				(gr_poly
					(pts
						(arc
							(start -0.1778 -0.2794)
							(mid -0.249642 -0.249642)
							(end -0.2794 -0.1778)
						)
						(arc
							(start -0.2794 0.1778)
							(mid -0.249642 0.249642)
							(end -0.1778 0.2794)
						)
						(arc
							(start 0.1778 0.2794)
							(mid 0.249642 0.249642)
							(end 0.2794 0.1778)
						)
						(arc
							(start 0.2794 -0.1778)
							(mid 0.249642 -0.249642)
							(end 0.1778 -0.2794)
						)
					)
					(width 0)
					(fill yes)
				)
			)
		)
		(pad "2" smd custom
			(at 0 0.4445 270)
			(size 0.1397 0.1397)
			(layers "F.Cu" "F.Mask" "F.Paste")
			(net "SDA_DR2")
			(options
				(clearance outline)
				(anchor circle)
			)
			(primitives
				(gr_poly
					(pts
						(arc
							(start -0.1778 -0.2794)
							(mid -0.249642 -0.249642)
							(end -0.2794 -0.1778)
						)
						(arc
							(start -0.2794 0.1778)
							(mid -0.249642 0.249642)
							(end -0.1778 0.2794)
						)
						(arc
							(start 0.1778 0.2794)
							(mid 0.249642 0.249642)
							(end 0.2794 0.1778)
						)
						(arc
							(start 0.2794 -0.1778)
							(mid 0.249642 -0.249642)
							(end 0.1778 -0.2794)
						)
					)
					(width 0)
					(fill yes)
				)
			)
		)
	)
	(footprint ""
		(layer "F.Cu")
		(at 230.251 -439.166 180)
		(property "Reference" "R9891"
			(at 0 0 180)
			(layer "F.SilkS")
			(hide yes)
			(effects
				(font
					(size 1.27 1.27)
				)
			)
		)
		(property "Value" "15KR2F-GP"
			(at 0.064008 -3.993896 180)
			(unlocked yes)
			(layer "F.Fab")
			(hide yes)
			(effects
				(font
					(size 1.016 1.016)
					(thickness 0.1524)
				)
			)
		)
		(property "Device Type" "R402H16"
			(at 0.064008 -5.517896 180)
			(unlocked yes)
			(layer "F.Fab")
			(hide yes)
			(effects
				(font
					(size 1.016 1.016)
					(thickness 0.1524)
				)
			)
		)
		(duplicate_pad_numbers_are_jumpers no)
		(fp_line
			(start 0.508 -0.9398)
			(end -0.508 -0.9398)
			(stroke
				(width 0.1524)
				(type default)
			)
			(layer "F.SilkS")
		)
		(fp_line
			(start -0.508 -0.9398)
			(end -0.508 0.9398)
			(stroke
				(width 0.1524)
				(type default)
			)
			(layer "F.SilkS")
		)
		(fp_rect
			(start -0.508 0.9398)
			(end 0.508 -0.9398)
			(stroke
				(width 0)
				(type default)
			)
			(fill no)
			(layer "F.CrtYd")
		)
		(fp_rect
			(start -0.508 0.9398)
			(end 0.508 -0.9398)
			(stroke
				(width 0)
				(type default)
			)
			(fill no)
			(layer "F.Fab")
		)
		(pad "1" smd custom
			(at 0 -0.4445 180)
			(size 0.1397 0.1397)
			(layers "F.Cu" "F.Mask" "F.Paste")
			(net "TPS53312_P3V3_PG")
			(options
				(clearance outline)
				(anchor circle)
			)
			(primitives
				(gr_poly
					(pts
						(arc
							(start -0.1778 -0.2794)
							(mid -0.249642 -0.249642)
							(end -0.2794 -0.1778)
						)
						(arc
							(start -0.2794 0.1778)
							(mid -0.249642 0.249642)
							(end -0.1778 0.2794)
						)
						(arc
							(start 0.1778 0.2794)
							(mid 0.249642 0.249642)
							(end 0.2794 0.1778)
						)
						(arc
							(start 0.2794 -0.1778)
							(mid 0.249642 -0.249642)
							(end 0.1778 -0.2794)
						)
					)
					(width 0)
					(fill yes)
				)
			)
		)
		(pad "2" smd custom
			(at 0 0.4445 180)
			(size 0.1397 0.1397)
			(layers "F.Cu" "F.Mask" "F.Paste")
			(net "GND")
			(options
				(clearance outline)
				(anchor circle)
			)
			(primitives
				(gr_poly
					(pts
						(arc
							(start -0.1778 -0.2794)
							(mid -0.249642 -0.249642)
							(end -0.2794 -0.1778)
						)
						(arc
							(start -0.2794 0.1778)
							(mid -0.249642 0.249642)
							(end -0.1778 0.2794)
						)
						(arc
							(start 0.1778 0.2794)
							(mid 0.249642 0.249642)
							(end 0.2794 0.1778)
						)
						(arc
							(start 0.2794 -0.1778)
							(mid 0.249642 -0.249642)
							(end 0.1778 -0.2794)
						)
					)
					(width 0)
					(fill yes)
				)
			)
		)
	)
	(footprint ""
		(layer "F.Cu")
		(at 28.8671 -300.5201 180)
		(property "Reference" "R9828"
			(at 0 0 180)
			(layer "F.SilkS")
			(hide yes)
			(effects
				(font
					(size 1.27 1.27)
				)
			)
		)
		(property "Value" "47KR2J-2-GP"
			(at 0.064008 -3.993896 180)
			(unlocked yes)
			(layer "F.Fab")
			(hide yes)
			(effects
				(font
					(size 1.016 1.016)
					(thickness 0.1524)
				)
			)
		)
		(property "Device Type" "R402H16"
			(at 0.064008 -5.517896 180)
			(unlocked yes)
			(layer "F.Fab")
			(hide yes)
			(effects
				(font
					(size 1.016 1.016)
					(thickness 0.1524)
				)
			)
		)
		(duplicate_pad_numbers_are_jumpers no)
		(fp_line
			(start 0.508 -0.9398)
			(end -0.508 -0.9398)
			(stroke
				(width 0.1524)
				(type default)
			)
			(layer "F.SilkS")
		)
		(fp_line
			(start -0.508 -0.9398)
			(end -0.508 0.9398)
			(stroke
				(width 0.1524)
				(type default)
			)
			(layer "F.SilkS")
		)
		(fp_rect
			(start -0.508 0.9398)
			(end 0.508 -0.9398)
			(stroke
				(width 0)
				(type default)
			)
			(fill no)
			(layer "F.CrtYd")
		)
		(fp_rect
			(start -0.508 0.9398)
			(end 0.508 -0.9398)
			(stroke
				(width 0)
				(type default)
			)
			(fill no)
			(layer "F.Fab")
		)
		(pad "1" smd custom
			(at 0 -0.4445 180)
			(size 0.1397 0.1397)
			(layers "F.Cu" "F.Mask" "F.Paste")
			(net "P12V")
			(options
				(clearance outline)
				(anchor circle)
			)
			(primitives
				(gr_poly
					(pts
						(arc
							(start -0.1778 -0.2794)
							(mid -0.249642 -0.249642)
							(end -0.2794 -0.1778)
						)
						(arc
							(start -0.2794 0.1778)
							(mid -0.249642 0.249642)
							(end -0.1778 0.2794)
						)
						(arc
							(start 0.1778 0.2794)
							(mid 0.249642 0.249642)
							(end 0.2794 0.1778)
						)
						(arc
							(start 0.2794 -0.1778)
							(mid 0.249642 -0.249642)
							(end 0.1778 -0.2794)
						)
					)
					(width 0)
					(fill yes)
				)
			)
		)
		(pad "2" smd custom
			(at 0 0.4445 180)
			(size 0.1397 0.1397)
			(layers "F.Cu" "F.Mask" "F.Paste")
			(net "P12V_MOST7_GATE")
			(options
				(clearance outline)
				(anchor circle)
			)
			(primitives
				(gr_poly
					(pts
						(arc
							(start -0.1778 -0.2794)
							(mid -0.249642 -0.249642)
							(end -0.2794 -0.1778)
						)
						(arc
							(start -0.2794 0.1778)
							(mid -0.249642 0.249642)
							(end -0.1778 0.2794)
						)
						(arc
							(start 0.1778 0.2794)
							(mid 0.249642 0.249642)
							(end 0.2794 0.1778)
						)
						(arc
							(start 0.2794 -0.1778)
							(mid 0.249642 -0.249642)
							(end 0.1778 -0.2794)
						)
					)
					(width 0)
					(fill yes)
				)
			)
		)
	)
	(footprint ""
		(layer "F.Cu")
		(at 91.059 -24.511)
		(property "Reference" "U53"
			(at 0 0 0)
			(layer "F.SilkS")
			(hide yes)
			(effects
				(font
					(size 1.27 1.27)
				)
			)
		)
		(property "Value" "ADS1015IDGSR-GP"
			(at 0 -11.1252 0)
			(unlocked yes)
			(layer "F.Fab")
			(hide yes)
			(effects
				(font
					(size 1.016 1.016)
					(thickness 0.1524)
				)
			)
		)
		(property "Device Type" "MSOP10H44"
			(at 0 -12.6492 0)
			(unlocked yes)
			(layer "F.Fab")
			(hide yes)
			(effects
				(font
					(size 1.016 1.016)
					(thickness 0.1524)
				)
			)
		)
		(duplicate_pad_numbers_are_jumpers no)
		(fp_line
			(start -2.0066 -1.016)
			(end 1.143 -1.016)
			(stroke
				(width 0.1524)
				(type default)
			)
			(layer "F.SilkS")
		)
		(fp_line
			(start -2.0066 1.016)
			(end -2.0066 -1.016)
			(stroke
				(width 0.1524)
				(type default)
			)
			(layer "F.SilkS")
		)
		(fp_line
			(start -1.8288 1.016)
			(end -1.8288 3.048)
			(stroke
				(width 0.508)
				(type default)
			)
			(layer "F.SilkS")
		)
		(fp_line
			(start -1.5748 0)
			(end -1.9558 -0.381)
			(stroke
				(width 0.1524)
				(type default)
			)
			(layer "F.SilkS")
		)
		(fp_line
			(start -1.5748 0)
			(end -1.9558 0.381)
			(stroke
				(width 0.1524)
				(type default)
			)
			(layer "F.SilkS")
		)
		(fp_line
			(start 1.143 -1.016)
			(end 1.143 1.016)
			(stroke
				(width 0.1524)
				(type default)
			)
			(layer "F.SilkS")
		)
		(fp_line
			(start 1.143 1.016)
			(end -2.0066 1.016)
			(stroke
				(width 0.1524)
				(type default)
			)
			(layer "F.SilkS")
		)
		(fp_poly
			(pts
				(xy -2.0828 3.3401) (xy 2.0828 3.3401) (xy 2.0828 -3.3401) (xy -2.0828 -3.3401)
			)
			(stroke
				(width 0)
				(type default)
			)
			(fill no)
			(layer "F.CrtYd")
		)
		(fp_poly
			(pts
				(xy -2.0828 3.3401) (xy 2.0828 3.3401) (xy 2.0828 -3.3401) (xy -2.0828 -3.3401)
			)
			(stroke
				(width 0)
				(type default)
			)
			(fill no)
			(layer "F.Fab")
		)
		(pad "1" smd rect
			(at -0.99949 2.0701)
			(size 0.3048 1.524)
			(layers "F.Cu" "F.Mask" "F.Paste")
			(net "VOL_SEN_ADDR")
		)
		(pad "2" smd rect
			(at -0.50038 2.0701)
			(size 0.3048 1.524)
			(layers "F.Cu" "F.Mask" "F.Paste")
			(net "VOL_SEN_ALERT")
		)
		(pad "3" smd rect
			(at 0 2.0701)
			(size 0.3048 1.524)
			(layers "F.Cu" "F.Mask" "F.Paste")
			(net "GND")
		)
		(pad "4" smd rect
			(at 0.50038 2.0701)
			(size 0.3048 1.524)
			(layers "F.Cu" "F.Mask" "F.Paste")
			(net "P12V_SENSE")
		)
		(pad "5" smd rect
			(at 0.99949 2.0701)
			(size 0.3048 1.524)
			(layers "F.Cu" "F.Mask" "F.Paste")
			(net "P12V_SSD14_SENSE")
		)
		(pad "6" smd rect
			(at 0.99949 -2.0701)
			(size 0.3048 1.524)
			(layers "F.Cu" "F.Mask" "F.Paste")
			(net "P3V3_SENSE")
		)
		(pad "7" smd rect
			(at 0.50038 -2.0701)
			(size 0.3048 1.524)
			(layers "F.Cu" "F.Mask" "F.Paste")
			(net "Net_31")
		)
		(pad "8" smd rect
			(at 0 -2.0701)
			(size 0.3048 1.524)
			(layers "F.Cu" "F.Mask" "F.Paste")
			(net "P3V3")
		)
		(pad "9" smd rect
			(at -0.50038 -2.0701)
			(size 0.3048 1.524)
			(layers "F.Cu" "F.Mask" "F.Paste")
			(net "VOL_SEN_SDA")
		)
		(pad "10" smd rect
			(at -0.99949 -2.0701)
			(size 0.3048 1.524)
			(layers "F.Cu" "F.Mask" "F.Paste")
			(net "VOL_SEN_SCL")
		)
	)
	(footprint ""
		(layer "F.Cu")
		(at 226.149916 -376.670062 90)
		(property "Reference" "J1"
			(at 0 0 90)
			(layer "F.SilkS")
			(hide yes)
			(effects
				(font
					(size 1.27 1.27)
				)
			)
		)
		(property "Value" "PCISLT68-14-GP-U1"
			(at -22.225 12.7508 90)
			(unlocked yes)
			(layer "F.Fab")
			(hide yes)
			(effects
				(font
					(size 1.016 1.016)
					(thickness 0.1524)
				)
			)
		)
		(property "Device Type" "SD-78827-0001"
			(at -22.225 11.2268 90)
			(unlocked yes)
			(layer "F.Fab")
			(hide yes)
			(effects
				(font
					(size 1.016 1.016)
					(thickness 0.1524)
				)
			)
		)
		(duplicate_pad_numbers_are_jumpers no)
		(fp_line
			(start 20.4724 -3.4036)
			(end 20.4724 0.0254)
			(stroke
				(width 0.1524)
				(type default)
			)
			(layer "F.SilkS")
		)
		(fp_line
			(start -20.4724 -3.4036)
			(end 20.4724 -3.4036)
			(stroke
				(width 0.1524)
				(type default)
			)
			(layer "F.SilkS")
		)
		(fp_line
			(start 23.749 0.0254)
			(end 23.749 4.6736)
			(stroke
				(width 0.1524)
				(type default)
			)
			(layer "F.SilkS")
		)
		(fp_line
			(start 20.4724 0.0254)
			(end 23.749 0.0254)
			(stroke
				(width 0.1524)
				(type default)
			)
			(layer "F.SilkS")
		)
		(fp_line
			(start -20.4724 0.0254)
			(end -20.4724 -3.4036)
			(stroke
				(width 0.1524)
				(type default)
			)
			(layer "F.SilkS")
		)
		(fp_line
			(start -23.749 0.0254)
			(end -20.4724 0.0254)
			(stroke
				(width 0.1524)
				(type default)
			)
			(layer "F.SilkS")
		)
		(fp_line
			(start 23.117556 1.803908)
			(end 23.117556 2.896108)
			(stroke
				(width 0.3048)
				(type default)
			)
			(layer "F.SilkS")
		)
		(fp_line
			(start -20.882356 1.803908)
			(end -20.882356 2.896108)
			(stroke
				(width 0.3048)
				(type default)
			)
			(layer "F.SilkS")
		)
		(fp_line
			(start 20.882356 2.896108)
			(end 20.882356 1.803908)
			(stroke
				(width 0.3048)
				(type default)
			)
			(layer "F.SilkS")
		)
		(fp_line
			(start -23.117556 2.896108)
			(end -23.117556 1.803908)
			(stroke
				(width 0.3048)
				(type default)
			)
			(layer "F.SilkS")
		)
		(fp_line
			(start 23.749 4.6736)
			(end 20.4724 4.6736)
			(stroke
				(width 0.1524)
				(type default)
			)
			(layer "F.SilkS")
		)
		(fp_line
			(start 20.4724 4.6736)
			(end 20.4724 12.0142)
			(stroke
				(width 0.1524)
				(type default)
			)
			(layer "F.SilkS")
		)
		(fp_line
			(start -20.4724 4.6736)
			(end -23.749 4.6736)
			(stroke
				(width 0.1524)
				(type default)
			)
			(layer "F.SilkS")
		)
		(fp_line
			(start -23.749 4.6736)
			(end -23.749 0.0254)
			(stroke
				(width 0.1524)
				(type default)
			)
			(layer "F.SilkS")
		)
		(fp_line
			(start 17.8435 10.3124)
			(end -17.8435 10.3124)
			(stroke
				(width 0.1524)
				(type default)
			)
			(layer "F.SilkS")
		)
		(fp_line
			(start -17.8435 10.3124)
			(end -17.8435 12.0142)
			(stroke
				(width 0.1524)
				(type default)
			)
			(layer "F.SilkS")
		)
		(fp_line
			(start 20.4724 12.0142)
			(end 17.8435 12.0142)
			(stroke
				(width 0.1524)
				(type default)
			)
			(layer "F.SilkS")
		)
		(fp_line
			(start 17.8435 12.0142)
			(end 17.8435 10.3124)
			(stroke
				(width 0.1524)
				(type default)
			)
			(layer "F.SilkS")
		)
		(fp_line
			(start -17.8435 12.0142)
			(end -20.4724 12.0142)
			(stroke
				(width 0.1524)
				(type default)
			)
			(layer "F.SilkS")
		)
		(fp_line
			(start -20.4724 12.0142)
			(end -20.4724 4.6736)
			(stroke
				(width 0.1524)
				(type default)
			)
			(layer "F.SilkS")
		)
		(fp_arc
			(start 20.882356 1.803908)
			(mid 21.999956 0.686308)
			(end 23.117556 1.803908)
			(stroke
				(width 0.3048)
				(type default)
			)
			(layer "F.SilkS")
		)
		(fp_arc
			(start -23.117556 1.803908)
			(mid -21.999956 0.686308)
			(end -20.882356 1.803908)
			(stroke
				(width 0.3048)
				(type default)
			)
			(layer "F.SilkS")
		)
		(fp_arc
			(start 23.117556 2.896108)
			(mid 21.999956 4.013708)
			(end 20.882356 2.896108)
			(stroke
				(width 0.3048)
				(type default)
			)
			(layer "F.SilkS")
		)
		(fp_arc
			(start -20.882356 2.896108)
			(mid -21.999956 4.013708)
			(end -23.117556 2.896108)
			(stroke
				(width 0.3048)
				(type default)
			)
			(layer "F.SilkS")
		)
		(fp_poly
			(pts
				(xy -20.2184 11.7602) (xy -20.2184 4.4196) (xy -23.495 4.4196) (xy -23.495 0.2794) (xy -20.2184 0.2794)
				(xy -20.2184 -3.1496) (xy 20.2184 -3.1496) (xy 20.2184 0.2794) (xy 23.495 0.2794) (xy 23.495 4.4196)
				(xy 20.2184 4.4196) (xy 20.2184 11.7602) (xy 18.0975 11.7602) (xy 18.0975 10.0584) (xy -18.0975 10.0584)
				(xy -18.0975 11.7602)
			)
			(stroke
				(width 0)
				(type default)
			)
			(fill no)
			(layer "F.CrtYd")
		)
		(fp_poly
			(pts
				(xy -21.2471 16.256) (xy -21.2471 4.9276) (xy -24.003 4.9276) (xy -24.003 -0.2286) (xy -20.7264 -0.2286)
				(xy -20.7264 -3.6576) (xy 20.7264 -3.6576) (xy 20.7264 -0.2286) (xy 24.003 -0.2286) (xy 24.003 -0.00635)
				(xy 20.2184 -0.00635) (xy 20.2184 -3.1496) (xy -20.2184 -3.1496) (xy -20.2184 0.2794) (xy -23.495 0.2794)
				(xy -23.495 4.4196) (xy -20.2184 4.4196) (xy -20.2184 11.7602) (xy -18.0975 11.7602) (xy -18.0975 10.0584)
				(xy 18.0975 10.0584) (xy 18.0975 11.7602) (xy 20.2184 11.7602) (xy 20.2184 4.4196) (xy 23.495 4.4196)
				(xy 23.495 0.2794) (xy 20.2184 0.2794) (xy 20.2184 0.00635) (xy 24.003 0.00635) (xy 24.003 4.9276)
				(xy 21.2471 4.9276) (xy 21.2471 16.256)
			)
			(stroke
				(width 0)
				(type default)
			)
			(fill no)
			(layer "F.CrtYd")
		)
		(fp_poly
			(pts
				(xy -21.2471 16.256) (xy -21.2471 4.9276) (xy -24.003 4.9276) (xy -24.003 -0.2286) (xy -20.7264 -0.2286)
				(xy -20.7264 -3.6576) (xy 20.7264 -3.6576) (xy 20.7264 -0.2286) (xy 24.003 -0.2286) (xy 24.003 4.9276)
				(xy 21.2471 4.9276) (xy 21.2471 16.256)
			)
			(stroke
				(width 0)
				(type default)
			)
			(fill no)
			(layer "F.Fab")
		)
		(pad "" np_thru_hole circle
			(at -18.999962 0 90)
			(size 0.254 0.254)
			(drill 1.8542)
			(layers "*.Cu" "*.Mask")
			(clearance 1.1557)
			(thermal_gap 1.1557)
		)
		(pad "" np_thru_hole circle
			(at 18.999962 0 90)
			(size 0.254 0.254)
			(drill 1.8542)
			(layers "*.Cu" "*.Mask")
			(clearance 1.1557)
			(thermal_gap 1.1557)
		)
		(pad "E1" smd rect
			(at -7.079996 1.240028 90)
			(size 0.508 2.0066)
			(layers "F.Cu" "F.Mask" "F.Paste")
			(net "PE_CLK100M_DR1_2_P")
		)
		(pad "E2" smd rect
			(at -6.279896 1.240028 90)
			(size 0.508 2.0066)
			(layers "F.Cu" "F.Mask" "F.Paste")
			(net "PE_CLK100M_DR1_2_N")
		)
		(pad "E3" smd rect
			(at -5.48005 1.240028 90)
			(size 0.508 2.0066)
			(layers "F.Cu" "F.Mask" "F.Paste")
			(net "P3V3")
		)
		(pad "E4" smd rect
			(at -4.67995 1.240028 90)
			(size 0.508 2.0066)
			(layers "F.Cu" "F.Mask" "F.Paste")
			(net "SSD1_PERST_N")
		)
		(pad "E5" smd rect
			(at -3.880104 1.240028 90)
			(size 0.508 2.0066)
			(layers "F.Cu" "F.Mask" "F.Paste")
			(net "SSD1_PERST_N")
		)
		(pad "E6" smd rect
			(at -3.080004 1.240028 90)
			(size 0.508 2.0066)
			(layers "F.Cu" "F.Mask" "F.Paste")
			(net "Net_1305")
		)
		(pad "E7" smd rect
			(at -15.48003 -1.949958 90)
			(size 0.508 2.0066)
			(layers "F.Cu" "F.Mask" "F.Paste")
			(net "PE_CLK100M_DR1_1_P")
		)
		(pad "E8" smd rect
			(at -14.67993 -1.949958 90)
			(size 0.508 2.0066)
			(layers "F.Cu" "F.Mask" "F.Paste")
			(net "PE_CLK100M_DR1_1_N")
		)
		(pad "E9" smd rect
			(at -13.880084 -1.949958 90)
			(size 0.508 2.0066)
			(layers "F.Cu" "F.Mask" "F.Paste")
			(net "GND")
		)
		(pad "E10" smd rect
			(at -13.079984 -1.949958 90)
			(size 0.508 2.0066)
			(layers "F.Cu" "F.Mask" "F.Paste")
			(net "PE_TX1_DR1_N")
		)
		(pad "E11" smd rect
			(at -12.279884 -1.949958 90)
			(size 0.508 2.0066)
			(layers "F.Cu" "F.Mask" "F.Paste")
			(net "PE_TX1_DR1_P")
		)
		(pad "E12" smd rect
			(at -11.480038 -1.949958 90)
			(size 0.508 2.0066)
			(layers "F.Cu" "F.Mask" "F.Paste")
			(net "GND")
		)
		(pad "E13" smd rect
			(at -10.679938 -1.949958 90)
			(size 0.508 2.0066)
			(layers "F.Cu" "F.Mask" "F.Paste")
			(net "PE_RX1_DR1_N")
		)
		(pad "E14" smd rect
			(at -9.880092 -1.949958 90)
			(size 0.508 2.0066)
			(layers "F.Cu" "F.Mask" "F.Paste")
			(net "PE_RX1_DR1_P")
		)
		(pad "E15" smd rect
			(at -9.079992 -1.949958 90)
			(size 0.508 2.0066)
			(layers "F.Cu" "F.Mask" "F.Paste")
			(net "GND")
		)
		(pad "E16" smd rect
			(at -8.279892 -1.949958 90)
			(size 0.508 2.0066)
			(layers "F.Cu" "F.Mask" "F.Paste")
			(net "Net_1312")
		)
		(pad "E17" smd rect
			(at 9.320022 -1.949958 90)
			(size 0.508 2.0066)
			(layers "F.Cu" "F.Mask" "F.Paste")
			(net "PE_TX4_DR1_N")
		)
		(pad "E18" smd rect
			(at 10.120122 -1.949958 90)
			(size 0.508 2.0066)
			(layers "F.Cu" "F.Mask" "F.Paste")
			(net "PE_TX4_DR1_P")
		)
		(pad "E19" smd rect
			(at 10.919968 -1.949958 90)
			(size 0.508 2.0066)
			(layers "F.Cu" "F.Mask" "F.Paste")
			(net "GND")
		)
		(pad "E20" smd rect
			(at 11.720068 -1.949958 90)
			(size 0.508 2.0066)
			(layers "F.Cu" "F.Mask" "F.Paste")
			(net "PE_RX4_DR1_N")
		)
		(pad "E21" smd rect
			(at 12.519914 -1.949958 90)
			(size 0.508 2.0066)
			(layers "F.Cu" "F.Mask" "F.Paste")
			(net "PE_RX4_DR1_P")
		)
		(pad "E22" smd rect
			(at 13.320014 -1.949958 90)
			(size 0.508 2.0066)
			(layers "F.Cu" "F.Mask" "F.Paste")
			(net "GND")
		)
		(pad "E23" smd rect
			(at 14.120114 -1.949958 90)
			(size 0.508 2.0066)
			(layers "F.Cu" "F.Mask" "F.Paste")
			(net "SCL_DR1_R")
		)
		(pad "E24" smd rect
			(at 14.91996 -1.949958 90)
			(size 0.508 2.0066)
			(layers "F.Cu" "F.Mask" "F.Paste")
			(net "SDA_DR1_R")
		)
		(pad "E25" smd rect
			(at 15.72006 -1.949958 90)
			(size 0.508 2.0066)
			(layers "F.Cu" "F.Mask" "F.Paste")
			(net "DUALPORTEN#1")
		)
		(pad "P1" smd rect
			(at -1.905 0.824992 90)
			(size 0.6604 2.0574)
			(layers "F.Cu" "F.Mask" "F.Paste")
			(net "Net_1308")
		)
		(pad "P2" smd rect
			(at -0.635 0.824992 90)
			(size 0.6604 2.0574)
			(layers "F.Cu" "F.Mask" "F.Paste")
			(net "Net_1307")
		)
		(pad "P3" smd rect
			(at 0.635 0.824992 90)
			(size 0.6604 2.0574)
			(layers "F.Cu" "F.Mask" "F.Paste")
			(net "Net_1306")
		)
		(pad "P4" smd rect
			(at 1.905 0.824992 90)
			(size 0.6604 2.0574)
			(layers "F.Cu" "F.Mask" "F.Paste")
			(net "SSD1_CLK0_OE_N")
		)
		(pad "P5" smd rect
			(at 3.175 0.824992 90)
			(size 0.6604 2.0574)
			(layers "F.Cu" "F.Mask" "F.Paste")
			(net "GND")
		)
		(pad "P6" smd rect
			(at 4.445 0.824992 90)
			(size 0.6604 2.0574)
			(layers "F.Cu" "F.Mask" "F.Paste")
			(net "GND")
		)
		(pad "P7" smd rect
			(at 5.715 0.824992 90)
			(size 0.6604 2.0574)
			(layers "F.Cu" "F.Mask" "F.Paste")
			(net "Net_94")
		)
		(pad "P8" smd rect
			(at 6.985 0.824992 90)
			(size 0.6604 2.0574)
			(layers "F.Cu" "F.Mask" "F.Paste")
			(net "Net_66")
		)
		(pad "P9" smd rect
			(at 8.255 0.824992 90)
			(size 0.6604 2.0574)
			(layers "F.Cu" "F.Mask" "F.Paste")
			(net "Net_80")
		)
		(pad "P10" smd rect
			(at 9.525 0.824992 90)
			(size 0.6604 2.0574)
			(layers "F.Cu" "F.Mask" "F.Paste")
			(net "SSD_PRSNT_NET1")
		)
		(pad "P11" smd rect
			(at 10.795 0.824992 90)
			(size 0.6604 2.0574)
			(layers "F.Cu" "F.Mask" "F.Paste")
			(net "SSD_ACT_DR1")
		)
		(pad "P12" smd rect
			(at 12.065 0.824992 90)
			(size 0.6604 2.0574)
			(layers "F.Cu" "F.Mask" "F.Paste")
			(net "GND")
		)
		(pad "P13" smd rect
			(at 13.335 0.824992 90)
			(size 0.6604 2.0574)
			(layers "F.Cu" "F.Mask" "F.Paste")
			(net "12V_PRECH_SSD1")
		)
		(pad "P14" smd rect
			(at 14.605 0.824992 90)
			(size 0.6604 2.0574)
			(layers "F.Cu" "F.Mask" "F.Paste")
			(net "P12V_SSD1")
		)
		(pad "P15" smd rect
			(at 15.875 0.824992 90)
			(size 0.6604 2.0574)
			(layers "F.Cu" "F.Mask" "F.Paste")
			(net "P12V_SSD1")
		)
		(pad "PTH1" thru_hole oval
			(at -21.999956 2.350008 90)
			(size 1.524 2.6162)
			(drill oval 0.8128 1.905)
			(layers "*.Cu" "*.Mask")
			(remove_unused_layers no)
			(net "Net_1317")
			(clearance 0.1524)
			(thermal_gap 0.1524)
		)
		(pad "PTH2" thru_hole oval
			(at 21.999956 2.350008 90)
			(size 1.524 2.6162)
			(drill oval 0.8128 1.905)
			(layers "*.Cu" "*.Mask")
			(remove_unused_layers no)
			(net "Net_1301")
			(clearance 0.1524)
			(thermal_gap 0.1524)
		)
		(pad "S1" smd rect
			(at -15.875 0.824992 90)
			(size 0.6604 2.0574)
			(layers "F.Cu" "F.Mask" "F.Paste")
			(net "GND")
		)
		(pad "S2" smd rect
			(at -14.605 0.824992 90)
			(size 0.6604 2.0574)
			(layers "F.Cu" "F.Mask" "F.Paste")
			(net "Net_1316")
		)
		(pad "S3" smd rect
			(at -13.335 0.824992 90)
			(size 0.6604 2.0574)
			(layers "F.Cu" "F.Mask" "F.Paste")
			(net "Net_1315")
		)
		(pad "S4" smd rect
			(at -12.065 0.824992 90)
			(size 0.6604 2.0574)
			(layers "F.Cu" "F.Mask" "F.Paste")
			(net "GND")
		)
		(pad "S5" smd rect
			(at -10.795 0.824992 90)
			(size 0.6604 2.0574)
			(layers "F.Cu" "F.Mask" "F.Paste")
			(net "Net_1314")
		)
		(pad "S6" smd rect
			(at -9.525 0.824992 90)
			(size 0.6604 2.0574)
			(layers "F.Cu" "F.Mask" "F.Paste")
			(net "Net_1313")
		)
		(pad "S7" smd rect
			(at -8.255 0.824992 90)
			(size 0.6604 2.0574)
			(layers "F.Cu" "F.Mask" "F.Paste")
			(net "GND")
		)
		(pad "S8" smd rect
			(at -7.480046 -1.949958 90)
			(size 0.508 2.0066)
			(layers "F.Cu" "F.Mask" "F.Paste")
			(net "GND")
		)
		(pad "S9" smd rect
			(at -6.679946 -1.949958 90)
			(size 0.508 2.0066)
			(layers "F.Cu" "F.Mask" "F.Paste")
			(net "Net_1311")
		)
		(pad "S10" smd rect
			(at -5.8801 -1.949958 90)
			(size 0.508 2.0066)
			(layers "F.Cu" "F.Mask" "F.Paste")
			(net "Net_1310")
		)
		(pad "S11" smd rect
			(at -5.08 -1.949958 90)
			(size 0.508 2.0066)
			(layers "F.Cu" "F.Mask" "F.Paste")
			(net "GND")
		)
		(pad "S12" smd rect
			(at -4.2799 -1.949958 90)
			(size 0.508 2.0066)
			(layers "F.Cu" "F.Mask" "F.Paste")
			(net "Net_1309")
		)
		(pad "S13" smd rect
			(at -3.480054 -1.949958 90)
			(size 0.508 2.0066)
			(layers "F.Cu" "F.Mask" "F.Paste")
			(net "Net_1304")
		)
		(pad "S14" smd rect
			(at -2.679954 -1.949958 90)
			(size 0.508 2.0066)
			(layers "F.Cu" "F.Mask" "F.Paste")
			(net "GND")
		)
		(pad "S15" smd rect
			(at -1.880108 -1.949958 90)
			(size 0.508 2.0066)
			(layers "F.Cu" "F.Mask" "F.Paste")
			(net "Net_1303")
		)
		(pad "S16" smd rect
			(at -1.080008 -1.949958 90)
			(size 0.508 2.0066)
			(layers "F.Cu" "F.Mask" "F.Paste")
			(net "GND")
		)
		(pad "S17" smd rect
			(at -0.279908 -1.949958 90)
			(size 0.508 2.0066)
			(layers "F.Cu" "F.Mask" "F.Paste")
			(net "PE_TX2_DR1_N")
		)
		(pad "S18" smd rect
			(at 0.519938 -1.949958 90)
			(size 0.508 2.0066)
			(layers "F.Cu" "F.Mask" "F.Paste")
			(net "PE_TX2_DR1_P")
		)
		(pad "S19" smd rect
			(at 1.320038 -1.949958 90)
			(size 0.508 2.0066)
			(layers "F.Cu" "F.Mask" "F.Paste")
			(net "GND")
		)
		(pad "S20" smd rect
			(at 2.119884 -1.949958 90)
			(size 0.508 2.0066)
			(layers "F.Cu" "F.Mask" "F.Paste")
			(net "PE_RX2_DR1_N")
		)
		(pad "S21" smd rect
			(at 2.919984 -1.949958 90)
			(size 0.508 2.0066)
			(layers "F.Cu" "F.Mask" "F.Paste")
			(net "PE_RX2_DR1_P")
		)
		(pad "S22" smd rect
			(at 3.720084 -1.949958 90)
			(size 0.508 2.0066)
			(layers "F.Cu" "F.Mask" "F.Paste")
			(net "GND")
		)
		(pad "S23" smd rect
			(at 4.51993 -1.949958 90)
			(size 0.508 2.0066)
			(layers "F.Cu" "F.Mask" "F.Paste")
			(net "PE_TX3_DR1_N")
		)
		(pad "S24" smd rect
			(at 5.32003 -1.949958 90)
			(size 0.508 2.0066)
			(layers "F.Cu" "F.Mask" "F.Paste")
			(net "PE_TX3_DR1_P")
		)
		(pad "S25" smd rect
			(at 6.119876 -1.949958 90)
			(size 0.508 2.0066)
			(layers "F.Cu" "F.Mask" "F.Paste")
			(net "GND")
		)
		(pad "S26" smd rect
			(at 6.919976 -1.949958 90)
			(size 0.508 2.0066)
			(layers "F.Cu" "F.Mask" "F.Paste")
			(net "PE_RX3_DR1_N")
		)
		(pad "S27" smd rect
			(at 7.720076 -1.949958 90)
			(size 0.508 2.0066)
			(layers "F.Cu" "F.Mask" "F.Paste")
			(net "PE_RX3_DR1_P")
		)
		(pad "S28" smd rect
			(at 8.519922 -1.949958 90)
			(size 0.508 2.0066)
			(layers "F.Cu" "F.Mask" "F.Paste")
			(net "GND")
		)
		(zone
			(layers "F.Cu" "B.Cu" "In1.Cu" "In2.Cu" "In3.Cu" "In4.Cu" "In5.Cu" "In6.Cu")
			(hatch none 0.5)
			(connect_pads
				(clearance 0)
			)
			(min_thickness 0.25)
			(keepout
				(tracks not_allowed)
				(vias allowed)
				(pads allowed)
				(copperpour not_allowed)
				(footprints allowed)
			)
			(placement
				(enabled no)
				(sheetname "")
			)
			(fill
				(thermal_gap 0.5)
				(thermal_bridge_width 0.5)
				(island_removal_mode 0)
			)
			(polygon
				(pts
					(arc
						(start 227.381816 -395.670024)
						(mid 224.918016 -395.670024)
						(end 227.381816 -395.670024)
					)
				)
			)
		)
		(zone
			(layers "F.Cu" "B.Cu" "In1.Cu" "In2.Cu" "In3.Cu" "In4.Cu" "In5.Cu" "In6.Cu")
			(hatch none 0.5)
			(connect_pads
				(clearance 0)
			)
			(min_thickness 0.25)
			(keepout
				(tracks not_allowed)
				(vias allowed)
				(pads allowed)
				(copperpour not_allowed)
				(footprints allowed)
			)
			(placement
				(enabled no)
				(sheetname "")
			)
			(fill
				(thermal_gap 0.5)
				(thermal_bridge_width 0.5)
				(island_removal_mode 0)
			)
			(polygon
				(pts
					(arc
						(start 227.381816 -357.6701)
						(mid 224.918016 -357.6701)
						(end 227.381816 -357.6701)
					)
				)
			)
		)
	)
	(footprint ""
		(layer "F.Cu")
		(at 200.873106 -492.634778 -90)
		(property "Reference" "R137"
			(at 0 0 270)
			(layer "F.SilkS")
			(hide yes)
			(effects
				(font
					(size 1.27 1.27)
				)
			)
		)
		(property "Value" "4K7R2J-2-GP"
			(at 0.064008 -3.993896 270)
			(unlocked yes)
			(layer "F.Fab")
			(hide yes)
			(effects
				(font
					(size 1.016 1.016)
					(thickness 0.1524)
				)
			)
		)
		(property "Device Type" "R402H16"
			(at 0.064008 -5.517896 270)
			(unlocked yes)
			(layer "F.Fab")
			(hide yes)
			(effects
				(font
					(size 1.016 1.016)
					(thickness 0.1524)
				)
			)
		)
		(duplicate_pad_numbers_are_jumpers no)
		(fp_line
			(start -0.508 -0.9398)
			(end -0.508 0.9398)
			(stroke
				(width 0.1524)
				(type default)
			)
			(layer "F.SilkS")
		)
		(fp_line
			(start 0.508 -0.9398)
			(end -0.508 -0.9398)
			(stroke
				(width 0.1524)
				(type default)
			)
			(layer "F.SilkS")
		)
		(fp_poly
			(pts
				(xy -0.508 0.9398) (xy 0.508 0.9398) (xy 0.508 -0.9398) (xy -0.508 -0.9398)
			)
			(stroke
				(width 0)
				(type default)
			)
			(fill no)
			(layer "F.CrtYd")
		)
		(fp_rect
			(start -0.508 0.9398)
			(end 0.508 -0.9398)
			(stroke
				(width 0)
				(type default)
			)
			(fill no)
			(layer "F.Fab")
		)
		(pad "1" smd custom
			(at 0 -0.4445 270)
			(size 0.1397 0.1397)
			(layers "F.Cu" "F.Mask" "F.Paste")
			(net "P12V")
			(options
				(clearance outline)
				(anchor circle)
			)
			(primitives
				(gr_poly
					(pts
						(arc
							(start -0.1778 -0.2794)
							(mid -0.249642 -0.249642)
							(end -0.2794 -0.1778)
						)
						(arc
							(start -0.2794 0.1778)
							(mid -0.249642 0.249642)
							(end -0.1778 0.2794)
						)
						(arc
							(start 0.1778 0.2794)
							(mid 0.249642 0.249642)
							(end 0.2794 0.1778)
						)
						(arc
							(start 0.2794 -0.1778)
							(mid 0.249642 -0.249642)
							(end 0.1778 -0.2794)
						)
					)
					(width 0)
					(fill yes)
				)
			)
		)
		(pad "2" smd custom
			(at 0 0.4445 270)
			(size 0.1397 0.1397)
			(layers "F.Cu" "F.Mask" "F.Paste")
			(net "SW_SSD0_R")
			(options
				(clearance outline)
				(anchor circle)
			)
			(primitives
				(gr_poly
					(pts
						(arc
							(start -0.1778 -0.2794)
							(mid -0.249642 -0.249642)
							(end -0.2794 -0.1778)
						)
						(arc
							(start -0.2794 0.1778)
							(mid -0.249642 0.249642)
							(end -0.1778 0.2794)
						)
						(arc
							(start 0.1778 0.2794)
							(mid 0.249642 0.249642)
							(end 0.2794 0.1778)
						)
						(arc
							(start 0.2794 -0.1778)
							(mid 0.249642 -0.249642)
							(end 0.1778 -0.2794)
						)
					)
					(width 0)
					(fill yes)
				)
			)
		)
	)
	(footprint ""
		(layer "F.Cu")
		(at 18.5674 -473.3036)
		(property "Reference" "Q79"
			(at 0 0 0)
			(layer "F.SilkS")
			(hide yes)
			(effects
				(font
					(size 1.27 1.27)
				)
			)
		)
		(property "Value" "2N7002A-7-GP"
			(at 0.127 -8.9662 0)
			(unlocked yes)
			(layer "F.Fab")
			(hide yes)
			(effects
				(font
					(size 1.016 1.016)
					(thickness 0.1524)
				)
			)
		)
		(property "Device Type" "SOT23DGS2D4H48"
			(at 0.127 -10.4902 0)
			(unlocked yes)
			(layer "F.Fab")
			(hide yes)
			(effects
				(font
					(size 1.016 1.016)
					(thickness 0.1524)
				)
			)
		)
		(duplicate_pad_numbers_are_jumpers no)
		(fp_line
			(start -1.651 -1.778)
			(end -1.651 1.778)
			(stroke
				(width 0.1524)
				(type default)
			)
			(layer "F.SilkS")
		)
		(fp_line
			(start -1.651 1.778)
			(end 1.651 1.778)
			(stroke
				(width 0.1524)
				(type default)
			)
			(layer "F.SilkS")
		)
		(fp_line
			(start 1.651 -1.778)
			(end -1.651 -1.778)
			(stroke
				(width 0.1524)
				(type default)
			)
			(layer "F.SilkS")
		)
		(fp_line
			(start 1.651 1.778)
			(end 1.651 -1.778)
			(stroke
				(width 0.1524)
				(type default)
			)
			(layer "F.SilkS")
		)
		(fp_poly
			(pts
				(xy -1.778 1.8796) (xy -1.778 -1.8796) (xy 1.778 -1.8796) (xy 1.778 1.8796)
			)
			(stroke
				(width 0)
				(type default)
			)
			(fill no)
			(layer "F.CrtYd")
		)
		(fp_poly
			(pts
				(xy -1.778 1.8796) (xy -1.778 -1.8796) (xy 1.778 -1.8796) (xy 1.778 1.8796)
			)
			(stroke
				(width 0)
				(type default)
			)
			(fill no)
			(layer "F.Fab")
		)
		(pad "D" smd custom
			(at 0 -0.9525)
			(size 0.1905 0.1905)
			(layers "F.Cu" "F.Mask" "F.Paste")
			(net "SSD10_CLK0_OE_MOS_N")
			(options
				(clearance outline)
				(anchor circle)
			)
			(primitives
				(gr_poly
					(pts
						(arc
							(start -0.1778 0.5715)
							(mid -0.321484 0.511984)
							(end -0.381 0.3683)
						)
						(arc
							(start -0.381 -0.3683)
							(mid -0.321484 -0.511984)
							(end -0.1778 -0.5715)
						)
						(arc
							(start 0.1778 -0.5715)
							(mid 0.321484 -0.511984)
							(end 0.381 -0.3683)
						)
						(arc
							(start 0.381 0.3683)
							(mid 0.321484 0.511984)
							(end 0.1778 0.5715)
						)
					)
					(width 0)
					(fill yes)
				)
			)
		)
		(pad "G" smd custom
			(at -0.98425 0.9525)
			(size 0.1905 0.1905)
			(layers "F.Cu" "F.Mask" "F.Paste")
			(net "SSD10_CLK0_OE_R_N")
			(options
				(clearance outline)
				(anchor circle)
			)
			(primitives
				(gr_poly
					(pts
						(arc
							(start -0.1778 0.5715)
							(mid -0.321484 0.511984)
							(end -0.381 0.3683)
						)
						(arc
							(start -0.381 -0.3683)
							(mid -0.321484 -0.511984)
							(end -0.1778 -0.5715)
						)
						(arc
							(start 0.1778 -0.5715)
							(mid 0.321484 -0.511984)
							(end 0.381 -0.3683)
						)
						(arc
							(start 0.381 0.3683)
							(mid 0.321484 0.511984)
							(end 0.1778 0.5715)
						)
					)
					(width 0)
					(fill yes)
				)
			)
		)
		(pad "S" smd custom
			(at 0.98425 0.9525)
			(size 0.1905 0.1905)
			(layers "F.Cu" "F.Mask" "F.Paste")
			(net "GND")
			(options
				(clearance outline)
				(anchor circle)
			)
			(primitives
				(gr_poly
					(pts
						(arc
							(start -0.1778 0.5715)
							(mid -0.321484 0.511984)
							(end -0.381 0.3683)
						)
						(arc
							(start -0.381 -0.3683)
							(mid -0.321484 -0.511984)
							(end -0.1778 -0.5715)
						)
						(arc
							(start 0.1778 -0.5715)
							(mid 0.321484 -0.511984)
							(end 0.381 -0.3683)
						)
						(arc
							(start 0.381 0.3683)
							(mid 0.321484 0.511984)
							(end 0.1778 0.5715)
						)
					)
					(width 0)
					(fill yes)
				)
			)
		)
	)
	(footprint ""
		(layer "F.Cu")
		(at 31.369 -94.9706 -90)
		(property "Reference" "Q72"
			(at 0 0 270)
			(layer "F.SilkS")
			(hide yes)
			(effects
				(font
					(size 1.27 1.27)
				)
			)
		)
		(property "Value" "2N7002A-7-GP"
			(at 0.127 -8.9662 270)
			(unlocked yes)
			(layer "F.Fab")
			(hide yes)
			(effects
				(font
					(size 1.016 1.016)
					(thickness 0.1524)
				)
			)
		)
		(property "Device Type" "SOT23DGS2D4H48"
			(at 0.127 -10.4902 270)
			(unlocked yes)
			(layer "F.Fab")
			(hide yes)
			(effects
				(font
					(size 1.016 1.016)
					(thickness 0.1524)
				)
			)
		)
		(duplicate_pad_numbers_are_jumpers no)
		(fp_line
			(start -1.651 1.778)
			(end 1.651 1.778)
			(stroke
				(width 0.1524)
				(type default)
			)
			(layer "F.SilkS")
		)
		(fp_line
			(start 1.651 1.778)
			(end 1.651 -1.778)
			(stroke
				(width 0.1524)
				(type default)
			)
			(layer "F.SilkS")
		)
		(fp_line
			(start -1.651 -1.778)
			(end -1.651 1.778)
			(stroke
				(width 0.1524)
				(type default)
			)
			(layer "F.SilkS")
		)
		(fp_line
			(start 1.651 -1.778)
			(end -1.651 -1.778)
			(stroke
				(width 0.1524)
				(type default)
			)
			(layer "F.SilkS")
		)
		(fp_poly
			(pts
				(xy -1.778 1.8796) (xy -1.778 -1.8796) (xy 1.778 -1.8796) (xy 1.778 1.8796)
			)
			(stroke
				(width 0)
				(type default)
			)
			(fill no)
			(layer "F.CrtYd")
		)
		(fp_poly
			(pts
				(xy -1.778 1.8796) (xy -1.778 -1.8796) (xy 1.778 -1.8796) (xy 1.778 1.8796)
			)
			(stroke
				(width 0)
				(type default)
			)
			(fill no)
			(layer "F.Fab")
		)
		(pad "D" smd custom
			(at 0 -0.9525 270)
			(size 0.1905 0.1905)
			(layers "F.Cu" "F.Mask" "F.Paste")
			(net "P12V_MOST9_GATE_D")
			(options
				(clearance outline)
				(anchor circle)
			)
			(primitives
				(gr_poly
					(pts
						(arc
							(start -0.1778 0.5715)
							(mid -0.321484 0.511984)
							(end -0.381 0.3683)
						)
						(arc
							(start -0.381 -0.3683)
							(mid -0.321484 -0.511984)
							(end -0.1778 -0.5715)
						)
						(arc
							(start 0.1778 -0.5715)
							(mid 0.321484 -0.511984)
							(end 0.381 -0.3683)
						)
						(arc
							(start 0.381 0.3683)
							(mid 0.321484 0.511984)
							(end 0.1778 0.5715)
						)
					)
					(width 0)
					(fill yes)
				)
			)
		)
		(pad "G" smd custom
			(at -0.98425 0.9525 270)
			(size 0.1905 0.1905)
			(layers "F.Cu" "F.Mask" "F.Paste")
			(net "P12V_MOST9_GATE")
			(options
				(clearance outline)
				(anchor circle)
			)
			(primitives
				(gr_poly
					(pts
						(arc
							(start -0.1778 0.5715)
							(mid -0.321484 0.511984)
							(end -0.381 0.3683)
						)
						(arc
							(start -0.381 -0.3683)
							(mid -0.321484 -0.511984)
							(end -0.1778 -0.5715)
						)
						(arc
							(start 0.1778 -0.5715)
							(mid 0.321484 -0.511984)
							(end 0.381 -0.3683)
						)
						(arc
							(start 0.381 0.3683)
							(mid 0.321484 0.511984)
							(end 0.1778 0.5715)
						)
					)
					(width 0)
					(fill yes)
				)
			)
		)
		(pad "S" smd custom
			(at 0.98425 0.9525 270)
			(size 0.1905 0.1905)
			(layers "F.Cu" "F.Mask" "F.Paste")
			(net "GND")
			(options
				(clearance outline)
				(anchor circle)
			)
			(primitives
				(gr_poly
					(pts
						(arc
							(start -0.1778 0.5715)
							(mid -0.321484 0.511984)
							(end -0.381 0.3683)
						)
						(arc
							(start -0.381 -0.3683)
							(mid -0.321484 -0.511984)
							(end -0.1778 -0.5715)
						)
						(arc
							(start 0.1778 -0.5715)
							(mid 0.321484 -0.511984)
							(end 0.381 -0.3683)
						)
						(arc
							(start 0.381 0.3683)
							(mid 0.321484 0.511984)
							(end 0.1778 0.5715)
						)
					)
					(width 0)
					(fill yes)
				)
			)
		)
	)
	(footprint ""
		(layer "F.Cu")
		(at 29.718 -421.513)
		(property "Reference" "SR1112"
			(at 0 0 0)
			(layer "F.SilkS")
			(hide yes)
			(effects
				(font
					(size 1.27 1.27)
				)
			)
		)
		(property "Value" "4K7R2F-GP"
			(at 0.064008 -3.993896 0)
			(unlocked yes)
			(layer "F.Fab")
			(hide yes)
			(effects
				(font
					(size 1.016 1.016)
					(thickness 0.1524)
				)
			)
		)
		(property "Device Type" "R402H16"
			(at 0.064008 -5.517896 0)
			(unlocked yes)
			(layer "F.Fab")
			(hide yes)
			(effects
				(font
					(size 1.016 1.016)
					(thickness 0.1524)
				)
			)
		)
		(duplicate_pad_numbers_are_jumpers no)
		(fp_line
			(start -0.508 -0.9398)
			(end -0.508 0.9398)
			(stroke
				(width 0.1524)
				(type default)
			)
			(layer "F.SilkS")
		)
		(fp_line
			(start 0.508 -0.9398)
			(end -0.508 -0.9398)
			(stroke
				(width 0.1524)
				(type default)
			)
			(layer "F.SilkS")
		)
		(fp_rect
			(start -0.508 0.9398)
			(end 0.508 -0.9398)
			(stroke
				(width 0)
				(type default)
			)
			(fill no)
			(layer "F.CrtYd")
		)
		(fp_rect
			(start -0.508 0.9398)
			(end 0.508 -0.9398)
			(stroke
				(width 0)
				(type default)
			)
			(fill no)
			(layer "F.Fab")
		)
		(pad "1" smd custom
			(at 0 -0.4445)
			(size 0.1397 0.1397)
			(layers "F.Cu" "F.Mask" "F.Paste")
			(net "DUALPORTEN#10")
			(options
				(clearance outline)
				(anchor circle)
			)
			(primitives
				(gr_poly
					(pts
						(arc
							(start -0.1778 -0.2794)
							(mid -0.249642 -0.249642)
							(end -0.2794 -0.1778)
						)
						(arc
							(start -0.2794 0.1778)
							(mid -0.249642 0.249642)
							(end -0.1778 0.2794)
						)
						(arc
							(start 0.1778 0.2794)
							(mid 0.249642 0.249642)
							(end 0.2794 0.1778)
						)
						(arc
							(start 0.2794 -0.1778)
							(mid 0.249642 -0.249642)
							(end 0.1778 -0.2794)
						)
					)
					(width 0)
					(fill yes)
				)
			)
		)
		(pad "2" smd custom
			(at 0 0.4445)
			(size 0.1397 0.1397)
			(layers "F.Cu" "F.Mask" "F.Paste")
			(net "GND")
			(options
				(clearance outline)
				(anchor circle)
			)
			(primitives
				(gr_poly
					(pts
						(arc
							(start -0.1778 -0.2794)
							(mid -0.249642 -0.249642)
							(end -0.2794 -0.1778)
						)
						(arc
							(start -0.2794 0.1778)
							(mid -0.249642 0.249642)
							(end -0.1778 0.2794)
						)
						(arc
							(start 0.1778 0.2794)
							(mid 0.249642 0.249642)
							(end 0.2794 0.1778)
						)
						(arc
							(start 0.2794 -0.1778)
							(mid 0.249642 -0.249642)
							(end 0.1778 -0.2794)
						)
					)
					(width 0)
					(fill yes)
				)
			)
		)
	)
	(footprint ""
		(layer "F.Cu")
		(at 35.687 -347.48089)
		(property "Reference" "Q60"
			(at 0 0 0)
			(layer "F.SilkS")
			(hide yes)
			(effects
				(font
					(size 1.27 1.27)
				)
			)
		)
		(property "Value" "2N7002A-7-GP"
			(at 0.127 -8.9662 0)
			(unlocked yes)
			(layer "F.Fab")
			(hide yes)
			(effects
				(font
					(size 1.016 1.016)
					(thickness 0.1524)
				)
			)
		)
		(property "Device Type" "SOT23DGS2D4H48"
			(at 0.127 -10.4902 0)
			(unlocked yes)
			(layer "F.Fab")
			(hide yes)
			(effects
				(font
					(size 1.016 1.016)
					(thickness 0.1524)
				)
			)
		)
		(duplicate_pad_numbers_are_jumpers no)
		(fp_line
			(start -1.651 -1.778)
			(end -1.651 1.778)
			(stroke
				(width 0.1524)
				(type default)
			)
			(layer "F.SilkS")
		)
		(fp_line
			(start -1.651 1.778)
			(end 1.651 1.778)
			(stroke
				(width 0.1524)
				(type default)
			)
			(layer "F.SilkS")
		)
		(fp_line
			(start 1.651 -1.778)
			(end -1.651 -1.778)
			(stroke
				(width 0.1524)
				(type default)
			)
			(layer "F.SilkS")
		)
		(fp_line
			(start 1.651 1.778)
			(end 1.651 -1.778)
			(stroke
				(width 0.1524)
				(type default)
			)
			(layer "F.SilkS")
		)
		(fp_poly
			(pts
				(xy -1.778 1.8796) (xy -1.778 -1.8796) (xy 1.778 -1.8796) (xy 1.778 1.8796)
			)
			(stroke
				(width 0)
				(type default)
			)
			(fill no)
			(layer "F.CrtYd")
		)
		(fp_poly
			(pts
				(xy -1.778 1.8796) (xy -1.778 -1.8796) (xy 1.778 -1.8796) (xy 1.778 1.8796)
			)
			(stroke
				(width 0)
				(type default)
			)
			(fill no)
			(layer "F.Fab")
		)
		(pad "D" smd custom
			(at 0 -0.9525)
			(size 0.1905 0.1905)
			(layers "F.Cu" "F.Mask" "F.Paste")
			(net "ATTN_LED_DR6_MOS_N")
			(options
				(clearance outline)
				(anchor circle)
			)
			(primitives
				(gr_poly
					(pts
						(arc
							(start -0.1778 0.5715)
							(mid -0.321484 0.511984)
							(end -0.381 0.3683)
						)
						(arc
							(start -0.381 -0.3683)
							(mid -0.321484 -0.511984)
							(end -0.1778 -0.5715)
						)
						(arc
							(start 0.1778 -0.5715)
							(mid 0.321484 -0.511984)
							(end 0.381 -0.3683)
						)
						(arc
							(start 0.381 0.3683)
							(mid 0.321484 0.511984)
							(end 0.1778 0.5715)
						)
					)
					(width 0)
					(fill yes)
				)
			)
		)
		(pad "G" smd custom
			(at -0.98425 0.9525)
			(size 0.1905 0.1905)
			(layers "F.Cu" "F.Mask" "F.Paste")
			(net "SSD6_CLK0_OE_MOS_N")
			(options
				(clearance outline)
				(anchor circle)
			)
			(primitives
				(gr_poly
					(pts
						(arc
							(start -0.1778 0.5715)
							(mid -0.321484 0.511984)
							(end -0.381 0.3683)
						)
						(arc
							(start -0.381 -0.3683)
							(mid -0.321484 -0.511984)
							(end -0.1778 -0.5715)
						)
						(arc
							(start 0.1778 -0.5715)
							(mid 0.321484 -0.511984)
							(end 0.381 -0.3683)
						)
						(arc
							(start 0.381 0.3683)
							(mid 0.321484 0.511984)
							(end 0.1778 0.5715)
						)
					)
					(width 0)
					(fill yes)
				)
			)
		)
		(pad "S" smd custom
			(at 0.98425 0.9525)
			(size 0.1905 0.1905)
			(layers "F.Cu" "F.Mask" "F.Paste")
			(net "ATTN_LED_DR6_R")
			(options
				(clearance outline)
				(anchor circle)
			)
			(primitives
				(gr_poly
					(pts
						(arc
							(start -0.1778 0.5715)
							(mid -0.321484 0.511984)
							(end -0.381 0.3683)
						)
						(arc
							(start -0.381 -0.3683)
							(mid -0.321484 -0.511984)
							(end -0.1778 -0.5715)
						)
						(arc
							(start 0.1778 -0.5715)
							(mid 0.321484 -0.511984)
							(end 0.381 -0.3683)
						)
						(arc
							(start 0.381 0.3683)
							(mid 0.321484 0.511984)
							(end 0.1778 0.5715)
						)
					)
					(width 0)
					(fill yes)
				)
			)
		)
	)
	(footprint ""
		(layer "F.Cu")
		(at 25.4 -445.135 180)
		(property "Reference" "PC1184"
			(at 0 0 180)
			(layer "F.SilkS")
			(hide yes)
			(effects
				(font
					(size 1.27 1.27)
				)
			)
		)
		(property "Value" "SCD1U25V3KX-GP"
			(at 0 -2.8194 180)
			(unlocked yes)
			(layer "F.Fab")
			(hide yes)
			(effects
				(font
					(size 1.016 1.016)
					(thickness 0.1524)
				)
			)
		)
		(property "Device Type" "C603H36"
			(at 0 -4.3434 180)
			(unlocked yes)
			(layer "F.Fab")
			(hide yes)
			(effects
				(font
					(size 1.016 1.016)
					(thickness 0.1524)
				)
			)
		)
		(duplicate_pad_numbers_are_jumpers no)
		(fp_line
			(start 0.508 0)
			(end -0.508 0)
			(stroke
				(width 0.2032)
				(type default)
			)
			(layer "F.SilkS")
		)
		(fp_rect
			(start -0.5842 1.3335)
			(end 0.5842 -1.3335)
			(stroke
				(width 0)
				(type default)
			)
			(fill no)
			(layer "F.CrtYd")
		)
		(fp_rect
			(start -0.5842 1.3335)
			(end 0.5842 -1.3335)
			(stroke
				(width 0)
				(type default)
			)
			(fill no)
			(layer "F.Fab")
		)
		(pad "1" smd custom
			(at 0 -0.762 180)
			(size 0.2159 0.2159)
			(layers "F.Cu" "F.Mask" "F.Paste")
			(net "P3V3")
			(options
				(clearance outline)
				(anchor circle)
			)
			(primitives
				(gr_poly
					(pts
						(arc
							(start -0.3302 -0.4318)
							(mid -0.402042 -0.402042)
							(end -0.4318 -0.3302)
						)
						(arc
							(start -0.4318 0.3302)
							(mid -0.402042 0.402042)
							(end -0.3302 0.4318)
						)
						(arc
							(start 0.3302 0.4318)
							(mid 0.402042 0.402042)
							(end 0.4318 0.3302)
						)
						(arc
							(start 0.4318 -0.3302)
							(mid 0.402042 -0.402042)
							(end 0.3302 -0.4318)
						)
					)
					(width 0)
					(fill yes)
				)
			)
		)
		(pad "2" smd custom
			(at 0 0.762 180)
			(size 0.2159 0.2159)
			(layers "F.Cu" "F.Mask" "F.Paste")
			(net "GND")
			(options
				(clearance outline)
				(anchor circle)
			)
			(primitives
				(gr_poly
					(pts
						(arc
							(start -0.3302 -0.4318)
							(mid -0.402042 -0.402042)
							(end -0.4318 -0.3302)
						)
						(arc
							(start -0.4318 0.3302)
							(mid -0.402042 0.402042)
							(end -0.3302 0.4318)
						)
						(arc
							(start 0.3302 0.4318)
							(mid 0.402042 0.402042)
							(end 0.4318 0.3302)
						)
						(arc
							(start 0.4318 -0.3302)
							(mid 0.402042 -0.402042)
							(end 0.3302 -0.4318)
						)
					)
					(width 0)
					(fill yes)
				)
			)
		)
	)
	(footprint ""
		(layer "F.Cu")
		(at 23.622 -256.667 180)
		(property "Reference" "R9904"
			(at 0 0 180)
			(layer "F.SilkS")
			(hide yes)
			(effects
				(font
					(size 1.27 1.27)
				)
			)
		)
		(property "Value" "1K82R2F-1-GP"
			(at 0.064008 -3.993896 180)
			(unlocked yes)
			(layer "F.Fab")
			(hide yes)
			(effects
				(font
					(size 1.016 1.016)
					(thickness 0.1524)
				)
			)
		)
		(property "Device Type" "R402H16"
			(at 0.064008 -5.517896 180)
			(unlocked yes)
			(layer "F.Fab")
			(hide yes)
			(effects
				(font
					(size 1.016 1.016)
					(thickness 0.1524)
				)
			)
		)
		(duplicate_pad_numbers_are_jumpers no)
		(fp_line
			(start 0.508 -0.9398)
			(end -0.508 -0.9398)
			(stroke
				(width 0.1524)
				(type default)
			)
			(layer "F.SilkS")
		)
		(fp_line
			(start -0.508 -0.9398)
			(end -0.508 0.9398)
			(stroke
				(width 0.1524)
				(type default)
			)
			(layer "F.SilkS")
		)
		(fp_rect
			(start -0.508 0.9398)
			(end 0.508 -0.9398)
			(stroke
				(width 0)
				(type default)
			)
			(fill no)
			(layer "F.CrtYd")
		)
		(fp_rect
			(start -0.508 0.9398)
			(end 0.508 -0.9398)
			(stroke
				(width 0)
				(type default)
			)
			(fill no)
			(layer "F.Fab")
		)
		(pad "1" smd custom
			(at 0 -0.4445 180)
			(size 0.1397 0.1397)
			(layers "F.Cu" "F.Mask" "F.Paste")
			(net "P12V")
			(options
				(clearance outline)
				(anchor circle)
			)
			(primitives
				(gr_poly
					(pts
						(arc
							(start -0.1778 -0.2794)
							(mid -0.249642 -0.249642)
							(end -0.2794 -0.1778)
						)
						(arc
							(start -0.2794 0.1778)
							(mid -0.249642 0.249642)
							(end -0.1778 0.2794)
						)
						(arc
							(start 0.1778 0.2794)
							(mid 0.249642 0.249642)
							(end 0.2794 0.1778)
						)
						(arc
							(start 0.2794 -0.1778)
							(mid 0.249642 -0.249642)
							(end 0.1778 -0.2794)
						)
					)
					(width 0)
					(fill yes)
				)
			)
		)
		(pad "2" smd custom
			(at 0 0.4445 180)
			(size 0.1397 0.1397)
			(layers "F.Cu" "F.Mask" "F.Paste")
			(net "DRV_ACT_12")
			(options
				(clearance outline)
				(anchor circle)
			)
			(primitives
				(gr_poly
					(pts
						(arc
							(start -0.1778 -0.2794)
							(mid -0.249642 -0.249642)
							(end -0.2794 -0.1778)
						)
						(arc
							(start -0.2794 0.1778)
							(mid -0.249642 0.249642)
							(end -0.1778 0.2794)
						)
						(arc
							(start 0.1778 0.2794)
							(mid 0.249642 0.249642)
							(end 0.2794 0.1778)
						)
						(arc
							(start 0.2794 -0.1778)
							(mid 0.249642 -0.249642)
							(end 0.1778 -0.2794)
						)
					)
					(width 0)
					(fill yes)
				)
			)
		)
	)
	(footprint ""
		(layer "F.Cu")
		(at 210.947 -197.9676 -90)
		(property "Reference" "Q42"
			(at 0 0 270)
			(layer "F.SilkS")
			(hide yes)
			(effects
				(font
					(size 1.27 1.27)
				)
			)
		)
		(property "Value" "2N7002A-7-GP"
			(at 0.127 -8.9662 270)
			(unlocked yes)
			(layer "F.Fab")
			(hide yes)
			(effects
				(font
					(size 1.016 1.016)
					(thickness 0.1524)
				)
			)
		)
		(property "Device Type" "SOT23DGS2D4H48"
			(at 0.127 -10.4902 270)
			(unlocked yes)
			(layer "F.Fab")
			(hide yes)
			(effects
				(font
					(size 1.016 1.016)
					(thickness 0.1524)
				)
			)
		)
		(duplicate_pad_numbers_are_jumpers no)
		(fp_line
			(start -1.651 1.778)
			(end 1.651 1.778)
			(stroke
				(width 0.1524)
				(type default)
			)
			(layer "F.SilkS")
		)
		(fp_line
			(start 1.651 1.778)
			(end 1.651 -1.778)
			(stroke
				(width 0.1524)
				(type default)
			)
			(layer "F.SilkS")
		)
		(fp_line
			(start -1.651 -1.778)
			(end -1.651 1.778)
			(stroke
				(width 0.1524)
				(type default)
			)
			(layer "F.SilkS")
		)
		(fp_line
			(start 1.651 -1.778)
			(end -1.651 -1.778)
			(stroke
				(width 0.1524)
				(type default)
			)
			(layer "F.SilkS")
		)
		(fp_poly
			(pts
				(xy -1.778 1.8796) (xy -1.778 -1.8796) (xy 1.778 -1.8796) (xy 1.778 1.8796)
			)
			(stroke
				(width 0)
				(type default)
			)
			(fill no)
			(layer "F.CrtYd")
		)
		(fp_poly
			(pts
				(xy -1.778 1.8796) (xy -1.778 -1.8796) (xy 1.778 -1.8796) (xy 1.778 1.8796)
			)
			(stroke
				(width 0)
				(type default)
			)
			(fill no)
			(layer "F.Fab")
		)
		(pad "D" smd custom
			(at 0 -0.9525 270)
			(size 0.1905 0.1905)
			(layers "F.Cu" "F.Mask" "F.Paste")
			(net "P12V_MOST3_GATE")
			(options
				(clearance outline)
				(anchor circle)
			)
			(primitives
				(gr_poly
					(pts
						(arc
							(start -0.1778 0.5715)
							(mid -0.321484 0.511984)
							(end -0.381 0.3683)
						)
						(arc
							(start -0.381 -0.3683)
							(mid -0.321484 -0.511984)
							(end -0.1778 -0.5715)
						)
						(arc
							(start 0.1778 -0.5715)
							(mid 0.321484 -0.511984)
							(end 0.381 -0.3683)
						)
						(arc
							(start 0.381 0.3683)
							(mid 0.321484 0.511984)
							(end 0.1778 0.5715)
						)
					)
					(width 0)
					(fill yes)
				)
			)
		)
		(pad "G" smd custom
			(at -0.98425 0.9525 270)
			(size 0.1905 0.1905)
			(layers "F.Cu" "F.Mask" "F.Paste")
			(net "SSD3_PWREN_R")
			(options
				(clearance outline)
				(anchor circle)
			)
			(primitives
				(gr_poly
					(pts
						(arc
							(start -0.1778 0.5715)
							(mid -0.321484 0.511984)
							(end -0.381 0.3683)
						)
						(arc
							(start -0.381 -0.3683)
							(mid -0.321484 -0.511984)
							(end -0.1778 -0.5715)
						)
						(arc
							(start 0.1778 -0.5715)
							(mid 0.321484 -0.511984)
							(end 0.381 -0.3683)
						)
						(arc
							(start 0.381 0.3683)
							(mid 0.321484 0.511984)
							(end 0.1778 0.5715)
						)
					)
					(width 0)
					(fill yes)
				)
			)
		)
		(pad "S" smd custom
			(at 0.98425 0.9525 270)
			(size 0.1905 0.1905)
			(layers "F.Cu" "F.Mask" "F.Paste")
			(net "GND")
			(options
				(clearance outline)
				(anchor circle)
			)
			(primitives
				(gr_poly
					(pts
						(arc
							(start -0.1778 0.5715)
							(mid -0.321484 0.511984)
							(end -0.381 0.3683)
						)
						(arc
							(start -0.381 -0.3683)
							(mid -0.321484 -0.511984)
							(end -0.1778 -0.5715)
						)
						(arc
							(start 0.1778 -0.5715)
							(mid 0.321484 -0.511984)
							(end 0.381 -0.3683)
						)
						(arc
							(start 0.381 0.3683)
							(mid 0.321484 0.511984)
							(end 0.1778 0.5715)
						)
					)
					(width 0)
					(fill yes)
				)
			)
		)
	)
	(footprint ""
		(layer "F.Cu")
		(at 97.663 -202.184)
		(property "Reference" "R9084"
			(at 0 0 0)
			(layer "F.SilkS")
			(hide yes)
			(effects
				(font
					(size 1.27 1.27)
				)
			)
		)
		(property "Value" "27R2F-GP"
			(at 0.064008 -3.993896 0)
			(unlocked yes)
			(layer "F.Fab")
			(hide yes)
			(effects
				(font
					(size 1.016 1.016)
					(thickness 0.1524)
				)
			)
		)
		(property "Device Type" "R402H16"
			(at 0.064008 -5.517896 0)
			(unlocked yes)
			(layer "F.Fab")
			(hide yes)
			(effects
				(font
					(size 1.016 1.016)
					(thickness 0.1524)
				)
			)
		)
		(duplicate_pad_numbers_are_jumpers no)
		(fp_line
			(start -0.508 -0.9398)
			(end -0.508 0.9398)
			(stroke
				(width 0.1524)
				(type default)
			)
			(layer "F.SilkS")
		)
		(fp_line
			(start 0.508 -0.9398)
			(end -0.508 -0.9398)
			(stroke
				(width 0.1524)
				(type default)
			)
			(layer "F.SilkS")
		)
		(fp_rect
			(start -0.508 0.9398)
			(end 0.508 -0.9398)
			(stroke
				(width 0)
				(type default)
			)
			(fill no)
			(layer "F.CrtYd")
		)
		(fp_rect
			(start -0.508 0.9398)
			(end 0.508 -0.9398)
			(stroke
				(width 0)
				(type default)
			)
			(fill no)
			(layer "F.Fab")
		)
		(pad "1" smd custom
			(at 0 -0.4445)
			(size 0.1397 0.1397)
			(layers "F.Cu" "F.Mask" "F.Paste")
			(net "PE_CLK_100M_DR4_1_R_P")
			(options
				(clearance outline)
				(anchor circle)
			)
			(primitives
				(gr_poly
					(pts
						(arc
							(start -0.1778 -0.2794)
							(mid -0.249642 -0.249642)
							(end -0.2794 -0.1778)
						)
						(arc
							(start -0.2794 0.1778)
							(mid -0.249642 0.249642)
							(end -0.1778 0.2794)
						)
						(arc
							(start 0.1778 0.2794)
							(mid 0.249642 0.249642)
							(end 0.2794 0.1778)
						)
						(arc
							(start 0.2794 -0.1778)
							(mid 0.249642 -0.249642)
							(end 0.1778 -0.2794)
						)
					)
					(width 0)
					(fill yes)
				)
			)
		)
		(pad "2" smd custom
			(at 0 0.4445)
			(size 0.1397 0.1397)
			(layers "F.Cu" "F.Mask" "F.Paste")
			(net "PE_CLK100M_DR4_1_P")
			(options
				(clearance outline)
				(anchor circle)
			)
			(primitives
				(gr_poly
					(pts
						(arc
							(start -0.1778 -0.2794)
							(mid -0.249642 -0.249642)
							(end -0.2794 -0.1778)
						)
						(arc
							(start -0.2794 0.1778)
							(mid -0.249642 0.249642)
							(end -0.1778 0.2794)
						)
						(arc
							(start 0.1778 0.2794)
							(mid 0.249642 0.249642)
							(end 0.2794 0.1778)
						)
						(arc
							(start 0.2794 -0.1778)
							(mid 0.249642 -0.249642)
							(end 0.1778 -0.2794)
						)
					)
					(width 0)
					(fill yes)
				)
			)
		)
	)
	(footprint ""
		(layer "F.Cu")
		(at 38.0746 -418.8714)
		(property "Reference" "R576"
			(at 0 0 0)
			(layer "F.SilkS")
			(hide yes)
			(effects
				(font
					(size 1.27 1.27)
				)
			)
		)
		(property "Value" "300KR2F-GP"
			(at 0.064008 -3.993896 0)
			(unlocked yes)
			(layer "F.Fab")
			(hide yes)
			(effects
				(font
					(size 1.016 1.016)
					(thickness 0.1524)
				)
			)
		)
		(property "Device Type" "R402H16"
			(at 0.064008 -5.517896 0)
			(unlocked yes)
			(layer "F.Fab")
			(hide yes)
			(effects
				(font
					(size 1.016 1.016)
					(thickness 0.1524)
				)
			)
		)
		(duplicate_pad_numbers_are_jumpers no)
		(fp_line
			(start -0.508 -0.9398)
			(end -0.508 0.9398)
			(stroke
				(width 0.1524)
				(type default)
			)
			(layer "F.SilkS")
		)
		(fp_line
			(start 0.508 -0.9398)
			(end -0.508 -0.9398)
			(stroke
				(width 0.1524)
				(type default)
			)
			(layer "F.SilkS")
		)
		(fp_rect
			(start -0.508 0.9398)
			(end 0.508 -0.9398)
			(stroke
				(width 0)
				(type default)
			)
			(fill no)
			(layer "F.CrtYd")
		)
		(fp_rect
			(start -0.508 0.9398)
			(end 0.508 -0.9398)
			(stroke
				(width 0)
				(type default)
			)
			(fill no)
			(layer "F.Fab")
		)
		(pad "1" smd custom
			(at 0 -0.4445)
			(size 0.1397 0.1397)
			(layers "F.Cu" "F.Mask" "F.Paste")
			(net "SW_SSD10_N")
			(options
				(clearance outline)
				(anchor circle)
			)
			(primitives
				(gr_poly
					(pts
						(arc
							(start -0.1778 -0.2794)
							(mid -0.249642 -0.249642)
							(end -0.2794 -0.1778)
						)
						(arc
							(start -0.2794 0.1778)
							(mid -0.249642 0.249642)
							(end -0.1778 0.2794)
						)
						(arc
							(start 0.1778 0.2794)
							(mid 0.249642 0.249642)
							(end 0.2794 0.1778)
						)
						(arc
							(start 0.2794 -0.1778)
							(mid 0.249642 -0.249642)
							(end 0.1778 -0.2794)
						)
					)
					(width 0)
					(fill yes)
				)
			)
		)
		(pad "2" smd custom
			(at 0 0.4445)
			(size 0.1397 0.1397)
			(layers "F.Cu" "F.Mask" "F.Paste")
			(net "P12V")
			(options
				(clearance outline)
				(anchor circle)
			)
			(primitives
				(gr_poly
					(pts
						(arc
							(start -0.1778 -0.2794)
							(mid -0.249642 -0.249642)
							(end -0.2794 -0.1778)
						)
						(arc
							(start -0.2794 0.1778)
							(mid -0.249642 0.249642)
							(end -0.1778 0.2794)
						)
						(arc
							(start 0.1778 0.2794)
							(mid 0.249642 0.249642)
							(end 0.2794 0.1778)
						)
						(arc
							(start 0.2794 -0.1778)
							(mid 0.249642 -0.249642)
							(end 0.1778 -0.2794)
						)
					)
					(width 0)
					(fill yes)
				)
			)
		)
	)
	(footprint ""
		(layer "F.Cu")
		(at 242.062 -422.529 90)
		(property "Reference" "PR9065"
			(at 0 0 90)
			(layer "F.SilkS")
			(hide yes)
			(effects
				(font
					(size 1.27 1.27)
				)
			)
		)
		(property "Value" "0R2J-2-GP"
			(at 0.064008 -3.993896 90)
			(unlocked yes)
			(layer "F.Fab")
			(hide yes)
			(effects
				(font
					(size 1.016 1.016)
					(thickness 0.1524)
				)
			)
		)
		(property "Device Type" "R402H16"
			(at 0.064008 -5.517896 90)
			(unlocked yes)
			(layer "F.Fab")
			(hide yes)
			(effects
				(font
					(size 1.016 1.016)
					(thickness 0.1524)
				)
			)
		)
		(duplicate_pad_numbers_are_jumpers no)
		(fp_line
			(start 0.508 -0.9398)
			(end -0.508 -0.9398)
			(stroke
				(width 0.1524)
				(type default)
			)
			(layer "F.SilkS")
		)
		(fp_line
			(start -0.508 -0.9398)
			(end -0.508 0.9398)
			(stroke
				(width 0.1524)
				(type default)
			)
			(layer "F.SilkS")
		)
		(fp_rect
			(start -0.508 0.9398)
			(end 0.508 -0.9398)
			(stroke
				(width 0)
				(type default)
			)
			(fill no)
			(layer "F.CrtYd")
		)
		(fp_rect
			(start -0.508 0.9398)
			(end 0.508 -0.9398)
			(stroke
				(width 0)
				(type default)
			)
			(fill no)
			(layer "F.Fab")
		)
		(pad "1" smd custom
			(at 0 -0.4445 90)
			(size 0.1397 0.1397)
			(layers "F.Cu" "F.Mask" "F.Paste")
			(net "SAS_I2C_C_BUF_SDA_R")
			(options
				(clearance outline)
				(anchor circle)
			)
			(primitives
				(gr_poly
					(pts
						(arc
							(start -0.1778 -0.2794)
							(mid -0.249642 -0.249642)
							(end -0.2794 -0.1778)
						)
						(arc
							(start -0.2794 0.1778)
							(mid -0.249642 0.249642)
							(end -0.1778 0.2794)
						)
						(arc
							(start 0.1778 0.2794)
							(mid 0.249642 0.249642)
							(end 0.2794 0.1778)
						)
						(arc
							(start 0.2794 -0.1778)
							(mid 0.249642 -0.249642)
							(end 0.1778 -0.2794)
						)
					)
					(width 0)
					(fill yes)
				)
			)
		)
		(pad "2" smd custom
			(at 0 0.4445 90)
			(size 0.1397 0.1397)
			(layers "F.Cu" "F.Mask" "F.Paste")
			(net "I2C_C_SDA")
			(options
				(clearance outline)
				(anchor circle)
			)
			(primitives
				(gr_poly
					(pts
						(arc
							(start -0.1778 -0.2794)
							(mid -0.249642 -0.249642)
							(end -0.2794 -0.1778)
						)
						(arc
							(start -0.2794 0.1778)
							(mid -0.249642 0.249642)
							(end -0.1778 0.2794)
						)
						(arc
							(start 0.1778 0.2794)
							(mid 0.249642 0.249642)
							(end 0.2794 0.1778)
						)
						(arc
							(start 0.2794 -0.1778)
							(mid 0.249642 -0.249642)
							(end 0.1778 -0.2794)
						)
					)
					(width 0)
					(fill yes)
				)
			)
		)
	)
	(footprint ""
		(layer "F.Cu")
		(at 19.4945 -370.0399)
		(property "Reference" "SR1144"
			(at 0 0 0)
			(layer "F.SilkS")
			(hide yes)
			(effects
				(font
					(size 1.27 1.27)
				)
			)
		)
		(property "Value" "4K7R2J-2-GP"
			(at 0.064008 -3.993896 0)
			(unlocked yes)
			(layer "F.Fab")
			(hide yes)
			(effects
				(font
					(size 1.016 1.016)
					(thickness 0.1524)
				)
			)
		)
		(property "Device Type" "R402H16"
			(at 0.064008 -5.517896 0)
			(unlocked yes)
			(layer "F.Fab")
			(hide yes)
			(effects
				(font
					(size 1.016 1.016)
					(thickness 0.1524)
				)
			)
		)
		(duplicate_pad_numbers_are_jumpers no)
		(fp_line
			(start -0.508 -0.9398)
			(end -0.508 0.9398)
			(stroke
				(width 0.1524)
				(type default)
			)
			(layer "F.SilkS")
		)
		(fp_line
			(start 0.508 -0.9398)
			(end -0.508 -0.9398)
			(stroke
				(width 0.1524)
				(type default)
			)
			(layer "F.SilkS")
		)
		(fp_rect
			(start -0.508 0.9398)
			(end 0.508 -0.9398)
			(stroke
				(width 0)
				(type default)
			)
			(fill no)
			(layer "F.CrtYd")
		)
		(fp_rect
			(start -0.508 0.9398)
			(end 0.508 -0.9398)
			(stroke
				(width 0)
				(type default)
			)
			(fill no)
			(layer "F.Fab")
		)
		(pad "1" smd custom
			(at 0 -0.4445)
			(size 0.1397 0.1397)
			(layers "F.Cu" "F.Mask" "F.Paste")
			(net "P3V3")
			(options
				(clearance outline)
				(anchor circle)
			)
			(primitives
				(gr_poly
					(pts
						(arc
							(start -0.1778 -0.2794)
							(mid -0.249642 -0.249642)
							(end -0.2794 -0.1778)
						)
						(arc
							(start -0.2794 0.1778)
							(mid -0.249642 0.249642)
							(end -0.1778 0.2794)
						)
						(arc
							(start 0.1778 0.2794)
							(mid 0.249642 0.249642)
							(end 0.2794 0.1778)
						)
						(arc
							(start 0.2794 -0.1778)
							(mid 0.249642 -0.249642)
							(end 0.1778 -0.2794)
						)
					)
					(width 0)
					(fill yes)
				)
			)
		)
		(pad "2" smd custom
			(at 0 0.4445)
			(size 0.1397 0.1397)
			(layers "F.Cu" "F.Mask" "F.Paste")
			(net "SSD_ACT_DR11")
			(options
				(clearance outline)
				(anchor circle)
			)
			(primitives
				(gr_poly
					(pts
						(arc
							(start -0.1778 -0.2794)
							(mid -0.249642 -0.249642)
							(end -0.2794 -0.1778)
						)
						(arc
							(start -0.2794 0.1778)
							(mid -0.249642 0.249642)
							(end -0.1778 0.2794)
						)
						(arc
							(start 0.1778 0.2794)
							(mid 0.249642 0.249642)
							(end 0.2794 0.1778)
						)
						(arc
							(start 0.2794 -0.1778)
							(mid 0.249642 -0.249642)
							(end 0.1778 -0.2794)
						)
					)
					(width 0)
					(fill yes)
				)
			)
		)
	)
	(footprint ""
		(layer "F.Cu")
		(at 38.851586 -343.484708 90)
		(property "Reference" "R9822"
			(at 0 0 90)
			(layer "F.SilkS")
			(hide yes)
			(effects
				(font
					(size 1.27 1.27)
				)
			)
		)
		(property "Value" "0R2J-2-GP"
			(at 0.064008 -3.993896 90)
			(unlocked yes)
			(layer "F.Fab")
			(hide yes)
			(effects
				(font
					(size 1.016 1.016)
					(thickness 0.1524)
				)
			)
		)
		(property "Device Type" "R402H16"
			(at 0.064008 -5.517896 90)
			(unlocked yes)
			(layer "F.Fab")
			(hide yes)
			(effects
				(font
					(size 1.016 1.016)
					(thickness 0.1524)
				)
			)
		)
		(duplicate_pad_numbers_are_jumpers no)
		(fp_line
			(start 0.508 -0.9398)
			(end -0.508 -0.9398)
			(stroke
				(width 0.1524)
				(type default)
			)
			(layer "F.SilkS")
		)
		(fp_line
			(start -0.508 -0.9398)
			(end -0.508 0.9398)
			(stroke
				(width 0.1524)
				(type default)
			)
			(layer "F.SilkS")
		)
		(fp_rect
			(start -0.508 0.9398)
			(end 0.508 -0.9398)
			(stroke
				(width 0)
				(type default)
			)
			(fill no)
			(layer "F.CrtYd")
		)
		(fp_rect
			(start -0.508 0.9398)
			(end 0.508 -0.9398)
			(stroke
				(width 0)
				(type default)
			)
			(fill no)
			(layer "F.Fab")
		)
		(pad "1" smd custom
			(at 0 -0.4445 90)
			(size 0.1397 0.1397)
			(layers "F.Cu" "F.Mask" "F.Paste")
			(net "ATTN_LED_DR6_R")
			(options
				(clearance outline)
				(anchor circle)
			)
			(primitives
				(gr_poly
					(pts
						(arc
							(start -0.1778 -0.2794)
							(mid -0.249642 -0.249642)
							(end -0.2794 -0.1778)
						)
						(arc
							(start -0.2794 0.1778)
							(mid -0.249642 0.249642)
							(end -0.1778 0.2794)
						)
						(arc
							(start 0.1778 0.2794)
							(mid 0.249642 0.249642)
							(end 0.2794 0.1778)
						)
						(arc
							(start 0.2794 -0.1778)
							(mid 0.249642 -0.249642)
							(end 0.1778 -0.2794)
						)
					)
					(width 0)
					(fill yes)
				)
			)
		)
		(pad "2" smd custom
			(at 0 0.4445 90)
			(size 0.1397 0.1397)
			(layers "F.Cu" "F.Mask" "F.Paste")
			(net "ATTN_LED_DR6_N")
			(options
				(clearance outline)
				(anchor circle)
			)
			(primitives
				(gr_poly
					(pts
						(arc
							(start -0.1778 -0.2794)
							(mid -0.249642 -0.249642)
							(end -0.2794 -0.1778)
						)
						(arc
							(start -0.2794 0.1778)
							(mid -0.249642 0.249642)
							(end -0.1778 0.2794)
						)
						(arc
							(start 0.1778 0.2794)
							(mid 0.249642 0.249642)
							(end 0.2794 0.1778)
						)
						(arc
							(start 0.2794 -0.1778)
							(mid 0.249642 -0.249642)
							(end 0.1778 -0.2794)
						)
					)
					(width 0)
					(fill yes)
				)
			)
		)
	)
	(footprint ""
		(layer "F.Cu")
		(at 24.3078 -87.122 180)
		(property "Reference" "R575"
			(at 0 0 180)
			(layer "F.SilkS")
			(hide yes)
			(effects
				(font
					(size 1.27 1.27)
				)
			)
		)
		(property "Value" "300KR2F-GP"
			(at 0.064008 -3.993896 180)
			(unlocked yes)
			(layer "F.Fab")
			(hide yes)
			(effects
				(font
					(size 1.016 1.016)
					(thickness 0.1524)
				)
			)
		)
		(property "Device Type" "R402H16"
			(at 0.064008 -5.517896 180)
			(unlocked yes)
			(layer "F.Fab")
			(hide yes)
			(effects
				(font
					(size 1.016 1.016)
					(thickness 0.1524)
				)
			)
		)
		(duplicate_pad_numbers_are_jumpers no)
		(fp_line
			(start 0.508 -0.9398)
			(end -0.508 -0.9398)
			(stroke
				(width 0.1524)
				(type default)
			)
			(layer "F.SilkS")
		)
		(fp_line
			(start -0.508 -0.9398)
			(end -0.508 0.9398)
			(stroke
				(width 0.1524)
				(type default)
			)
			(layer "F.SilkS")
		)
		(fp_rect
			(start -0.508 0.9398)
			(end 0.508 -0.9398)
			(stroke
				(width 0)
				(type default)
			)
			(fill no)
			(layer "F.CrtYd")
		)
		(fp_rect
			(start -0.508 0.9398)
			(end 0.508 -0.9398)
			(stroke
				(width 0)
				(type default)
			)
			(fill no)
			(layer "F.Fab")
		)
		(pad "1" smd custom
			(at 0 -0.4445 180)
			(size 0.1397 0.1397)
			(layers "F.Cu" "F.Mask" "F.Paste")
			(net "SW_SSD9_N")
			(options
				(clearance outline)
				(anchor circle)
			)
			(primitives
				(gr_poly
					(pts
						(arc
							(start -0.1778 -0.2794)
							(mid -0.249642 -0.249642)
							(end -0.2794 -0.1778)
						)
						(arc
							(start -0.2794 0.1778)
							(mid -0.249642 0.249642)
							(end -0.1778 0.2794)
						)
						(arc
							(start 0.1778 0.2794)
							(mid 0.249642 0.249642)
							(end 0.2794 0.1778)
						)
						(arc
							(start 0.2794 -0.1778)
							(mid 0.249642 -0.249642)
							(end 0.1778 -0.2794)
						)
					)
					(width 0)
					(fill yes)
				)
			)
		)
		(pad "2" smd custom
			(at 0 0.4445 180)
			(size 0.1397 0.1397)
			(layers "F.Cu" "F.Mask" "F.Paste")
			(net "P12V")
			(options
				(clearance outline)
				(anchor circle)
			)
			(primitives
				(gr_poly
					(pts
						(arc
							(start -0.1778 -0.2794)
							(mid -0.249642 -0.249642)
							(end -0.2794 -0.1778)
						)
						(arc
							(start -0.2794 0.1778)
							(mid -0.249642 0.249642)
							(end -0.1778 0.2794)
						)
						(arc
							(start 0.1778 0.2794)
							(mid 0.249642 0.249642)
							(end 0.2794 0.1778)
						)
						(arc
							(start 0.2794 -0.1778)
							(mid 0.249642 -0.249642)
							(end 0.1778 -0.2794)
						)
					)
					(width 0)
					(fill yes)
				)
			)
		)
	)
	(footprint ""
		(layer "F.Cu")
		(at 20.066 -167.380158 -90)
		(property "Reference" "R9867"
			(at 0 0 270)
			(layer "F.SilkS")
			(hide yes)
			(effects
				(font
					(size 1.27 1.27)
				)
			)
		)
		(property "Value" "0R2J-2-GP"
			(at 0.064008 -3.993896 270)
			(unlocked yes)
			(layer "F.Fab")
			(hide yes)
			(effects
				(font
					(size 1.016 1.016)
					(thickness 0.1524)
				)
			)
		)
		(property "Device Type" "R402H16"
			(at 0.064008 -5.517896 270)
			(unlocked yes)
			(layer "F.Fab")
			(hide yes)
			(effects
				(font
					(size 1.016 1.016)
					(thickness 0.1524)
				)
			)
		)
		(duplicate_pad_numbers_are_jumpers no)
		(fp_line
			(start -0.508 -0.9398)
			(end -0.508 0.9398)
			(stroke
				(width 0.1524)
				(type default)
			)
			(layer "F.SilkS")
		)
		(fp_line
			(start 0.508 -0.9398)
			(end -0.508 -0.9398)
			(stroke
				(width 0.1524)
				(type default)
			)
			(layer "F.SilkS")
		)
		(fp_rect
			(start -0.508 0.9398)
			(end 0.508 -0.9398)
			(stroke
				(width 0)
				(type default)
			)
			(fill no)
			(layer "F.CrtYd")
		)
		(fp_rect
			(start -0.508 0.9398)
			(end 0.508 -0.9398)
			(stroke
				(width 0)
				(type default)
			)
			(fill no)
			(layer "F.Fab")
		)
		(pad "1" smd custom
			(at 0 -0.4445 270)
			(size 0.1397 0.1397)
			(layers "F.Cu" "F.Mask" "F.Paste")
			(net "ATTN_LED_DR13_AND")
			(options
				(clearance outline)
				(anchor circle)
			)
			(primitives
				(gr_poly
					(pts
						(arc
							(start -0.1778 -0.2794)
							(mid -0.249642 -0.249642)
							(end -0.2794 -0.1778)
						)
						(arc
							(start -0.2794 0.1778)
							(mid -0.249642 0.249642)
							(end -0.1778 0.2794)
						)
						(arc
							(start 0.1778 0.2794)
							(mid 0.249642 0.249642)
							(end 0.2794 0.1778)
						)
						(arc
							(start 0.2794 -0.1778)
							(mid 0.249642 -0.249642)
							(end 0.1778 -0.2794)
						)
					)
					(width 0)
					(fill yes)
				)
			)
		)
		(pad "2" smd custom
			(at 0 0.4445 270)
			(size 0.1397 0.1397)
			(layers "F.Cu" "F.Mask" "F.Paste")
			(net "ATTN_LED_DR13_AND_R")
			(options
				(clearance outline)
				(anchor circle)
			)
			(primitives
				(gr_poly
					(pts
						(arc
							(start -0.1778 -0.2794)
							(mid -0.249642 -0.249642)
							(end -0.2794 -0.1778)
						)
						(arc
							(start -0.2794 0.1778)
							(mid -0.249642 0.249642)
							(end -0.1778 0.2794)
						)
						(arc
							(start 0.1778 0.2794)
							(mid 0.249642 0.249642)
							(end 0.2794 0.1778)
						)
						(arc
							(start 0.2794 -0.1778)
							(mid 0.249642 -0.249642)
							(end 0.1778 -0.2794)
						)
					)
					(width 0)
					(fill yes)
				)
			)
		)
	)
	(footprint ""
		(layer "F.Cu")
		(at 89.789 -222.885 -90)
		(property "Reference" "C9361"
			(at 0 0 270)
			(layer "F.SilkS")
			(hide yes)
			(effects
				(font
					(size 1.27 1.27)
				)
			)
		)
		(property "Value" "SC1KP50V2KX-1GP"
			(at 1.1811 -2.7051 270)
			(unlocked yes)
			(layer "F.Fab")
			(hide yes)
			(effects
				(font
					(size 1.016 1.016)
					(thickness 0.1524)
				)
			)
		)
		(property "Device Type" "C402H22"
			(at 1.1811 -4.2291 270)
			(unlocked yes)
			(layer "F.Fab")
			(hide yes)
			(effects
				(font
					(size 1.016 1.016)
					(thickness 0.1524)
				)
			)
		)
		(duplicate_pad_numbers_are_jumpers no)
		(fp_rect
			(start -0.4318 0.9525)
			(end 0.4318 -0.9525)
			(stroke
				(width 0)
				(type default)
			)
			(fill no)
			(layer "F.CrtYd")
		)
		(fp_rect
			(start -0.4318 0.9525)
			(end 0.4318 -0.9525)
			(stroke
				(width 0)
				(type default)
			)
			(fill no)
			(layer "F.Fab")
		)
		(pad "1" smd custom
			(at 0 -0.4445 270)
			(size 0.1524 0.1524)
			(layers "F.Cu" "F.Mask" "F.Paste")
			(net "SSD_PRSNT12")
			(options
				(clearance outline)
				(anchor circle)
			)
			(primitives
				(gr_poly
					(pts
						(arc
							(start 0.3048 -0.2032)
							(mid 0.275042 -0.275042)
							(end 0.2032 -0.3048)
						)
						(arc
							(start -0.2032 -0.3048)
							(mid -0.275042 -0.275042)
							(end -0.3048 -0.2032)
						)
						(arc
							(start -0.3048 0.2032)
							(mid -0.275042 0.275042)
							(end -0.2032 0.3048)
						)
						(arc
							(start 0.2032 0.3048)
							(mid 0.275042 0.275042)
							(end 0.3048 0.2032)
						)
					)
					(width 0)
					(fill yes)
				)
			)
		)
		(pad "2" smd custom
			(at 0 0.4445 270)
			(size 0.1524 0.1524)
			(layers "F.Cu" "F.Mask" "F.Paste")
			(net "GND")
			(options
				(clearance outline)
				(anchor circle)
			)
			(primitives
				(gr_poly
					(pts
						(arc
							(start 0.3048 -0.2032)
							(mid 0.275042 -0.275042)
							(end 0.2032 -0.3048)
						)
						(arc
							(start -0.2032 -0.3048)
							(mid -0.275042 -0.275042)
							(end -0.3048 -0.2032)
						)
						(arc
							(start -0.3048 0.2032)
							(mid -0.275042 0.275042)
							(end -0.2032 0.3048)
						)
						(arc
							(start 0.2032 0.3048)
							(mid 0.275042 0.275042)
							(end 0.3048 0.2032)
						)
					)
					(width 0)
					(fill yes)
				)
			)
		)
	)
	(footprint ""
		(layer "F.Cu")
		(at 87.63 -88.138 180)
		(property "Reference" "R9606"
			(at 0 0 180)
			(layer "F.SilkS")
			(hide yes)
			(effects
				(font
					(size 1.27 1.27)
				)
			)
		)
		(property "Value" "10R2F-L-GP"
			(at 0.064008 -3.993896 180)
			(unlocked yes)
			(layer "F.Fab")
			(hide yes)
			(effects
				(font
					(size 1.016 1.016)
					(thickness 0.1524)
				)
			)
		)
		(property "Device Type" "R402H14"
			(at 0.064008 -5.517896 180)
			(unlocked yes)
			(layer "F.Fab")
			(hide yes)
			(effects
				(font
					(size 1.016 1.016)
					(thickness 0.1524)
				)
			)
		)
		(duplicate_pad_numbers_are_jumpers no)
		(fp_line
			(start 0.508 -0.9398)
			(end -0.508 -0.9398)
			(stroke
				(width 0.1524)
				(type default)
			)
			(layer "F.SilkS")
		)
		(fp_line
			(start -0.508 -0.9398)
			(end -0.508 0.9398)
			(stroke
				(width 0.1524)
				(type default)
			)
			(layer "F.SilkS")
		)
		(fp_rect
			(start -0.508 0.9398)
			(end 0.508 -0.9398)
			(stroke
				(width 0)
				(type default)
			)
			(fill no)
			(layer "F.CrtYd")
		)
		(fp_rect
			(start -0.508 0.9398)
			(end 0.508 -0.9398)
			(stroke
				(width 0)
				(type default)
			)
			(fill no)
			(layer "F.Fab")
		)
		(pad "1" smd custom
			(at 0 -0.4445 180)
			(size 0.1397 0.1397)
			(layers "F.Cu" "F.Mask" "F.Paste")
			(net "SSD_PRSNT_NET9")
			(options
				(clearance outline)
				(anchor circle)
			)
			(primitives
				(gr_poly
					(pts
						(arc
							(start -0.1778 -0.2794)
							(mid -0.249642 -0.249642)
							(end -0.2794 -0.1778)
						)
						(arc
							(start -0.2794 0.1778)
							(mid -0.249642 0.249642)
							(end -0.1778 0.2794)
						)
						(arc
							(start 0.1778 0.2794)
							(mid 0.249642 0.249642)
							(end 0.2794 0.1778)
						)
						(arc
							(start 0.2794 -0.1778)
							(mid 0.249642 -0.249642)
							(end 0.1778 -0.2794)
						)
					)
					(width 0)
					(fill yes)
				)
			)
		)
		(pad "2" smd custom
			(at 0 0.4445 180)
			(size 0.1397 0.1397)
			(layers "F.Cu" "F.Mask" "F.Paste")
			(net "SSD_PRSNT9")
			(options
				(clearance outline)
				(anchor circle)
			)
			(primitives
				(gr_poly
					(pts
						(arc
							(start -0.1778 -0.2794)
							(mid -0.249642 -0.249642)
							(end -0.2794 -0.1778)
						)
						(arc
							(start -0.2794 0.1778)
							(mid -0.249642 0.249642)
							(end -0.1778 0.2794)
						)
						(arc
							(start 0.1778 0.2794)
							(mid 0.249642 0.249642)
							(end 0.2794 0.1778)
						)
						(arc
							(start 0.2794 -0.1778)
							(mid 0.249642 -0.249642)
							(end 0.1778 -0.2794)
						)
					)
					(width 0)
					(fill yes)
				)
			)
		)
	)
	(footprint ""
		(layer "F.Cu")
		(at 50.546 -136.398 180)
		(property "Reference" "R342"
			(at 0 0 180)
			(layer "F.SilkS")
			(hide yes)
			(effects
				(font
					(size 1.27 1.27)
				)
			)
		)
		(property "Value" "4K7R2F-GP"
			(at 0.064008 -3.993896 180)
			(unlocked yes)
			(layer "F.Fab")
			(hide yes)
			(effects
				(font
					(size 1.016 1.016)
					(thickness 0.1524)
				)
			)
		)
		(property "Device Type" "R402H16"
			(at 0.064008 -5.517896 180)
			(unlocked yes)
			(layer "F.Fab")
			(hide yes)
			(effects
				(font
					(size 1.016 1.016)
					(thickness 0.1524)
				)
			)
		)
		(duplicate_pad_numbers_are_jumpers no)
		(fp_line
			(start 0.508 -0.9398)
			(end -0.508 -0.9398)
			(stroke
				(width 0.1524)
				(type default)
			)
			(layer "F.SilkS")
		)
		(fp_line
			(start -0.508 -0.9398)
			(end -0.508 0.9398)
			(stroke
				(width 0.1524)
				(type default)
			)
			(layer "F.SilkS")
		)
		(fp_rect
			(start -0.508 0.9398)
			(end 0.508 -0.9398)
			(stroke
				(width 0)
				(type default)
			)
			(fill no)
			(layer "F.CrtYd")
		)
		(fp_rect
			(start -0.508 0.9398)
			(end 0.508 -0.9398)
			(stroke
				(width 0)
				(type default)
			)
			(fill no)
			(layer "F.Fab")
		)
		(pad "1" smd custom
			(at 0 -0.4445 180)
			(size 0.1397 0.1397)
			(layers "F.Cu" "F.Mask" "F.Paste")
			(net "I2C_B_TMP1_A1")
			(options
				(clearance outline)
				(anchor circle)
			)
			(primitives
				(gr_poly
					(pts
						(arc
							(start -0.1778 -0.2794)
							(mid -0.249642 -0.249642)
							(end -0.2794 -0.1778)
						)
						(arc
							(start -0.2794 0.1778)
							(mid -0.249642 0.249642)
							(end -0.1778 0.2794)
						)
						(arc
							(start 0.1778 0.2794)
							(mid 0.249642 0.249642)
							(end 0.2794 0.1778)
						)
						(arc
							(start 0.2794 -0.1778)
							(mid 0.249642 -0.249642)
							(end 0.1778 -0.2794)
						)
					)
					(width 0)
					(fill yes)
				)
			)
		)
		(pad "2" smd custom
			(at 0 0.4445 180)
			(size 0.1397 0.1397)
			(layers "F.Cu" "F.Mask" "F.Paste")
			(net "GND")
			(options
				(clearance outline)
				(anchor circle)
			)
			(primitives
				(gr_poly
					(pts
						(arc
							(start -0.1778 -0.2794)
							(mid -0.249642 -0.249642)
							(end -0.2794 -0.1778)
						)
						(arc
							(start -0.2794 0.1778)
							(mid -0.249642 0.249642)
							(end -0.1778 0.2794)
						)
						(arc
							(start 0.1778 0.2794)
							(mid 0.249642 0.249642)
							(end 0.2794 0.1778)
						)
						(arc
							(start 0.2794 -0.1778)
							(mid 0.249642 -0.249642)
							(end 0.1778 -0.2794)
						)
					)
					(width 0)
					(fill yes)
				)
			)
		)
	)
	(footprint ""
		(layer "F.Cu")
		(at 89.789 -446.786 90)
		(property "Reference" "R9416"
			(at 0 0 90)
			(layer "F.SilkS")
			(hide yes)
			(effects
				(font
					(size 1.27 1.27)
				)
			)
		)
		(property "Value" "4K7R2J-2-GP"
			(at 0.064008 -3.993896 90)
			(unlocked yes)
			(layer "F.Fab")
			(hide yes)
			(effects
				(font
					(size 1.016 1.016)
					(thickness 0.1524)
				)
			)
		)
		(property "Device Type" "R402H16"
			(at 0.064008 -5.517896 90)
			(unlocked yes)
			(layer "F.Fab")
			(hide yes)
			(effects
				(font
					(size 1.016 1.016)
					(thickness 0.1524)
				)
			)
		)
		(duplicate_pad_numbers_are_jumpers no)
		(fp_line
			(start 0.508 -0.9398)
			(end -0.508 -0.9398)
			(stroke
				(width 0.1524)
				(type default)
			)
			(layer "F.SilkS")
		)
		(fp_line
			(start -0.508 -0.9398)
			(end -0.508 0.9398)
			(stroke
				(width 0.1524)
				(type default)
			)
			(layer "F.SilkS")
		)
		(fp_rect
			(start -0.508 0.9398)
			(end 0.508 -0.9398)
			(stroke
				(width 0)
				(type default)
			)
			(fill no)
			(layer "F.CrtYd")
		)
		(fp_rect
			(start -0.508 0.9398)
			(end 0.508 -0.9398)
			(stroke
				(width 0)
				(type default)
			)
			(fill no)
			(layer "F.Fab")
		)
		(pad "1" smd custom
			(at 0 -0.4445 90)
			(size 0.1397 0.1397)
			(layers "F.Cu" "F.Mask" "F.Paste")
			(net "P3V3")
			(options
				(clearance outline)
				(anchor circle)
			)
			(primitives
				(gr_poly
					(pts
						(arc
							(start -0.1778 -0.2794)
							(mid -0.249642 -0.249642)
							(end -0.2794 -0.1778)
						)
						(arc
							(start -0.2794 0.1778)
							(mid -0.249642 0.249642)
							(end -0.1778 0.2794)
						)
						(arc
							(start 0.1778 0.2794)
							(mid 0.249642 0.249642)
							(end 0.2794 0.1778)
						)
						(arc
							(start 0.2794 -0.1778)
							(mid 0.249642 -0.249642)
							(end 0.1778 -0.2794)
						)
					)
					(width 0)
					(fill yes)
				)
			)
		)
		(pad "2" smd custom
			(at 0 0.4445 90)
			(size 0.1397 0.1397)
			(layers "F.Cu" "F.Mask" "F.Paste")
			(net "SSD_PRSNT_NET5")
			(options
				(clearance outline)
				(anchor circle)
			)
			(primitives
				(gr_poly
					(pts
						(arc
							(start -0.1778 -0.2794)
							(mid -0.249642 -0.249642)
							(end -0.2794 -0.1778)
						)
						(arc
							(start -0.2794 0.1778)
							(mid -0.249642 0.249642)
							(end -0.1778 0.2794)
						)
						(arc
							(start 0.1778 0.2794)
							(mid 0.249642 0.249642)
							(end 0.2794 0.1778)
						)
						(arc
							(start 0.2794 -0.1778)
							(mid 0.249642 -0.249642)
							(end 0.1778 -0.2794)
						)
					)
					(width 0)
					(fill yes)
				)
			)
		)
	)
	(footprint ""
		(layer "F.Cu")
		(at 99.314 -92.964)
		(property "Reference" "R9129"
			(at 0 0 0)
			(layer "F.SilkS")
			(hide yes)
			(effects
				(font
					(size 1.27 1.27)
				)
			)
		)
		(property "Value" "27R2F-GP"
			(at 0.064008 -3.993896 0)
			(unlocked yes)
			(layer "F.Fab")
			(hide yes)
			(effects
				(font
					(size 1.016 1.016)
					(thickness 0.1524)
				)
			)
		)
		(property "Device Type" "R402H16"
			(at 0.064008 -5.517896 0)
			(unlocked yes)
			(layer "F.Fab")
			(hide yes)
			(effects
				(font
					(size 1.016 1.016)
					(thickness 0.1524)
				)
			)
		)
		(duplicate_pad_numbers_are_jumpers no)
		(fp_line
			(start -0.508 -0.9398)
			(end -0.508 0.9398)
			(stroke
				(width 0.1524)
				(type default)
			)
			(layer "F.SilkS")
		)
		(fp_line
			(start 0.508 -0.9398)
			(end -0.508 -0.9398)
			(stroke
				(width 0.1524)
				(type default)
			)
			(layer "F.SilkS")
		)
		(fp_rect
			(start -0.508 0.9398)
			(end 0.508 -0.9398)
			(stroke
				(width 0)
				(type default)
			)
			(fill no)
			(layer "F.CrtYd")
		)
		(fp_rect
			(start -0.508 0.9398)
			(end 0.508 -0.9398)
			(stroke
				(width 0)
				(type default)
			)
			(fill no)
			(layer "F.Fab")
		)
		(pad "1" smd custom
			(at 0 -0.4445)
			(size 0.1397 0.1397)
			(layers "F.Cu" "F.Mask" "F.Paste")
			(net "PE_CLK_100M_DR14_1_R_P")
			(options
				(clearance outline)
				(anchor circle)
			)
			(primitives
				(gr_poly
					(pts
						(arc
							(start -0.1778 -0.2794)
							(mid -0.249642 -0.249642)
							(end -0.2794 -0.1778)
						)
						(arc
							(start -0.2794 0.1778)
							(mid -0.249642 0.249642)
							(end -0.1778 0.2794)
						)
						(arc
							(start 0.1778 0.2794)
							(mid 0.249642 0.249642)
							(end 0.2794 0.1778)
						)
						(arc
							(start 0.2794 -0.1778)
							(mid 0.249642 -0.249642)
							(end 0.1778 -0.2794)
						)
					)
					(width 0)
					(fill yes)
				)
			)
		)
		(pad "2" smd custom
			(at 0 0.4445)
			(size 0.1397 0.1397)
			(layers "F.Cu" "F.Mask" "F.Paste")
			(net "PE_CLK100M_DR14_1_P")
			(options
				(clearance outline)
				(anchor circle)
			)
			(primitives
				(gr_poly
					(pts
						(arc
							(start -0.1778 -0.2794)
							(mid -0.249642 -0.249642)
							(end -0.2794 -0.1778)
						)
						(arc
							(start -0.2794 0.1778)
							(mid -0.249642 0.249642)
							(end -0.1778 0.2794)
						)
						(arc
							(start 0.1778 0.2794)
							(mid 0.249642 0.249642)
							(end 0.2794 0.1778)
						)
						(arc
							(start 0.2794 -0.1778)
							(mid 0.249642 -0.249642)
							(end 0.1778 -0.2794)
						)
					)
					(width 0)
					(fill yes)
				)
			)
		)
	)
	(footprint ""
		(layer "F.Cu")
		(at 83.185 -152.654 -90)
		(property "Reference" "SR1151"
			(at 0 0 270)
			(layer "F.SilkS")
			(hide yes)
			(effects
				(font
					(size 1.27 1.27)
				)
			)
		)
		(property "Value" "4K7R2F-GP"
			(at 0.064008 -3.993896 270)
			(unlocked yes)
			(layer "F.Fab")
			(hide yes)
			(effects
				(font
					(size 1.016 1.016)
					(thickness 0.1524)
				)
			)
		)
		(property "Device Type" "R402H16"
			(at 0.064008 -5.517896 270)
			(unlocked yes)
			(layer "F.Fab")
			(hide yes)
			(effects
				(font
					(size 1.016 1.016)
					(thickness 0.1524)
				)
			)
		)
		(duplicate_pad_numbers_are_jumpers no)
		(fp_line
			(start -0.508 -0.9398)
			(end -0.508 0.9398)
			(stroke
				(width 0.1524)
				(type default)
			)
			(layer "F.SilkS")
		)
		(fp_line
			(start 0.508 -0.9398)
			(end -0.508 -0.9398)
			(stroke
				(width 0.1524)
				(type default)
			)
			(layer "F.SilkS")
		)
		(fp_rect
			(start -0.508 0.9398)
			(end 0.508 -0.9398)
			(stroke
				(width 0)
				(type default)
			)
			(fill no)
			(layer "F.CrtYd")
		)
		(fp_rect
			(start -0.508 0.9398)
			(end 0.508 -0.9398)
			(stroke
				(width 0)
				(type default)
			)
			(fill no)
			(layer "F.Fab")
		)
		(pad "1" smd custom
			(at 0 -0.4445 270)
			(size 0.1397 0.1397)
			(layers "F.Cu" "F.Mask" "F.Paste")
			(net "P3V3")
			(options
				(clearance outline)
				(anchor circle)
			)
			(primitives
				(gr_poly
					(pts
						(arc
							(start -0.1778 -0.2794)
							(mid -0.249642 -0.249642)
							(end -0.2794 -0.1778)
						)
						(arc
							(start -0.2794 0.1778)
							(mid -0.249642 0.249642)
							(end -0.1778 0.2794)
						)
						(arc
							(start 0.1778 0.2794)
							(mid 0.249642 0.249642)
							(end 0.2794 0.1778)
						)
						(arc
							(start 0.2794 -0.1778)
							(mid 0.249642 -0.249642)
							(end 0.1778 -0.2794)
						)
					)
					(width 0)
					(fill yes)
				)
			)
		)
		(pad "2" smd custom
			(at 0 0.4445 270)
			(size 0.1397 0.1397)
			(layers "F.Cu" "F.Mask" "F.Paste")
			(net "I2C_SW_EU16_ADDRESS_A1")
			(options
				(clearance outline)
				(anchor circle)
			)
			(primitives
				(gr_poly
					(pts
						(arc
							(start -0.1778 -0.2794)
							(mid -0.249642 -0.249642)
							(end -0.2794 -0.1778)
						)
						(arc
							(start -0.2794 0.1778)
							(mid -0.249642 0.249642)
							(end -0.1778 0.2794)
						)
						(arc
							(start 0.1778 0.2794)
							(mid 0.249642 0.249642)
							(end 0.2794 0.1778)
						)
						(arc
							(start 0.2794 -0.1778)
							(mid 0.249642 -0.249642)
							(end 0.1778 -0.2794)
						)
					)
					(width 0)
					(fill yes)
				)
			)
		)
	)
	(footprint ""
		(layer "F.Cu")
		(at 41.150032 -67.669918 90)
		(property "Reference" "J9"
			(at 0 0 90)
			(layer "F.SilkS")
			(hide yes)
			(effects
				(font
					(size 1.27 1.27)
				)
			)
		)
		(property "Value" "PCISLT68-14-GP-U1"
			(at -22.225 12.7508 90)
			(unlocked yes)
			(layer "F.Fab")
			(hide yes)
			(effects
				(font
					(size 1.016 1.016)
					(thickness 0.1524)
				)
			)
		)
		(property "Device Type" "SD-78827-0001"
			(at -22.225 11.2268 90)
			(unlocked yes)
			(layer "F.Fab")
			(hide yes)
			(effects
				(font
					(size 1.016 1.016)
					(thickness 0.1524)
				)
			)
		)
		(duplicate_pad_numbers_are_jumpers no)
		(fp_line
			(start 20.4724 -3.4036)
			(end 20.4724 0.0254)
			(stroke
				(width 0.1524)
				(type default)
			)
			(layer "F.SilkS")
		)
		(fp_line
			(start -20.4724 -3.4036)
			(end 20.4724 -3.4036)
			(stroke
				(width 0.1524)
				(type default)
			)
			(layer "F.SilkS")
		)
		(fp_line
			(start 23.749 0.0254)
			(end 23.749 4.6736)
			(stroke
				(width 0.1524)
				(type default)
			)
			(layer "F.SilkS")
		)
		(fp_line
			(start 20.4724 0.0254)
			(end 23.749 0.0254)
			(stroke
				(width 0.1524)
				(type default)
			)
			(layer "F.SilkS")
		)
		(fp_line
			(start -20.4724 0.0254)
			(end -20.4724 -3.4036)
			(stroke
				(width 0.1524)
				(type default)
			)
			(layer "F.SilkS")
		)
		(fp_line
			(start -23.749 0.0254)
			(end -20.4724 0.0254)
			(stroke
				(width 0.1524)
				(type default)
			)
			(layer "F.SilkS")
		)
		(fp_line
			(start 23.117556 1.803908)
			(end 23.117556 2.896108)
			(stroke
				(width 0.3048)
				(type default)
			)
			(layer "F.SilkS")
		)
		(fp_line
			(start -20.882356 1.803908)
			(end -20.882356 2.896108)
			(stroke
				(width 0.3048)
				(type default)
			)
			(layer "F.SilkS")
		)
		(fp_line
			(start 20.882356 2.896108)
			(end 20.882356 1.803908)
			(stroke
				(width 0.3048)
				(type default)
			)
			(layer "F.SilkS")
		)
		(fp_line
			(start -23.117556 2.896108)
			(end -23.117556 1.803908)
			(stroke
				(width 0.3048)
				(type default)
			)
			(layer "F.SilkS")
		)
		(fp_line
			(start 23.749 4.6736)
			(end 20.4724 4.6736)
			(stroke
				(width 0.1524)
				(type default)
			)
			(layer "F.SilkS")
		)
		(fp_line
			(start 20.4724 4.6736)
			(end 20.4724 12.0142)
			(stroke
				(width 0.1524)
				(type default)
			)
			(layer "F.SilkS")
		)
		(fp_line
			(start -20.4724 4.6736)
			(end -23.749 4.6736)
			(stroke
				(width 0.1524)
				(type default)
			)
			(layer "F.SilkS")
		)
		(fp_line
			(start -23.749 4.6736)
			(end -23.749 0.0254)
			(stroke
				(width 0.1524)
				(type default)
			)
			(layer "F.SilkS")
		)
		(fp_line
			(start 17.8435 10.3124)
			(end -17.8435 10.3124)
			(stroke
				(width 0.1524)
				(type default)
			)
			(layer "F.SilkS")
		)
		(fp_line
			(start -17.8435 10.3124)
			(end -17.8435 12.0142)
			(stroke
				(width 0.1524)
				(type default)
			)
			(layer "F.SilkS")
		)
		(fp_line
			(start 20.4724 12.0142)
			(end 17.8435 12.0142)
			(stroke
				(width 0.1524)
				(type default)
			)
			(layer "F.SilkS")
		)
		(fp_line
			(start 17.8435 12.0142)
			(end 17.8435 10.3124)
			(stroke
				(width 0.1524)
				(type default)
			)
			(layer "F.SilkS")
		)
		(fp_line
			(start -17.8435 12.0142)
			(end -20.4724 12.0142)
			(stroke
				(width 0.1524)
				(type default)
			)
			(layer "F.SilkS")
		)
		(fp_line
			(start -20.4724 12.0142)
			(end -20.4724 4.6736)
			(stroke
				(width 0.1524)
				(type default)
			)
			(layer "F.SilkS")
		)
		(fp_arc
			(start 20.882356 1.803908)
			(mid 21.999956 0.686308)
			(end 23.117556 1.803908)
			(stroke
				(width 0.3048)
				(type default)
			)
			(layer "F.SilkS")
		)
		(fp_arc
			(start -23.117556 1.803908)
			(mid -21.999956 0.686308)
			(end -20.882356 1.803908)
			(stroke
				(width 0.3048)
				(type default)
			)
			(layer "F.SilkS")
		)
		(fp_arc
			(start 23.117556 2.896108)
			(mid 21.999956 4.013708)
			(end 20.882356 2.896108)
			(stroke
				(width 0.3048)
				(type default)
			)
			(layer "F.SilkS")
		)
		(fp_arc
			(start -20.882356 2.896108)
			(mid -21.999956 4.013708)
			(end -23.117556 2.896108)
			(stroke
				(width 0.3048)
				(type default)
			)
			(layer "F.SilkS")
		)
		(fp_poly
			(pts
				(xy -20.2184 11.7602) (xy -20.2184 4.4196) (xy -23.495 4.4196) (xy -23.495 0.2794) (xy -20.2184 0.2794)
				(xy -20.2184 -3.1496) (xy 20.2184 -3.1496) (xy 20.2184 0.2794) (xy 23.495 0.2794) (xy 23.495 4.4196)
				(xy 20.2184 4.4196) (xy 20.2184 11.7602) (xy 18.0975 11.7602) (xy 18.0975 10.0584) (xy -18.0975 10.0584)
				(xy -18.0975 11.7602)
			)
			(stroke
				(width 0)
				(type default)
			)
			(fill no)
			(layer "F.CrtYd")
		)
		(fp_poly
			(pts
				(xy -21.2471 16.256) (xy -21.2471 4.9276) (xy -24.003 4.9276) (xy -24.003 -0.2286) (xy -20.7264 -0.2286)
				(xy -20.7264 -3.6576) (xy 20.7264 -3.6576) (xy 20.7264 -0.2286) (xy 24.003 -0.2286) (xy 24.003 -0.00635)
				(xy 20.2184 -0.00635) (xy 20.2184 -3.1496) (xy -20.2184 -3.1496) (xy -20.2184 0.2794) (xy -23.495 0.2794)
				(xy -23.495 4.4196) (xy -20.2184 4.4196) (xy -20.2184 11.7602) (xy -18.0975 11.7602) (xy -18.0975 10.0584)
				(xy 18.0975 10.0584) (xy 18.0975 11.7602) (xy 20.2184 11.7602) (xy 20.2184 4.4196) (xy 23.495 4.4196)
				(xy 23.495 0.2794) (xy 20.2184 0.2794) (xy 20.2184 0.00635) (xy 24.003 0.00635) (xy 24.003 4.9276)
				(xy 21.2471 4.9276) (xy 21.2471 16.256)
			)
			(stroke
				(width 0)
				(type default)
			)
			(fill no)
			(layer "F.CrtYd")
		)
		(fp_poly
			(pts
				(xy -21.2471 16.256) (xy -21.2471 4.9276) (xy -24.003 4.9276) (xy -24.003 -0.2286) (xy -20.7264 -0.2286)
				(xy -20.7264 -3.6576) (xy 20.7264 -3.6576) (xy 20.7264 -0.2286) (xy 24.003 -0.2286) (xy 24.003 4.9276)
				(xy 21.2471 4.9276) (xy 21.2471 16.256)
			)
			(stroke
				(width 0)
				(type default)
			)
			(fill no)
			(layer "F.Fab")
		)
		(pad "" np_thru_hole circle
			(at -18.999962 0 90)
			(size 0.254 0.254)
			(drill 1.8542)
			(layers "*.Cu" "*.Mask")
			(clearance 1.1557)
			(thermal_gap 1.1557)
		)
		(pad "" np_thru_hole circle
			(at 18.999962 0 90)
			(size 0.254 0.254)
			(drill 1.8542)
			(layers "*.Cu" "*.Mask")
			(clearance 1.1557)
			(thermal_gap 1.1557)
		)
		(pad "E1" smd rect
			(at -7.079996 1.240028 90)
			(size 0.508 2.0066)
			(layers "F.Cu" "F.Mask" "F.Paste")
			(net "PE_CLK100M_DR9_2_P")
		)
		(pad "E2" smd rect
			(at -6.279896 1.240028 90)
			(size 0.508 2.0066)
			(layers "F.Cu" "F.Mask" "F.Paste")
			(net "PE_CLK100M_DR9_2_N")
		)
		(pad "E3" smd rect
			(at -5.48005 1.240028 90)
			(size 0.508 2.0066)
			(layers "F.Cu" "F.Mask" "F.Paste")
			(net "P3V3")
		)
		(pad "E4" smd rect
			(at -4.67995 1.240028 90)
			(size 0.508 2.0066)
			(layers "F.Cu" "F.Mask" "F.Paste")
			(net "SSD9_PERST_N")
		)
		(pad "E5" smd rect
			(at -3.880104 1.240028 90)
			(size 0.508 2.0066)
			(layers "F.Cu" "F.Mask" "F.Paste")
			(net "SSD9_PERST_N")
		)
		(pad "E6" smd rect
			(at -3.080004 1.240028 90)
			(size 0.508 2.0066)
			(layers "F.Cu" "F.Mask" "F.Paste")
			(net "Net_1071")
		)
		(pad "E7" smd rect
			(at -15.48003 -1.949958 90)
			(size 0.508 2.0066)
			(layers "F.Cu" "F.Mask" "F.Paste")
			(net "PE_CLK100M_DR9_1_P")
		)
		(pad "E8" smd rect
			(at -14.67993 -1.949958 90)
			(size 0.508 2.0066)
			(layers "F.Cu" "F.Mask" "F.Paste")
			(net "PE_CLK100M_DR9_1_N")
		)
		(pad "E9" smd rect
			(at -13.880084 -1.949958 90)
			(size 0.508 2.0066)
			(layers "F.Cu" "F.Mask" "F.Paste")
			(net "GND")
		)
		(pad "E10" smd rect
			(at -13.079984 -1.949958 90)
			(size 0.508 2.0066)
			(layers "F.Cu" "F.Mask" "F.Paste")
			(net "PE_TX1_DR9_N")
		)
		(pad "E11" smd rect
			(at -12.279884 -1.949958 90)
			(size 0.508 2.0066)
			(layers "F.Cu" "F.Mask" "F.Paste")
			(net "PE_TX1_DR9_P")
		)
		(pad "E12" smd rect
			(at -11.480038 -1.949958 90)
			(size 0.508 2.0066)
			(layers "F.Cu" "F.Mask" "F.Paste")
			(net "GND")
		)
		(pad "E13" smd rect
			(at -10.679938 -1.949958 90)
			(size 0.508 2.0066)
			(layers "F.Cu" "F.Mask" "F.Paste")
			(net "PE_RX1_DR9_N")
		)
		(pad "E14" smd rect
			(at -9.880092 -1.949958 90)
			(size 0.508 2.0066)
			(layers "F.Cu" "F.Mask" "F.Paste")
			(net "PE_RX1_DR9_P")
		)
		(pad "E15" smd rect
			(at -9.079992 -1.949958 90)
			(size 0.508 2.0066)
			(layers "F.Cu" "F.Mask" "F.Paste")
			(net "GND")
		)
		(pad "E16" smd rect
			(at -8.279892 -1.949958 90)
			(size 0.508 2.0066)
			(layers "F.Cu" "F.Mask" "F.Paste")
			(net "Net_1078")
		)
		(pad "E17" smd rect
			(at 9.320022 -1.949958 90)
			(size 0.508 2.0066)
			(layers "F.Cu" "F.Mask" "F.Paste")
			(net "PE_TX4_DR9_N")
		)
		(pad "E18" smd rect
			(at 10.120122 -1.949958 90)
			(size 0.508 2.0066)
			(layers "F.Cu" "F.Mask" "F.Paste")
			(net "PE_TX4_DR9_P")
		)
		(pad "E19" smd rect
			(at 10.919968 -1.949958 90)
			(size 0.508 2.0066)
			(layers "F.Cu" "F.Mask" "F.Paste")
			(net "GND")
		)
		(pad "E20" smd rect
			(at 11.720068 -1.949958 90)
			(size 0.508 2.0066)
			(layers "F.Cu" "F.Mask" "F.Paste")
			(net "PE_RX4_DR9_N")
		)
		(pad "E21" smd rect
			(at 12.519914 -1.949958 90)
			(size 0.508 2.0066)
			(layers "F.Cu" "F.Mask" "F.Paste")
			(net "PE_RX4_DR9_P")
		)
		(pad "E22" smd rect
			(at 13.320014 -1.949958 90)
			(size 0.508 2.0066)
			(layers "F.Cu" "F.Mask" "F.Paste")
			(net "GND")
		)
		(pad "E23" smd rect
			(at 14.120114 -1.949958 90)
			(size 0.508 2.0066)
			(layers "F.Cu" "F.Mask" "F.Paste")
			(net "SCL_DR9_R")
		)
		(pad "E24" smd rect
			(at 14.91996 -1.949958 90)
			(size 0.508 2.0066)
			(layers "F.Cu" "F.Mask" "F.Paste")
			(net "SDA_DR9_R")
		)
		(pad "E25" smd rect
			(at 15.72006 -1.949958 90)
			(size 0.508 2.0066)
			(layers "F.Cu" "F.Mask" "F.Paste")
			(net "DUALPORTEN#9")
		)
		(pad "P1" smd rect
			(at -1.905 0.824992 90)
			(size 0.6604 2.0574)
			(layers "F.Cu" "F.Mask" "F.Paste")
			(net "Net_1074")
		)
		(pad "P2" smd rect
			(at -0.635 0.824992 90)
			(size 0.6604 2.0574)
			(layers "F.Cu" "F.Mask" "F.Paste")
			(net "Net_1073")
		)
		(pad "P3" smd rect
			(at 0.635 0.824992 90)
			(size 0.6604 2.0574)
			(layers "F.Cu" "F.Mask" "F.Paste")
			(net "Net_1072")
		)
		(pad "P4" smd rect
			(at 1.905 0.824992 90)
			(size 0.6604 2.0574)
			(layers "F.Cu" "F.Mask" "F.Paste")
			(net "SSD9_CLK0_OE_N")
		)
		(pad "P5" smd rect
			(at 3.175 0.824992 90)
			(size 0.6604 2.0574)
			(layers "F.Cu" "F.Mask" "F.Paste")
			(net "GND")
		)
		(pad "P6" smd rect
			(at 4.445 0.824992 90)
			(size 0.6604 2.0574)
			(layers "F.Cu" "F.Mask" "F.Paste")
			(net "GND")
		)
		(pad "P7" smd rect
			(at 5.715 0.824992 90)
			(size 0.6604 2.0574)
			(layers "F.Cu" "F.Mask" "F.Paste")
			(net "Net_96")
		)
		(pad "P8" smd rect
			(at 6.985 0.824992 90)
			(size 0.6604 2.0574)
			(layers "F.Cu" "F.Mask" "F.Paste")
			(net "Net_68")
		)
		(pad "P9" smd rect
			(at 8.255 0.824992 90)
			(size 0.6604 2.0574)
			(layers "F.Cu" "F.Mask" "F.Paste")
			(net "Net_82")
		)
		(pad "P10" smd rect
			(at 9.525 0.824992 90)
			(size 0.6604 2.0574)
			(layers "F.Cu" "F.Mask" "F.Paste")
			(net "SSD_PRSNT_NET9")
		)
		(pad "P11" smd rect
			(at 10.795 0.824992 90)
			(size 0.6604 2.0574)
			(layers "F.Cu" "F.Mask" "F.Paste")
			(net "SSD_ACT_DR9")
		)
		(pad "P12" smd rect
			(at 12.065 0.824992 90)
			(size 0.6604 2.0574)
			(layers "F.Cu" "F.Mask" "F.Paste")
			(net "GND")
		)
		(pad "P13" smd rect
			(at 13.335 0.824992 90)
			(size 0.6604 2.0574)
			(layers "F.Cu" "F.Mask" "F.Paste")
			(net "12V_PRECH_SSD9")
		)
		(pad "P14" smd rect
			(at 14.605 0.824992 90)
			(size 0.6604 2.0574)
			(layers "F.Cu" "F.Mask" "F.Paste")
			(net "P12V_SSD9")
		)
		(pad "P15" smd rect
			(at 15.875 0.824992 90)
			(size 0.6604 2.0574)
			(layers "F.Cu" "F.Mask" "F.Paste")
			(net "P12V_SSD9")
		)
		(pad "PTH1" thru_hole oval
			(at -21.999956 2.350008 90)
			(size 1.524 2.6162)
			(drill oval 0.8128 1.905)
			(layers "*.Cu" "*.Mask")
			(remove_unused_layers no)
			(net "Net_1083")
			(clearance 0.1524)
			(thermal_gap 0.1524)
		)
		(pad "PTH2" thru_hole oval
			(at 21.999956 2.350008 90)
			(size 1.524 2.6162)
			(drill oval 0.8128 1.905)
			(layers "*.Cu" "*.Mask")
			(remove_unused_layers no)
			(net "Net_1067")
			(clearance 0.1524)
			(thermal_gap 0.1524)
		)
		(pad "S1" smd rect
			(at -15.875 0.824992 90)
			(size 0.6604 2.0574)
			(layers "F.Cu" "F.Mask" "F.Paste")
			(net "GND")
		)
		(pad "S2" smd rect
			(at -14.605 0.824992 90)
			(size 0.6604 2.0574)
			(layers "F.Cu" "F.Mask" "F.Paste")
			(net "Net_1082")
		)
		(pad "S3" smd rect
			(at -13.335 0.824992 90)
			(size 0.6604 2.0574)
			(layers "F.Cu" "F.Mask" "F.Paste")
			(net "Net_1081")
		)
		(pad "S4" smd rect
			(at -12.065 0.824992 90)
			(size 0.6604 2.0574)
			(layers "F.Cu" "F.Mask" "F.Paste")
			(net "GND")
		)
		(pad "S5" smd rect
			(at -10.795 0.824992 90)
			(size 0.6604 2.0574)
			(layers "F.Cu" "F.Mask" "F.Paste")
			(net "Net_1080")
		)
		(pad "S6" smd rect
			(at -9.525 0.824992 90)
			(size 0.6604 2.0574)
			(layers "F.Cu" "F.Mask" "F.Paste")
			(net "Net_1079")
		)
		(pad "S7" smd rect
			(at -8.255 0.824992 90)
			(size 0.6604 2.0574)
			(layers "F.Cu" "F.Mask" "F.Paste")
			(net "GND")
		)
		(pad "S8" smd rect
			(at -7.480046 -1.949958 90)
			(size 0.508 2.0066)
			(layers "F.Cu" "F.Mask" "F.Paste")
			(net "GND")
		)
		(pad "S9" smd rect
			(at -6.679946 -1.949958 90)
			(size 0.508 2.0066)
			(layers "F.Cu" "F.Mask" "F.Paste")
			(net "Net_1077")
		)
		(pad "S10" smd rect
			(at -5.8801 -1.949958 90)
			(size 0.508 2.0066)
			(layers "F.Cu" "F.Mask" "F.Paste")
			(net "Net_1076")
		)
		(pad "S11" smd rect
			(at -5.08 -1.949958 90)
			(size 0.508 2.0066)
			(layers "F.Cu" "F.Mask" "F.Paste")
			(net "GND")
		)
		(pad "S12" smd rect
			(at -4.2799 -1.949958 90)
			(size 0.508 2.0066)
			(layers "F.Cu" "F.Mask" "F.Paste")
			(net "Net_1075")
		)
		(pad "S13" smd rect
			(at -3.480054 -1.949958 90)
			(size 0.508 2.0066)
			(layers "F.Cu" "F.Mask" "F.Paste")
			(net "Net_1070")
		)
		(pad "S14" smd rect
			(at -2.679954 -1.949958 90)
			(size 0.508 2.0066)
			(layers "F.Cu" "F.Mask" "F.Paste")
			(net "GND")
		)
		(pad "S15" smd rect
			(at -1.880108 -1.949958 90)
			(size 0.508 2.0066)
			(layers "F.Cu" "F.Mask" "F.Paste")
			(net "Net_1069")
		)
		(pad "S16" smd rect
			(at -1.080008 -1.949958 90)
			(size 0.508 2.0066)
			(layers "F.Cu" "F.Mask" "F.Paste")
			(net "GND")
		)
		(pad "S17" smd rect
			(at -0.279908 -1.949958 90)
			(size 0.508 2.0066)
			(layers "F.Cu" "F.Mask" "F.Paste")
			(net "PE_TX2_DR9_N")
		)
		(pad "S18" smd rect
			(at 0.519938 -1.949958 90)
			(size 0.508 2.0066)
			(layers "F.Cu" "F.Mask" "F.Paste")
			(net "PE_TX2_DR9_P")
		)
		(pad "S19" smd rect
			(at 1.320038 -1.949958 90)
			(size 0.508 2.0066)
			(layers "F.Cu" "F.Mask" "F.Paste")
			(net "GND")
		)
		(pad "S20" smd rect
			(at 2.119884 -1.949958 90)
			(size 0.508 2.0066)
			(layers "F.Cu" "F.Mask" "F.Paste")
			(net "PE_RX2_DR9_N")
		)
		(pad "S21" smd rect
			(at 2.919984 -1.949958 90)
			(size 0.508 2.0066)
			(layers "F.Cu" "F.Mask" "F.Paste")
			(net "PE_RX2_DR9_P")
		)
		(pad "S22" smd rect
			(at 3.720084 -1.949958 90)
			(size 0.508 2.0066)
			(layers "F.Cu" "F.Mask" "F.Paste")
			(net "GND")
		)
		(pad "S23" smd rect
			(at 4.51993 -1.949958 90)
			(size 0.508 2.0066)
			(layers "F.Cu" "F.Mask" "F.Paste")
			(net "PE_TX3_DR9_N")
		)
		(pad "S24" smd rect
			(at 5.32003 -1.949958 90)
			(size 0.508 2.0066)
			(layers "F.Cu" "F.Mask" "F.Paste")
			(net "PE_TX3_DR9_P")
		)
		(pad "S25" smd rect
			(at 6.119876 -1.949958 90)
			(size 0.508 2.0066)
			(layers "F.Cu" "F.Mask" "F.Paste")
			(net "GND")
		)
		(pad "S26" smd rect
			(at 6.919976 -1.949958 90)
			(size 0.508 2.0066)
			(layers "F.Cu" "F.Mask" "F.Paste")
			(net "PE_RX3_DR9_N")
		)
		(pad "S27" smd rect
			(at 7.720076 -1.949958 90)
			(size 0.508 2.0066)
			(layers "F.Cu" "F.Mask" "F.Paste")
			(net "PE_RX3_DR9_P")
		)
		(pad "S28" smd rect
			(at 8.519922 -1.949958 90)
			(size 0.508 2.0066)
			(layers "F.Cu" "F.Mask" "F.Paste")
			(net "GND")
		)
		(zone
			(layers "F.Cu" "B.Cu" "In1.Cu" "In2.Cu" "In3.Cu" "In4.Cu" "In5.Cu" "In6.Cu")
			(hatch none 0.5)
			(connect_pads
				(clearance 0)
			)
			(min_thickness 0.25)
			(keepout
				(tracks not_allowed)
				(vias allowed)
				(pads allowed)
				(copperpour not_allowed)
				(footprints allowed)
			)
			(placement
				(enabled no)
				(sheetname "")
			)
			(fill
				(thermal_gap 0.5)
				(thermal_bridge_width 0.5)
				(island_removal_mode 0)
			)
			(polygon
				(pts
					(arc
						(start 42.381932 -86.66988)
						(mid 39.918132 -86.66988)
						(end 42.381932 -86.66988)
					)
				)
			)
		)
		(zone
			(layers "F.Cu" "B.Cu" "In1.Cu" "In2.Cu" "In3.Cu" "In4.Cu" "In5.Cu" "In6.Cu")
			(hatch none 0.5)
			(connect_pads
				(clearance 0)
			)
			(min_thickness 0.25)
			(keepout
				(tracks not_allowed)
				(vias allowed)
				(pads allowed)
				(copperpour not_allowed)
				(footprints allowed)
			)
			(placement
				(enabled no)
				(sheetname "")
			)
			(fill
				(thermal_gap 0.5)
				(thermal_bridge_width 0.5)
				(island_removal_mode 0)
			)
			(polygon
				(pts
					(arc
						(start 42.381932 -48.669956)
						(mid 39.918132 -48.669956)
						(end 42.381932 -48.669956)
					)
				)
			)
		)
	)
	(footprint ""
		(layer "F.Cu")
		(at 39.83355 -307.01615 -90)
		(property "Reference" "R9851"
			(at 0 0 270)
			(layer "F.SilkS")
			(hide yes)
			(effects
				(font
					(size 1.27 1.27)
				)
			)
		)
		(property "Value" "1KR2J-1-GP"
			(at 0.064008 -3.993896 270)
			(unlocked yes)
			(layer "F.Fab")
			(hide yes)
			(effects
				(font
					(size 1.016 1.016)
					(thickness 0.1524)
				)
			)
		)
		(property "Device Type" "R402H16"
			(at 0.064008 -5.517896 270)
			(unlocked yes)
			(layer "F.Fab")
			(hide yes)
			(effects
				(font
					(size 1.016 1.016)
					(thickness 0.1524)
				)
			)
		)
		(duplicate_pad_numbers_are_jumpers no)
		(fp_line
			(start -0.508 -0.9398)
			(end -0.508 0.9398)
			(stroke
				(width 0.1524)
				(type default)
			)
			(layer "F.SilkS")
		)
		(fp_line
			(start 0.508 -0.9398)
			(end -0.508 -0.9398)
			(stroke
				(width 0.1524)
				(type default)
			)
			(layer "F.SilkS")
		)
		(fp_rect
			(start -0.508 0.9398)
			(end 0.508 -0.9398)
			(stroke
				(width 0)
				(type default)
			)
			(fill no)
			(layer "F.CrtYd")
		)
		(fp_rect
			(start -0.508 0.9398)
			(end 0.508 -0.9398)
			(stroke
				(width 0)
				(type default)
			)
			(fill no)
			(layer "F.Fab")
		)
		(pad "1" smd custom
			(at 0 -0.4445 270)
			(size 0.1397 0.1397)
			(layers "F.Cu" "F.Mask" "F.Paste")
			(net "SSD11_PWREN")
			(options
				(clearance outline)
				(anchor circle)
			)
			(primitives
				(gr_poly
					(pts
						(arc
							(start -0.1778 -0.2794)
							(mid -0.249642 -0.249642)
							(end -0.2794 -0.1778)
						)
						(arc
							(start -0.2794 0.1778)
							(mid -0.249642 0.249642)
							(end -0.1778 0.2794)
						)
						(arc
							(start 0.1778 0.2794)
							(mid 0.249642 0.249642)
							(end 0.2794 0.1778)
						)
						(arc
							(start 0.2794 -0.1778)
							(mid 0.249642 -0.249642)
							(end 0.1778 -0.2794)
						)
					)
					(width 0)
					(fill yes)
				)
			)
		)
		(pad "2" smd custom
			(at 0 0.4445 270)
			(size 0.1397 0.1397)
			(layers "F.Cu" "F.Mask" "F.Paste")
			(net "SSD11_PWREN_R")
			(options
				(clearance outline)
				(anchor circle)
			)
			(primitives
				(gr_poly
					(pts
						(arc
							(start -0.1778 -0.2794)
							(mid -0.249642 -0.249642)
							(end -0.2794 -0.1778)
						)
						(arc
							(start -0.2794 0.1778)
							(mid -0.249642 0.249642)
							(end -0.1778 0.2794)
						)
						(arc
							(start 0.1778 0.2794)
							(mid 0.249642 0.249642)
							(end 0.2794 0.1778)
						)
						(arc
							(start 0.2794 -0.1778)
							(mid 0.249642 -0.249642)
							(end 0.1778 -0.2794)
						)
					)
					(width 0)
					(fill yes)
				)
			)
		)
	)
	(footprint ""
		(layer "F.Cu")
		(at 84.455 -300.355 90)
		(property "Reference" "R421"
			(at 0 0 90)
			(layer "F.SilkS")
			(hide yes)
			(effects
				(font
					(size 1.27 1.27)
				)
			)
		)
		(property "Value" "0R2J-2-GP"
			(at 0.064008 -3.993896 90)
			(unlocked yes)
			(layer "F.Fab")
			(hide yes)
			(effects
				(font
					(size 1.016 1.016)
					(thickness 0.1524)
				)
			)
		)
		(property "Device Type" "R402H16"
			(at 0.064008 -5.517896 90)
			(unlocked yes)
			(layer "F.Fab")
			(hide yes)
			(effects
				(font
					(size 1.016 1.016)
					(thickness 0.1524)
				)
			)
		)
		(duplicate_pad_numbers_are_jumpers no)
		(fp_line
			(start 0.508 -0.9398)
			(end -0.508 -0.9398)
			(stroke
				(width 0.1524)
				(type default)
			)
			(layer "F.SilkS")
		)
		(fp_line
			(start -0.508 -0.9398)
			(end -0.508 0.9398)
			(stroke
				(width 0.1524)
				(type default)
			)
			(layer "F.SilkS")
		)
		(fp_rect
			(start -0.508 0.9398)
			(end 0.508 -0.9398)
			(stroke
				(width 0)
				(type default)
			)
			(fill no)
			(layer "F.CrtYd")
		)
		(fp_rect
			(start -0.508 0.9398)
			(end 0.508 -0.9398)
			(stroke
				(width 0)
				(type default)
			)
			(fill no)
			(layer "F.Fab")
		)
		(pad "1" smd custom
			(at 0 -0.4445 90)
			(size 0.1397 0.1397)
			(layers "F.Cu" "F.Mask" "F.Paste")
			(net "BMC_I2C_SCL_BUF_9")
			(options
				(clearance outline)
				(anchor circle)
			)
			(primitives
				(gr_poly
					(pts
						(arc
							(start -0.1778 -0.2794)
							(mid -0.249642 -0.249642)
							(end -0.2794 -0.1778)
						)
						(arc
							(start -0.2794 0.1778)
							(mid -0.249642 0.249642)
							(end -0.1778 0.2794)
						)
						(arc
							(start 0.1778 0.2794)
							(mid 0.249642 0.249642)
							(end 0.2794 0.1778)
						)
						(arc
							(start 0.2794 -0.1778)
							(mid 0.249642 -0.249642)
							(end 0.1778 -0.2794)
						)
					)
					(width 0)
					(fill yes)
				)
			)
		)
		(pad "2" smd custom
			(at 0 0.4445 90)
			(size 0.1397 0.1397)
			(layers "F.Cu" "F.Mask" "F.Paste")
			(net "I2C_SCL_BUF_9_EU2_R")
			(options
				(clearance outline)
				(anchor circle)
			)
			(primitives
				(gr_poly
					(pts
						(arc
							(start -0.1778 -0.2794)
							(mid -0.249642 -0.249642)
							(end -0.2794 -0.1778)
						)
						(arc
							(start -0.2794 0.1778)
							(mid -0.249642 0.249642)
							(end -0.1778 0.2794)
						)
						(arc
							(start 0.1778 0.2794)
							(mid 0.249642 0.249642)
							(end 0.2794 0.1778)
						)
						(arc
							(start 0.2794 -0.1778)
							(mid 0.249642 -0.249642)
							(end 0.1778 -0.2794)
						)
					)
					(width 0)
					(fill yes)
				)
			)
		)
	)
	(footprint ""
		(layer "F.Cu")
		(at 77.7748 -430.3395)
		(property "Reference" "R9958"
			(at 0 0 0)
			(layer "F.SilkS")
			(hide yes)
			(effects
				(font
					(size 1.27 1.27)
				)
			)
		)
		(property "Value" "56R2F-1-GP"
			(at 0.064008 -3.993896 0)
			(unlocked yes)
			(layer "F.Fab")
			(hide yes)
			(effects
				(font
					(size 1.016 1.016)
					(thickness 0.1524)
				)
			)
		)
		(property "Device Type" "R402H16"
			(at 0.064008 -5.517896 0)
			(unlocked yes)
			(layer "F.Fab")
			(hide yes)
			(effects
				(font
					(size 1.016 1.016)
					(thickness 0.1524)
				)
			)
		)
		(duplicate_pad_numbers_are_jumpers no)
		(fp_line
			(start -0.508 -0.9398)
			(end -0.508 0.9398)
			(stroke
				(width 0.1524)
				(type default)
			)
			(layer "F.SilkS")
		)
		(fp_line
			(start 0.508 -0.9398)
			(end -0.508 -0.9398)
			(stroke
				(width 0.1524)
				(type default)
			)
			(layer "F.SilkS")
		)
		(fp_rect
			(start -0.508 0.9398)
			(end 0.508 -0.9398)
			(stroke
				(width 0)
				(type default)
			)
			(fill no)
			(layer "F.CrtYd")
		)
		(fp_rect
			(start -0.508 0.9398)
			(end 0.508 -0.9398)
			(stroke
				(width 0)
				(type default)
			)
			(fill no)
			(layer "F.Fab")
		)
		(pad "1" smd custom
			(at 0 -0.4445)
			(size 0.1397 0.1397)
			(layers "F.Cu" "F.Mask" "F.Paste")
			(net "PE_100M_CLK4_N")
			(options
				(clearance outline)
				(anchor circle)
			)
			(primitives
				(gr_poly
					(pts
						(arc
							(start -0.1778 -0.2794)
							(mid -0.249642 -0.249642)
							(end -0.2794 -0.1778)
						)
						(arc
							(start -0.2794 0.1778)
							(mid -0.249642 0.249642)
							(end -0.1778 0.2794)
						)
						(arc
							(start 0.1778 0.2794)
							(mid 0.249642 0.249642)
							(end 0.2794 0.1778)
						)
						(arc
							(start 0.2794 -0.1778)
							(mid 0.249642 -0.249642)
							(end 0.1778 -0.2794)
						)
					)
					(width 0)
					(fill yes)
				)
			)
		)
		(pad "2" smd custom
			(at 0 0.4445)
			(size 0.1397 0.1397)
			(layers "F.Cu" "F.Mask" "F.Paste")
			(net "GND")
			(options
				(clearance outline)
				(anchor circle)
			)
			(primitives
				(gr_poly
					(pts
						(arc
							(start -0.1778 -0.2794)
							(mid -0.249642 -0.249642)
							(end -0.2794 -0.1778)
						)
						(arc
							(start -0.2794 0.1778)
							(mid -0.249642 0.249642)
							(end -0.1778 0.2794)
						)
						(arc
							(start 0.1778 0.2794)
							(mid 0.249642 0.249642)
							(end 0.2794 0.1778)
						)
						(arc
							(start 0.2794 -0.1778)
							(mid 0.249642 -0.249642)
							(end 0.1778 -0.2794)
						)
					)
					(width 0)
					(fill yes)
				)
			)
		)
	)
	(footprint ""
		(layer "F.Cu")
		(at 30.607 -410.9974 90)
		(property "Reference" "Q77"
			(at 0 0 90)
			(layer "F.SilkS")
			(hide yes)
			(effects
				(font
					(size 1.27 1.27)
				)
			)
		)
		(property "Value" "2N7002A-7-GP"
			(at 0.127 -8.9662 90)
			(unlocked yes)
			(layer "F.Fab")
			(hide yes)
			(effects
				(font
					(size 1.016 1.016)
					(thickness 0.1524)
				)
			)
		)
		(property "Device Type" "SOT23DGS2D4H48"
			(at 0.127 -10.4902 90)
			(unlocked yes)
			(layer "F.Fab")
			(hide yes)
			(effects
				(font
					(size 1.016 1.016)
					(thickness 0.1524)
				)
			)
		)
		(duplicate_pad_numbers_are_jumpers no)
		(fp_line
			(start 1.651 -1.778)
			(end -1.651 -1.778)
			(stroke
				(width 0.1524)
				(type default)
			)
			(layer "F.SilkS")
		)
		(fp_line
			(start -1.651 -1.778)
			(end -1.651 1.778)
			(stroke
				(width 0.1524)
				(type default)
			)
			(layer "F.SilkS")
		)
		(fp_line
			(start 1.651 1.778)
			(end 1.651 -1.778)
			(stroke
				(width 0.1524)
				(type default)
			)
			(layer "F.SilkS")
		)
		(fp_line
			(start -1.651 1.778)
			(end 1.651 1.778)
			(stroke
				(width 0.1524)
				(type default)
			)
			(layer "F.SilkS")
		)
		(fp_poly
			(pts
				(xy -1.778 1.8796) (xy -1.778 -1.8796) (xy 1.778 -1.8796) (xy 1.778 1.8796)
			)
			(stroke
				(width 0)
				(type default)
			)
			(fill no)
			(layer "F.CrtYd")
		)
		(fp_poly
			(pts
				(xy -1.778 1.8796) (xy -1.778 -1.8796) (xy 1.778 -1.8796) (xy 1.778 1.8796)
			)
			(stroke
				(width 0)
				(type default)
			)
			(fill no)
			(layer "F.Fab")
		)
		(pad "D" smd custom
			(at 0 -0.9525 90)
			(size 0.1905 0.1905)
			(layers "F.Cu" "F.Mask" "F.Paste")
			(net "P12V_MOST10_GATE_D")
			(options
				(clearance outline)
				(anchor circle)
			)
			(primitives
				(gr_poly
					(pts
						(arc
							(start -0.1778 0.5715)
							(mid -0.321484 0.511984)
							(end -0.381 0.3683)
						)
						(arc
							(start -0.381 -0.3683)
							(mid -0.321484 -0.511984)
							(end -0.1778 -0.5715)
						)
						(arc
							(start 0.1778 -0.5715)
							(mid 0.321484 -0.511984)
							(end 0.381 -0.3683)
						)
						(arc
							(start 0.381 0.3683)
							(mid 0.321484 0.511984)
							(end 0.1778 0.5715)
						)
					)
					(width 0)
					(fill yes)
				)
			)
		)
		(pad "G" smd custom
			(at -0.98425 0.9525 90)
			(size 0.1905 0.1905)
			(layers "F.Cu" "F.Mask" "F.Paste")
			(net "P12V_MOST10_GATE")
			(options
				(clearance outline)
				(anchor circle)
			)
			(primitives
				(gr_poly
					(pts
						(arc
							(start -0.1778 0.5715)
							(mid -0.321484 0.511984)
							(end -0.381 0.3683)
						)
						(arc
							(start -0.381 -0.3683)
							(mid -0.321484 -0.511984)
							(end -0.1778 -0.5715)
						)
						(arc
							(start 0.1778 -0.5715)
							(mid 0.321484 -0.511984)
							(end 0.381 -0.3683)
						)
						(arc
							(start 0.381 0.3683)
							(mid 0.321484 0.511984)
							(end 0.1778 0.5715)
						)
					)
					(width 0)
					(fill yes)
				)
			)
		)
		(pad "S" smd custom
			(at 0.98425 0.9525 90)
			(size 0.1905 0.1905)
			(layers "F.Cu" "F.Mask" "F.Paste")
			(net "GND")
			(options
				(clearance outline)
				(anchor circle)
			)
			(primitives
				(gr_poly
					(pts
						(arc
							(start -0.1778 0.5715)
							(mid -0.321484 0.511984)
							(end -0.381 0.3683)
						)
						(arc
							(start -0.381 -0.3683)
							(mid -0.321484 -0.511984)
							(end -0.1778 -0.5715)
						)
						(arc
							(start 0.1778 -0.5715)
							(mid 0.321484 -0.511984)
							(end 0.381 -0.3683)
						)
						(arc
							(start 0.381 0.3683)
							(mid 0.321484 0.511984)
							(end 0.1778 0.5715)
						)
					)
					(width 0)
					(fill yes)
				)
			)
		)
	)
	(footprint ""
		(layer "F.Cu")
		(at 73.914 -354.965 180)
		(property "Reference" "R430"
			(at 0 0 180)
			(layer "F.SilkS")
			(hide yes)
			(effects
				(font
					(size 1.27 1.27)
				)
			)
		)
		(property "Value" "0R2J-2-GP"
			(at 0.064008 -3.993896 180)
			(unlocked yes)
			(layer "F.Fab")
			(hide yes)
			(effects
				(font
					(size 1.016 1.016)
					(thickness 0.1524)
				)
			)
		)
		(property "Device Type" "R402H16"
			(at 0.064008 -5.517896 180)
			(unlocked yes)
			(layer "F.Fab")
			(hide yes)
			(effects
				(font
					(size 1.016 1.016)
					(thickness 0.1524)
				)
			)
		)
		(duplicate_pad_numbers_are_jumpers no)
		(fp_line
			(start 0.508 -0.9398)
			(end -0.508 -0.9398)
			(stroke
				(width 0.1524)
				(type default)
			)
			(layer "F.SilkS")
		)
		(fp_line
			(start -0.508 -0.9398)
			(end -0.508 0.9398)
			(stroke
				(width 0.1524)
				(type default)
			)
			(layer "F.SilkS")
		)
		(fp_rect
			(start -0.508 0.9398)
			(end 0.508 -0.9398)
			(stroke
				(width 0)
				(type default)
			)
			(fill no)
			(layer "F.CrtYd")
		)
		(fp_rect
			(start -0.508 0.9398)
			(end 0.508 -0.9398)
			(stroke
				(width 0)
				(type default)
			)
			(fill no)
			(layer "F.Fab")
		)
		(pad "1" smd custom
			(at 0 -0.4445 180)
			(size 0.1397 0.1397)
			(layers "F.Cu" "F.Mask" "F.Paste")
			(net "BMC_I2C_SDA_BUF_9")
			(options
				(clearance outline)
				(anchor circle)
			)
			(primitives
				(gr_poly
					(pts
						(arc
							(start -0.1778 -0.2794)
							(mid -0.249642 -0.249642)
							(end -0.2794 -0.1778)
						)
						(arc
							(start -0.2794 0.1778)
							(mid -0.249642 0.249642)
							(end -0.1778 0.2794)
						)
						(arc
							(start 0.1778 0.2794)
							(mid 0.249642 0.249642)
							(end 0.2794 0.1778)
						)
						(arc
							(start 0.2794 -0.1778)
							(mid 0.249642 -0.249642)
							(end 0.1778 -0.2794)
						)
					)
					(width 0)
					(fill yes)
				)
			)
		)
		(pad "2" smd custom
			(at 0 0.4445 180)
			(size 0.1397 0.1397)
			(layers "F.Cu" "F.Mask" "F.Paste")
			(net "I2C8_SDA_R_SW_EU17")
			(options
				(clearance outline)
				(anchor circle)
			)
			(primitives
				(gr_poly
					(pts
						(arc
							(start -0.1778 -0.2794)
							(mid -0.249642 -0.249642)
							(end -0.2794 -0.1778)
						)
						(arc
							(start -0.2794 0.1778)
							(mid -0.249642 0.249642)
							(end -0.1778 0.2794)
						)
						(arc
							(start 0.1778 0.2794)
							(mid 0.249642 0.249642)
							(end 0.2794 0.1778)
						)
						(arc
							(start 0.2794 -0.1778)
							(mid 0.249642 -0.249642)
							(end 0.1778 -0.2794)
						)
					)
					(width 0)
					(fill yes)
				)
			)
		)
	)
	(footprint ""
		(layer "F.Cu")
		(at 49.022 -452.501 -90)
		(property "Reference" "R9897"
			(at 0 0 270)
			(layer "F.SilkS")
			(hide yes)
			(effects
				(font
					(size 1.27 1.27)
				)
			)
		)
		(property "Value" "1K82R2F-1-GP"
			(at 0.064008 -3.993896 270)
			(unlocked yes)
			(layer "F.Fab")
			(hide yes)
			(effects
				(font
					(size 1.016 1.016)
					(thickness 0.1524)
				)
			)
		)
		(property "Device Type" "R402H16"
			(at 0.064008 -5.517896 270)
			(unlocked yes)
			(layer "F.Fab")
			(hide yes)
			(effects
				(font
					(size 1.016 1.016)
					(thickness 0.1524)
				)
			)
		)
		(duplicate_pad_numbers_are_jumpers no)
		(fp_line
			(start -0.508 -0.9398)
			(end -0.508 0.9398)
			(stroke
				(width 0.1524)
				(type default)
			)
			(layer "F.SilkS")
		)
		(fp_line
			(start 0.508 -0.9398)
			(end -0.508 -0.9398)
			(stroke
				(width 0.1524)
				(type default)
			)
			(layer "F.SilkS")
		)
		(fp_rect
			(start -0.508 0.9398)
			(end 0.508 -0.9398)
			(stroke
				(width 0)
				(type default)
			)
			(fill no)
			(layer "F.CrtYd")
		)
		(fp_rect
			(start -0.508 0.9398)
			(end 0.508 -0.9398)
			(stroke
				(width 0)
				(type default)
			)
			(fill no)
			(layer "F.Fab")
		)
		(pad "1" smd custom
			(at 0 -0.4445 270)
			(size 0.1397 0.1397)
			(layers "F.Cu" "F.Mask" "F.Paste")
			(net "P12V")
			(options
				(clearance outline)
				(anchor circle)
			)
			(primitives
				(gr_poly
					(pts
						(arc
							(start -0.1778 -0.2794)
							(mid -0.249642 -0.249642)
							(end -0.2794 -0.1778)
						)
						(arc
							(start -0.2794 0.1778)
							(mid -0.249642 0.249642)
							(end -0.1778 0.2794)
						)
						(arc
							(start 0.1778 0.2794)
							(mid 0.249642 0.249642)
							(end 0.2794 0.1778)
						)
						(arc
							(start 0.2794 -0.1778)
							(mid 0.249642 -0.249642)
							(end 0.1778 -0.2794)
						)
					)
					(width 0)
					(fill yes)
				)
			)
		)
		(pad "2" smd custom
			(at 0 0.4445 270)
			(size 0.1397 0.1397)
			(layers "F.Cu" "F.Mask" "F.Paste")
			(net "DRV_ACT_5")
			(options
				(clearance outline)
				(anchor circle)
			)
			(primitives
				(gr_poly
					(pts
						(arc
							(start -0.1778 -0.2794)
							(mid -0.249642 -0.249642)
							(end -0.2794 -0.1778)
						)
						(arc
							(start -0.2794 0.1778)
							(mid -0.249642 0.249642)
							(end -0.1778 0.2794)
						)
						(arc
							(start 0.1778 0.2794)
							(mid 0.249642 0.249642)
							(end 0.2794 0.1778)
						)
						(arc
							(start 0.2794 -0.1778)
							(mid 0.249642 -0.249642)
							(end 0.1778 -0.2794)
						)
					)
					(width 0)
					(fill yes)
				)
			)
		)
	)
	(footprint ""
		(layer "F.Cu")
		(at 38.241478 -35.052)
		(property "Reference" "R9921"
			(at 0 0 0)
			(layer "F.SilkS")
			(hide yes)
			(effects
				(font
					(size 1.27 1.27)
				)
			)
		)
		(property "Value" "47KR2J-2-GP"
			(at 0.064008 -3.993896 0)
			(unlocked yes)
			(layer "F.Fab")
			(hide yes)
			(effects
				(font
					(size 1.016 1.016)
					(thickness 0.1524)
				)
			)
		)
		(property "Device Type" "R402H16"
			(at 0.064008 -5.517896 0)
			(unlocked yes)
			(layer "F.Fab")
			(hide yes)
			(effects
				(font
					(size 1.016 1.016)
					(thickness 0.1524)
				)
			)
		)
		(duplicate_pad_numbers_are_jumpers no)
		(fp_line
			(start -0.508 -0.9398)
			(end -0.508 0.9398)
			(stroke
				(width 0.1524)
				(type default)
			)
			(layer "F.SilkS")
		)
		(fp_line
			(start 0.508 -0.9398)
			(end -0.508 -0.9398)
			(stroke
				(width 0.1524)
				(type default)
			)
			(layer "F.SilkS")
		)
		(fp_rect
			(start -0.508 0.9398)
			(end 0.508 -0.9398)
			(stroke
				(width 0)
				(type default)
			)
			(fill no)
			(layer "F.CrtYd")
		)
		(fp_rect
			(start -0.508 0.9398)
			(end 0.508 -0.9398)
			(stroke
				(width 0)
				(type default)
			)
			(fill no)
			(layer "F.Fab")
		)
		(pad "1" smd custom
			(at 0 -0.4445)
			(size 0.1397 0.1397)
			(layers "F.Cu" "F.Mask" "F.Paste")
			(net "P3V3")
			(options
				(clearance outline)
				(anchor circle)
			)
			(primitives
				(gr_poly
					(pts
						(arc
							(start -0.1778 -0.2794)
							(mid -0.249642 -0.249642)
							(end -0.2794 -0.1778)
						)
						(arc
							(start -0.2794 0.1778)
							(mid -0.249642 0.249642)
							(end -0.1778 0.2794)
						)
						(arc
							(start 0.1778 0.2794)
							(mid 0.249642 0.249642)
							(end 0.2794 0.1778)
						)
						(arc
							(start 0.2794 -0.1778)
							(mid 0.249642 -0.249642)
							(end 0.1778 -0.2794)
						)
					)
					(width 0)
					(fill yes)
				)
			)
		)
		(pad "2" smd custom
			(at 0 0.4445)
			(size 0.1397 0.1397)
			(layers "F.Cu" "F.Mask" "F.Paste")
			(net "ATTN_LED_DR9_N")
			(options
				(clearance outline)
				(anchor circle)
			)
			(primitives
				(gr_poly
					(pts
						(arc
							(start -0.1778 -0.2794)
							(mid -0.249642 -0.249642)
							(end -0.2794 -0.1778)
						)
						(arc
							(start -0.2794 0.1778)
							(mid -0.249642 0.249642)
							(end -0.1778 0.2794)
						)
						(arc
							(start 0.1778 0.2794)
							(mid 0.249642 0.249642)
							(end 0.2794 0.1778)
						)
						(arc
							(start 0.2794 -0.1778)
							(mid 0.249642 -0.249642)
							(end 0.1778 -0.2794)
						)
					)
					(width 0)
					(fill yes)
				)
			)
		)
	)
	(footprint ""
		(layer "F.Cu")
		(at 30.607 -205.0034 90)
		(property "Reference" "Q86"
			(at 0 0 90)
			(layer "F.SilkS")
			(hide yes)
			(effects
				(font
					(size 1.27 1.27)
				)
			)
		)
		(property "Value" "2N7002A-7-GP"
			(at 0.127 -8.9662 90)
			(unlocked yes)
			(layer "F.Fab")
			(hide yes)
			(effects
				(font
					(size 1.016 1.016)
					(thickness 0.1524)
				)
			)
		)
		(property "Device Type" "SOT23DGS2D4H48"
			(at 0.127 -10.4902 90)
			(unlocked yes)
			(layer "F.Fab")
			(hide yes)
			(effects
				(font
					(size 1.016 1.016)
					(thickness 0.1524)
				)
			)
		)
		(duplicate_pad_numbers_are_jumpers no)
		(fp_line
			(start 1.651 -1.778)
			(end -1.651 -1.778)
			(stroke
				(width 0.1524)
				(type default)
			)
			(layer "F.SilkS")
		)
		(fp_line
			(start -1.651 -1.778)
			(end -1.651 1.778)
			(stroke
				(width 0.1524)
				(type default)
			)
			(layer "F.SilkS")
		)
		(fp_line
			(start 1.651 1.778)
			(end 1.651 -1.778)
			(stroke
				(width 0.1524)
				(type default)
			)
			(layer "F.SilkS")
		)
		(fp_line
			(start -1.651 1.778)
			(end 1.651 1.778)
			(stroke
				(width 0.1524)
				(type default)
			)
			(layer "F.SilkS")
		)
		(fp_poly
			(pts
				(xy -1.778 1.8796) (xy -1.778 -1.8796) (xy 1.778 -1.8796) (xy 1.778 1.8796)
			)
			(stroke
				(width 0)
				(type default)
			)
			(fill no)
			(layer "F.CrtYd")
		)
		(fp_poly
			(pts
				(xy -1.778 1.8796) (xy -1.778 -1.8796) (xy 1.778 -1.8796) (xy 1.778 1.8796)
			)
			(stroke
				(width 0)
				(type default)
			)
			(fill no)
			(layer "F.Fab")
		)
		(pad "D" smd custom
			(at 0 -0.9525 90)
			(size 0.1905 0.1905)
			(layers "F.Cu" "F.Mask" "F.Paste")
			(net "P12V_MOST12_GATE_D")
			(options
				(clearance outline)
				(anchor circle)
			)
			(primitives
				(gr_poly
					(pts
						(arc
							(start -0.1778 0.5715)
							(mid -0.321484 0.511984)
							(end -0.381 0.3683)
						)
						(arc
							(start -0.381 -0.3683)
							(mid -0.321484 -0.511984)
							(end -0.1778 -0.5715)
						)
						(arc
							(start 0.1778 -0.5715)
							(mid 0.321484 -0.511984)
							(end 0.381 -0.3683)
						)
						(arc
							(start 0.381 0.3683)
							(mid 0.321484 0.511984)
							(end 0.1778 0.5715)
						)
					)
					(width 0)
					(fill yes)
				)
			)
		)
		(pad "G" smd custom
			(at -0.98425 0.9525 90)
			(size 0.1905 0.1905)
			(layers "F.Cu" "F.Mask" "F.Paste")
			(net "P12V_MOST12_GATE")
			(options
				(clearance outline)
				(anchor circle)
			)
			(primitives
				(gr_poly
					(pts
						(arc
							(start -0.1778 0.5715)
							(mid -0.321484 0.511984)
							(end -0.381 0.3683)
						)
						(arc
							(start -0.381 -0.3683)
							(mid -0.321484 -0.511984)
							(end -0.1778 -0.5715)
						)
						(arc
							(start 0.1778 -0.5715)
							(mid 0.321484 -0.511984)
							(end 0.381 -0.3683)
						)
						(arc
							(start 0.381 0.3683)
							(mid 0.321484 0.511984)
							(end 0.1778 0.5715)
						)
					)
					(width 0)
					(fill yes)
				)
			)
		)
		(pad "S" smd custom
			(at 0.98425 0.9525 90)
			(size 0.1905 0.1905)
			(layers "F.Cu" "F.Mask" "F.Paste")
			(net "GND")
			(options
				(clearance outline)
				(anchor circle)
			)
			(primitives
				(gr_poly
					(pts
						(arc
							(start -0.1778 0.5715)
							(mid -0.321484 0.511984)
							(end -0.381 0.3683)
						)
						(arc
							(start -0.381 -0.3683)
							(mid -0.321484 -0.511984)
							(end -0.1778 -0.5715)
						)
						(arc
							(start 0.1778 -0.5715)
							(mid 0.321484 -0.511984)
							(end 0.381 -0.3683)
						)
						(arc
							(start 0.381 0.3683)
							(mid 0.321484 0.511984)
							(end 0.1778 0.5715)
						)
					)
					(width 0)
					(fill yes)
				)
			)
		)
	)
	(footprint ""
		(layer "F.Cu")
		(at 243.586 -422.148 180)
		(property "Reference" "R370"
			(at 0 0 180)
			(layer "F.SilkS")
			(hide yes)
			(effects
				(font
					(size 1.27 1.27)
				)
			)
		)
		(property "Value" "4K7R2J-2-GP"
			(at 0.064008 -3.993896 180)
			(unlocked yes)
			(layer "F.Fab")
			(hide yes)
			(effects
				(font
					(size 1.016 1.016)
					(thickness 0.1524)
				)
			)
		)
		(property "Device Type" "R402H16"
			(at 0.064008 -5.517896 180)
			(unlocked yes)
			(layer "F.Fab")
			(hide yes)
			(effects
				(font
					(size 1.016 1.016)
					(thickness 0.1524)
				)
			)
		)
		(duplicate_pad_numbers_are_jumpers no)
		(fp_line
			(start 0.508 -0.9398)
			(end -0.508 -0.9398)
			(stroke
				(width 0.1524)
				(type default)
			)
			(layer "F.SilkS")
		)
		(fp_line
			(start -0.508 -0.9398)
			(end -0.508 0.9398)
			(stroke
				(width 0.1524)
				(type default)
			)
			(layer "F.SilkS")
		)
		(fp_rect
			(start -0.508 0.9398)
			(end 0.508 -0.9398)
			(stroke
				(width 0)
				(type default)
			)
			(fill no)
			(layer "F.CrtYd")
		)
		(fp_rect
			(start -0.508 0.9398)
			(end 0.508 -0.9398)
			(stroke
				(width 0)
				(type default)
			)
			(fill no)
			(layer "F.Fab")
		)
		(pad "1" smd custom
			(at 0 -0.4445 180)
			(size 0.1397 0.1397)
			(layers "F.Cu" "F.Mask" "F.Paste")
			(net "P3V3")
			(options
				(clearance outline)
				(anchor circle)
			)
			(primitives
				(gr_poly
					(pts
						(arc
							(start -0.1778 -0.2794)
							(mid -0.249642 -0.249642)
							(end -0.2794 -0.1778)
						)
						(arc
							(start -0.2794 0.1778)
							(mid -0.249642 0.249642)
							(end -0.1778 0.2794)
						)
						(arc
							(start 0.1778 0.2794)
							(mid 0.249642 0.249642)
							(end 0.2794 0.1778)
						)
						(arc
							(start 0.2794 -0.1778)
							(mid 0.249642 -0.249642)
							(end 0.1778 -0.2794)
						)
					)
					(width 0)
					(fill yes)
				)
			)
		)
		(pad "2" smd custom
			(at 0 0.4445 180)
			(size 0.1397 0.1397)
			(layers "F.Cu" "F.Mask" "F.Paste")
			(net "I2C_C_SDA")
			(options
				(clearance outline)
				(anchor circle)
			)
			(primitives
				(gr_poly
					(pts
						(arc
							(start -0.1778 -0.2794)
							(mid -0.249642 -0.249642)
							(end -0.2794 -0.1778)
						)
						(arc
							(start -0.2794 0.1778)
							(mid -0.249642 0.249642)
							(end -0.1778 0.2794)
						)
						(arc
							(start 0.1778 0.2794)
							(mid 0.249642 0.249642)
							(end 0.2794 0.1778)
						)
						(arc
							(start 0.2794 -0.1778)
							(mid 0.249642 -0.249642)
							(end 0.1778 -0.2794)
						)
					)
					(width 0)
					(fill yes)
				)
			)
		)
	)
	(footprint ""
		(layer "F.Cu")
		(at 234.061 -342.007952 90)
		(property "Reference" "R9787"
			(at 0 0 90)
			(layer "F.SilkS")
			(hide yes)
			(effects
				(font
					(size 1.27 1.27)
				)
			)
		)
		(property "Value" "0R2J-2-GP"
			(at 0.064008 -3.993896 90)
			(unlocked yes)
			(layer "F.Fab")
			(hide yes)
			(effects
				(font
					(size 1.016 1.016)
					(thickness 0.1524)
				)
			)
		)
		(property "Device Type" "R402H16"
			(at 0.064008 -5.517896 90)
			(unlocked yes)
			(layer "F.Fab")
			(hide yes)
			(effects
				(font
					(size 1.016 1.016)
					(thickness 0.1524)
				)
			)
		)
		(duplicate_pad_numbers_are_jumpers no)
		(fp_line
			(start 0.508 -0.9398)
			(end -0.508 -0.9398)
			(stroke
				(width 0.1524)
				(type default)
			)
			(layer "F.SilkS")
		)
		(fp_line
			(start -0.508 -0.9398)
			(end -0.508 0.9398)
			(stroke
				(width 0.1524)
				(type default)
			)
			(layer "F.SilkS")
		)
		(fp_rect
			(start -0.508 0.9398)
			(end 0.508 -0.9398)
			(stroke
				(width 0)
				(type default)
			)
			(fill no)
			(layer "F.CrtYd")
		)
		(fp_rect
			(start -0.508 0.9398)
			(end 0.508 -0.9398)
			(stroke
				(width 0)
				(type default)
			)
			(fill no)
			(layer "F.Fab")
		)
		(pad "1" smd custom
			(at 0 -0.4445 90)
			(size 0.1397 0.1397)
			(layers "F.Cu" "F.Mask" "F.Paste")
			(net "ATTN_LED_DR1_AND")
			(options
				(clearance outline)
				(anchor circle)
			)
			(primitives
				(gr_poly
					(pts
						(arc
							(start -0.1778 -0.2794)
							(mid -0.249642 -0.249642)
							(end -0.2794 -0.1778)
						)
						(arc
							(start -0.2794 0.1778)
							(mid -0.249642 0.249642)
							(end -0.1778 0.2794)
						)
						(arc
							(start 0.1778 0.2794)
							(mid 0.249642 0.249642)
							(end 0.2794 0.1778)
						)
						(arc
							(start 0.2794 -0.1778)
							(mid 0.249642 -0.249642)
							(end 0.1778 -0.2794)
						)
					)
					(width 0)
					(fill yes)
				)
			)
		)
		(pad "2" smd custom
			(at 0 0.4445 90)
			(size 0.1397 0.1397)
			(layers "F.Cu" "F.Mask" "F.Paste")
			(net "ATTN_LED_DR1_AND_R")
			(options
				(clearance outline)
				(anchor circle)
			)
			(primitives
				(gr_poly
					(pts
						(arc
							(start -0.1778 -0.2794)
							(mid -0.249642 -0.249642)
							(end -0.2794 -0.1778)
						)
						(arc
							(start -0.2794 0.1778)
							(mid -0.249642 0.249642)
							(end -0.1778 0.2794)
						)
						(arc
							(start 0.1778 0.2794)
							(mid 0.249642 0.249642)
							(end 0.2794 0.1778)
						)
						(arc
							(start 0.2794 -0.1778)
							(mid 0.249642 -0.249642)
							(end 0.1778 -0.2794)
						)
					)
					(width 0)
					(fill yes)
				)
			)
		)
	)
	(footprint ""
		(layer "F.Cu")
		(at 50.038 -14.859)
		(property "Reference" "R583"
			(at 0 0 0)
			(layer "F.SilkS")
			(hide yes)
			(effects
				(font
					(size 1.27 1.27)
				)
			)
		)
		(property "Value" "300KR2F-GP"
			(at 0.064008 -3.993896 0)
			(unlocked yes)
			(layer "F.Fab")
			(hide yes)
			(effects
				(font
					(size 1.016 1.016)
					(thickness 0.1524)
				)
			)
		)
		(property "Device Type" "R402H16"
			(at 0.064008 -5.517896 0)
			(unlocked yes)
			(layer "F.Fab")
			(hide yes)
			(effects
				(font
					(size 1.016 1.016)
					(thickness 0.1524)
				)
			)
		)
		(duplicate_pad_numbers_are_jumpers no)
		(fp_line
			(start -0.508 -0.9398)
			(end -0.508 0.9398)
			(stroke
				(width 0.1524)
				(type default)
			)
			(layer "F.SilkS")
		)
		(fp_line
			(start 0.508 -0.9398)
			(end -0.508 -0.9398)
			(stroke
				(width 0.1524)
				(type default)
			)
			(layer "F.SilkS")
		)
		(fp_rect
			(start -0.508 0.9398)
			(end 0.508 -0.9398)
			(stroke
				(width 0)
				(type default)
			)
			(fill no)
			(layer "F.CrtYd")
		)
		(fp_rect
			(start -0.508 0.9398)
			(end 0.508 -0.9398)
			(stroke
				(width 0)
				(type default)
			)
			(fill no)
			(layer "F.Fab")
		)
		(pad "1" smd custom
			(at 0 -0.4445)
			(size 0.1397 0.1397)
			(layers "F.Cu" "F.Mask" "F.Paste")
			(net "SW_SSD14_N")
			(options
				(clearance outline)
				(anchor circle)
			)
			(primitives
				(gr_poly
					(pts
						(arc
							(start -0.1778 -0.2794)
							(mid -0.249642 -0.249642)
							(end -0.2794 -0.1778)
						)
						(arc
							(start -0.2794 0.1778)
							(mid -0.249642 0.249642)
							(end -0.1778 0.2794)
						)
						(arc
							(start 0.1778 0.2794)
							(mid 0.249642 0.249642)
							(end 0.2794 0.1778)
						)
						(arc
							(start 0.2794 -0.1778)
							(mid 0.249642 -0.249642)
							(end 0.1778 -0.2794)
						)
					)
					(width 0)
					(fill yes)
				)
			)
		)
		(pad "2" smd custom
			(at 0 0.4445)
			(size 0.1397 0.1397)
			(layers "F.Cu" "F.Mask" "F.Paste")
			(net "P12V")
			(options
				(clearance outline)
				(anchor circle)
			)
			(primitives
				(gr_poly
					(pts
						(arc
							(start -0.1778 -0.2794)
							(mid -0.249642 -0.249642)
							(end -0.2794 -0.1778)
						)
						(arc
							(start -0.2794 0.1778)
							(mid -0.249642 0.249642)
							(end -0.1778 0.2794)
						)
						(arc
							(start 0.1778 0.2794)
							(mid 0.249642 0.249642)
							(end 0.2794 0.1778)
						)
						(arc
							(start 0.2794 -0.1778)
							(mid 0.249642 -0.249642)
							(end 0.1778 -0.2794)
						)
					)
					(width 0)
					(fill yes)
				)
			)
		)
	)
	(footprint ""
		(layer "F.Cu")
		(at 52.07 -241.040158 180)
		(property "Reference" "Q64"
			(at 0 0 180)
			(layer "F.SilkS")
			(hide yes)
			(effects
				(font
					(size 1.27 1.27)
				)
			)
		)
		(property "Value" "2N7002A-7-GP"
			(at 0.127 -8.9662 180)
			(unlocked yes)
			(layer "F.Fab")
			(hide yes)
			(effects
				(font
					(size 1.016 1.016)
					(thickness 0.1524)
				)
			)
		)
		(property "Device Type" "SOT23DGS2D4H48"
			(at 0.127 -10.4902 180)
			(unlocked yes)
			(layer "F.Fab")
			(hide yes)
			(effects
				(font
					(size 1.016 1.016)
					(thickness 0.1524)
				)
			)
		)
		(duplicate_pad_numbers_are_jumpers no)
		(fp_line
			(start 1.651 1.778)
			(end 1.651 -1.778)
			(stroke
				(width 0.1524)
				(type default)
			)
			(layer "F.SilkS")
		)
		(fp_line
			(start 1.651 -1.778)
			(end -1.651 -1.778)
			(stroke
				(width 0.1524)
				(type default)
			)
			(layer "F.SilkS")
		)
		(fp_line
			(start -1.651 1.778)
			(end 1.651 1.778)
			(stroke
				(width 0.1524)
				(type default)
			)
			(layer "F.SilkS")
		)
		(fp_line
			(start -1.651 -1.778)
			(end -1.651 1.778)
			(stroke
				(width 0.1524)
				(type default)
			)
			(layer "F.SilkS")
		)
		(fp_poly
			(pts
				(xy -1.778 1.8796) (xy -1.778 -1.8796) (xy 1.778 -1.8796) (xy 1.778 1.8796)
			)
			(stroke
				(width 0)
				(type default)
			)
			(fill no)
			(layer "F.CrtYd")
		)
		(fp_poly
			(pts
				(xy -1.778 1.8796) (xy -1.778 -1.8796) (xy 1.778 -1.8796) (xy 1.778 1.8796)
			)
			(stroke
				(width 0)
				(type default)
			)
			(fill no)
			(layer "F.Fab")
		)
		(pad "D" smd custom
			(at 0 -0.9525 180)
			(size 0.1905 0.1905)
			(layers "F.Cu" "F.Mask" "F.Paste")
			(net "SSD7_CLK0_OE_MOS_N")
			(options
				(clearance outline)
				(anchor circle)
			)
			(primitives
				(gr_poly
					(pts
						(arc
							(start -0.1778 0.5715)
							(mid -0.321484 0.511984)
							(end -0.381 0.3683)
						)
						(arc
							(start -0.381 -0.3683)
							(mid -0.321484 -0.511984)
							(end -0.1778 -0.5715)
						)
						(arc
							(start 0.1778 -0.5715)
							(mid 0.321484 -0.511984)
							(end 0.381 -0.3683)
						)
						(arc
							(start 0.381 0.3683)
							(mid 0.321484 0.511984)
							(end 0.1778 0.5715)
						)
					)
					(width 0)
					(fill yes)
				)
			)
		)
		(pad "G" smd custom
			(at -0.98425 0.9525 180)
			(size 0.1905 0.1905)
			(layers "F.Cu" "F.Mask" "F.Paste")
			(net "SSD7_CLK0_OE_R_N")
			(options
				(clearance outline)
				(anchor circle)
			)
			(primitives
				(gr_poly
					(pts
						(arc
							(start -0.1778 0.5715)
							(mid -0.321484 0.511984)
							(end -0.381 0.3683)
						)
						(arc
							(start -0.381 -0.3683)
							(mid -0.321484 -0.511984)
							(end -0.1778 -0.5715)
						)
						(arc
							(start 0.1778 -0.5715)
							(mid 0.321484 -0.511984)
							(end 0.381 -0.3683)
						)
						(arc
							(start 0.381 0.3683)
							(mid 0.321484 0.511984)
							(end 0.1778 0.5715)
						)
					)
					(width 0)
					(fill yes)
				)
			)
		)
		(pad "S" smd custom
			(at 0.98425 0.9525 180)
			(size 0.1905 0.1905)
			(layers "F.Cu" "F.Mask" "F.Paste")
			(net "GND")
			(options
				(clearance outline)
				(anchor circle)
			)
			(primitives
				(gr_poly
					(pts
						(arc
							(start -0.1778 0.5715)
							(mid -0.321484 0.511984)
							(end -0.381 0.3683)
						)
						(arc
							(start -0.381 -0.3683)
							(mid -0.321484 -0.511984)
							(end -0.1778 -0.5715)
						)
						(arc
							(start 0.1778 -0.5715)
							(mid 0.321484 -0.511984)
							(end 0.381 -0.3683)
						)
						(arc
							(start 0.381 0.3683)
							(mid 0.321484 0.511984)
							(end 0.1778 0.5715)
						)
					)
					(width 0)
					(fill yes)
				)
			)
		)
	)
	(footprint ""
		(layer "F.Cu")
		(at 194.243706 -498.222778 180)
		(property "Reference" "R9495"
			(at 0 0 180)
			(layer "F.SilkS")
			(hide yes)
			(effects
				(font
					(size 1.27 1.27)
				)
			)
		)
		(property "Value" "4K7R2J-2-GP"
			(at 0.064008 -3.993896 180)
			(unlocked yes)
			(layer "F.Fab")
			(hide yes)
			(effects
				(font
					(size 1.016 1.016)
					(thickness 0.1524)
				)
			)
		)
		(property "Device Type" "R402H16"
			(at 0.064008 -5.517896 180)
			(unlocked yes)
			(layer "F.Fab")
			(hide yes)
			(effects
				(font
					(size 1.016 1.016)
					(thickness 0.1524)
				)
			)
		)
		(duplicate_pad_numbers_are_jumpers no)
		(fp_line
			(start 0.508 -0.9398)
			(end -0.508 -0.9398)
			(stroke
				(width 0.1524)
				(type default)
			)
			(layer "F.SilkS")
		)
		(fp_line
			(start -0.508 -0.9398)
			(end -0.508 0.9398)
			(stroke
				(width 0.1524)
				(type default)
			)
			(layer "F.SilkS")
		)
		(fp_rect
			(start -0.508 0.9398)
			(end 0.508 -0.9398)
			(stroke
				(width 0)
				(type default)
			)
			(fill no)
			(layer "F.CrtYd")
		)
		(fp_rect
			(start -0.508 0.9398)
			(end 0.508 -0.9398)
			(stroke
				(width 0)
				(type default)
			)
			(fill no)
			(layer "F.Fab")
		)
		(pad "1" smd custom
			(at 0 -0.4445 180)
			(size 0.1397 0.1397)
			(layers "F.Cu" "F.Mask" "F.Paste")
			(net "P3V3")
			(options
				(clearance outline)
				(anchor circle)
			)
			(primitives
				(gr_poly
					(pts
						(arc
							(start -0.1778 -0.2794)
							(mid -0.249642 -0.249642)
							(end -0.2794 -0.1778)
						)
						(arc
							(start -0.2794 0.1778)
							(mid -0.249642 0.249642)
							(end -0.1778 0.2794)
						)
						(arc
							(start 0.1778 0.2794)
							(mid 0.249642 0.249642)
							(end 0.2794 0.1778)
						)
						(arc
							(start 0.2794 -0.1778)
							(mid 0.249642 -0.249642)
							(end 0.1778 -0.2794)
						)
					)
					(width 0)
					(fill yes)
				)
			)
		)
		(pad "2" smd custom
			(at 0 0.4445 180)
			(size 0.1397 0.1397)
			(layers "F.Cu" "F.Mask" "F.Paste")
			(net "SSD0_PWREN")
			(options
				(clearance outline)
				(anchor circle)
			)
			(primitives
				(gr_poly
					(pts
						(arc
							(start -0.1778 -0.2794)
							(mid -0.249642 -0.249642)
							(end -0.2794 -0.1778)
						)
						(arc
							(start -0.2794 0.1778)
							(mid -0.249642 0.249642)
							(end -0.1778 0.2794)
						)
						(arc
							(start 0.1778 0.2794)
							(mid 0.249642 0.249642)
							(end 0.2794 0.1778)
						)
						(arc
							(start 0.2794 -0.1778)
							(mid 0.249642 -0.249642)
							(end 0.1778 -0.2794)
						)
					)
					(width 0)
					(fill yes)
				)
			)
		)
	)
	(footprint ""
		(layer "F.Cu")
		(at 197.799706 -498.959378 -90)
		(property "Reference" "Q23"
			(at 0 0 270)
			(layer "F.SilkS")
			(hide yes)
			(effects
				(font
					(size 1.27 1.27)
				)
			)
		)
		(property "Value" "2N7002A-7-GP"
			(at 0.127 -8.9662 270)
			(unlocked yes)
			(layer "F.Fab")
			(hide yes)
			(effects
				(font
					(size 1.016 1.016)
					(thickness 0.1524)
				)
			)
		)
		(property "Device Type" "SOT23DGS2D4H48"
			(at 0.127 -10.4902 270)
			(unlocked yes)
			(layer "F.Fab")
			(hide yes)
			(effects
				(font
					(size 1.016 1.016)
					(thickness 0.1524)
				)
			)
		)
		(duplicate_pad_numbers_are_jumpers no)
		(fp_line
			(start -1.651 1.778)
			(end 1.651 1.778)
			(stroke
				(width 0.1524)
				(type default)
			)
			(layer "F.SilkS")
		)
		(fp_line
			(start 1.651 1.778)
			(end 1.651 -1.778)
			(stroke
				(width 0.1524)
				(type default)
			)
			(layer "F.SilkS")
		)
		(fp_line
			(start -1.651 -1.778)
			(end -1.651 1.778)
			(stroke
				(width 0.1524)
				(type default)
			)
			(layer "F.SilkS")
		)
		(fp_line
			(start 1.651 -1.778)
			(end -1.651 -1.778)
			(stroke
				(width 0.1524)
				(type default)
			)
			(layer "F.SilkS")
		)
		(fp_poly
			(pts
				(xy -1.778 1.8796) (xy -1.778 -1.8796) (xy 1.778 -1.8796) (xy 1.778 1.8796)
			)
			(stroke
				(width 0)
				(type default)
			)
			(fill no)
			(layer "F.CrtYd")
		)
		(fp_poly
			(pts
				(xy -1.778 1.8796) (xy -1.778 -1.8796) (xy 1.778 -1.8796) (xy 1.778 1.8796)
			)
			(stroke
				(width 0)
				(type default)
			)
			(fill no)
			(layer "F.Fab")
		)
		(pad "D" smd custom
			(at 0 -0.9525 270)
			(size 0.1905 0.1905)
			(layers "F.Cu" "F.Mask" "F.Paste")
			(net "P12V_MOST0_GATE")
			(options
				(clearance outline)
				(anchor circle)
			)
			(primitives
				(gr_poly
					(pts
						(arc
							(start -0.1778 0.5715)
							(mid -0.321484 0.511984)
							(end -0.381 0.3683)
						)
						(arc
							(start -0.381 -0.3683)
							(mid -0.321484 -0.511984)
							(end -0.1778 -0.5715)
						)
						(arc
							(start 0.1778 -0.5715)
							(mid 0.321484 -0.511984)
							(end 0.381 -0.3683)
						)
						(arc
							(start 0.381 0.3683)
							(mid 0.321484 0.511984)
							(end 0.1778 0.5715)
						)
					)
					(width 0)
					(fill yes)
				)
			)
		)
		(pad "G" smd custom
			(at -0.98425 0.9525 270)
			(size 0.1905 0.1905)
			(layers "F.Cu" "F.Mask" "F.Paste")
			(net "SSD0_PWREN_R")
			(options
				(clearance outline)
				(anchor circle)
			)
			(primitives
				(gr_poly
					(pts
						(arc
							(start -0.1778 0.5715)
							(mid -0.321484 0.511984)
							(end -0.381 0.3683)
						)
						(arc
							(start -0.381 -0.3683)
							(mid -0.321484 -0.511984)
							(end -0.1778 -0.5715)
						)
						(arc
							(start 0.1778 -0.5715)
							(mid 0.321484 -0.511984)
							(end 0.381 -0.3683)
						)
						(arc
							(start 0.381 0.3683)
							(mid 0.321484 0.511984)
							(end 0.1778 0.5715)
						)
					)
					(width 0)
					(fill yes)
				)
			)
		)
		(pad "S" smd custom
			(at 0.98425 0.9525 270)
			(size 0.1905 0.1905)
			(layers "F.Cu" "F.Mask" "F.Paste")
			(net "GND")
			(options
				(clearance outline)
				(anchor circle)
			)
			(primitives
				(gr_poly
					(pts
						(arc
							(start -0.1778 0.5715)
							(mid -0.321484 0.511984)
							(end -0.381 0.3683)
						)
						(arc
							(start -0.381 -0.3683)
							(mid -0.321484 -0.511984)
							(end -0.1778 -0.5715)
						)
						(arc
							(start 0.1778 -0.5715)
							(mid 0.321484 -0.511984)
							(end 0.381 -0.3683)
						)
						(arc
							(start 0.381 0.3683)
							(mid 0.321484 0.511984)
							(end 0.1778 0.5715)
						)
					)
					(width 0)
					(fill yes)
				)
			)
		)
	)
	(footprint ""
		(layer "F.Cu")
		(at 36.957 -400.431 180)
		(property "Reference" "PC1240"
			(at 0 0 180)
			(layer "F.SilkS")
			(hide yes)
			(effects
				(font
					(size 1.27 1.27)
				)
			)
		)
		(property "Value" "SC22U25V6KX-GP-U"
			(at -2.860802 -5.279644 180)
			(unlocked yes)
			(layer "F.Fab")
			(hide yes)
			(effects
				(font
					(size 1.016 1.016)
					(thickness 0.1524)
				)
			)
		)
		(property "Device Type" "C1206-TO0D3H75"
			(at -2.860802 -6.803644 180)
			(unlocked yes)
			(layer "F.Fab")
			(hide yes)
			(effects
				(font
					(size 1.016 1.016)
					(thickness 0.1524)
				)
			)
		)
		(duplicate_pad_numbers_are_jumpers no)
		(fp_line
			(start 1.3081 2.3749)
			(end -1.3081 2.3749)
			(stroke
				(width 0.1524)
				(type default)
			)
			(layer "F.SilkS")
		)
		(fp_line
			(start 1.3081 -2.3749)
			(end 1.3081 2.3749)
			(stroke
				(width 0.1524)
				(type default)
			)
			(layer "F.SilkS")
		)
		(fp_line
			(start -1.3081 2.3749)
			(end -1.3081 -2.3749)
			(stroke
				(width 0.1524)
				(type default)
			)
			(layer "F.SilkS")
		)
		(fp_line
			(start -1.3081 -2.3749)
			(end 1.3081 -2.3749)
			(stroke
				(width 0.1524)
				(type default)
			)
			(layer "F.SilkS")
		)
		(fp_rect
			(start -0.8001 1.6002)
			(end 0.8001 -1.6002)
			(stroke
				(width 0)
				(type default)
			)
			(fill no)
			(layer "F.CrtYd")
		)
		(fp_poly
			(pts
				(xy -1.5621 2.4511) (xy -1.5621 1.6002) (xy 0.8001 1.6002) (xy 0.8001 -1.6002) (xy -0.8001 -1.6002)
				(xy -0.8001 1.5875) (xy -1.5621 1.5875) (xy -1.5621 -2.4511) (xy 1.5621 -2.4511) (xy 1.5621 2.4511)
			)
			(stroke
				(width 0)
				(type default)
			)
			(fill no)
			(layer "F.CrtYd")
		)
		(fp_rect
			(start -1.5621 2.4511)
			(end 1.5621 -2.4511)
			(stroke
				(width 0)
				(type default)
			)
			(fill no)
			(layer "F.Fab")
		)
		(pad "1" smd rect
			(at 0 -1.392936 180)
			(size 2.1082 1.4478)
			(layers "F.Cu" "F.Mask" "F.Paste")
			(net "P12V_SSD6")
		)
		(pad "2" smd rect
			(at 0 1.392936 180)
			(size 2.1082 1.4478)
			(layers "F.Cu" "F.Mask" "F.Paste")
			(net "GND")
		)
	)
	(footprint ""
		(layer "F.Cu")
		(at 97.0788 -21.9456 180)
		(property "Reference" "R388"
			(at 0 0 180)
			(layer "F.SilkS")
			(hide yes)
			(effects
				(font
					(size 1.27 1.27)
				)
			)
		)
		(property "Value" "10KR2F-2-GP"
			(at 0.064008 -3.993896 180)
			(unlocked yes)
			(layer "F.Fab")
			(hide yes)
			(effects
				(font
					(size 1.016 1.016)
					(thickness 0.1524)
				)
			)
		)
		(property "Device Type" "R402H16"
			(at 0.064008 -5.517896 180)
			(unlocked yes)
			(layer "F.Fab")
			(hide yes)
			(effects
				(font
					(size 1.016 1.016)
					(thickness 0.1524)
				)
			)
		)
		(duplicate_pad_numbers_are_jumpers no)
		(fp_line
			(start 0.508 -0.9398)
			(end -0.508 -0.9398)
			(stroke
				(width 0.1524)
				(type default)
			)
			(layer "F.SilkS")
		)
		(fp_line
			(start -0.508 -0.9398)
			(end -0.508 0.9398)
			(stroke
				(width 0.1524)
				(type default)
			)
			(layer "F.SilkS")
		)
		(fp_rect
			(start -0.508 0.9398)
			(end 0.508 -0.9398)
			(stroke
				(width 0)
				(type default)
			)
			(fill no)
			(layer "F.CrtYd")
		)
		(fp_rect
			(start -0.508 0.9398)
			(end 0.508 -0.9398)
			(stroke
				(width 0)
				(type default)
			)
			(fill no)
			(layer "F.Fab")
		)
		(pad "1" smd custom
			(at 0 -0.4445 180)
			(size 0.1397 0.1397)
			(layers "F.Cu" "F.Mask" "F.Paste")
			(net "P12V_SSD14")
			(options
				(clearance outline)
				(anchor circle)
			)
			(primitives
				(gr_poly
					(pts
						(arc
							(start -0.1778 -0.2794)
							(mid -0.249642 -0.249642)
							(end -0.2794 -0.1778)
						)
						(arc
							(start -0.2794 0.1778)
							(mid -0.249642 0.249642)
							(end -0.1778 0.2794)
						)
						(arc
							(start 0.1778 0.2794)
							(mid 0.249642 0.249642)
							(end 0.2794 0.1778)
						)
						(arc
							(start 0.2794 -0.1778)
							(mid 0.249642 -0.249642)
							(end 0.1778 -0.2794)
						)
					)
					(width 0)
					(fill yes)
				)
			)
		)
		(pad "2" smd custom
			(at 0 0.4445 180)
			(size 0.1397 0.1397)
			(layers "F.Cu" "F.Mask" "F.Paste")
			(net "P12V_SSD14_SENSE")
			(options
				(clearance outline)
				(anchor circle)
			)
			(primitives
				(gr_poly
					(pts
						(arc
							(start -0.1778 -0.2794)
							(mid -0.249642 -0.249642)
							(end -0.2794 -0.1778)
						)
						(arc
							(start -0.2794 0.1778)
							(mid -0.249642 0.249642)
							(end -0.1778 0.2794)
						)
						(arc
							(start 0.1778 0.2794)
							(mid 0.249642 0.249642)
							(end 0.2794 0.1778)
						)
						(arc
							(start 0.2794 -0.1778)
							(mid 0.249642 -0.249642)
							(end 0.1778 -0.2794)
						)
					)
					(width 0)
					(fill yes)
				)
			)
		)
	)
	(footprint ""
		(layer "F.Cu")
		(at 230.632 -140.19911 -90)
		(property "Reference" "R9803"
			(at 0 0 270)
			(layer "F.SilkS")
			(hide yes)
			(effects
				(font
					(size 1.27 1.27)
				)
			)
		)
		(property "Value" "0R2J-2-GP"
			(at 0.064008 -3.993896 270)
			(unlocked yes)
			(layer "F.Fab")
			(hide yes)
			(effects
				(font
					(size 1.016 1.016)
					(thickness 0.1524)
				)
			)
		)
		(property "Device Type" "R402H16"
			(at 0.064008 -5.517896 270)
			(unlocked yes)
			(layer "F.Fab")
			(hide yes)
			(effects
				(font
					(size 1.016 1.016)
					(thickness 0.1524)
				)
			)
		)
		(duplicate_pad_numbers_are_jumpers no)
		(fp_line
			(start -0.508 -0.9398)
			(end -0.508 0.9398)
			(stroke
				(width 0.1524)
				(type default)
			)
			(layer "F.SilkS")
		)
		(fp_line
			(start 0.508 -0.9398)
			(end -0.508 -0.9398)
			(stroke
				(width 0.1524)
				(type default)
			)
			(layer "F.SilkS")
		)
		(fp_rect
			(start -0.508 0.9398)
			(end 0.508 -0.9398)
			(stroke
				(width 0)
				(type default)
			)
			(fill no)
			(layer "F.CrtYd")
		)
		(fp_rect
			(start -0.508 0.9398)
			(end 0.508 -0.9398)
			(stroke
				(width 0)
				(type default)
			)
			(fill no)
			(layer "F.Fab")
		)
		(pad "1" smd custom
			(at 0 -0.4445 270)
			(size 0.1397 0.1397)
			(layers "F.Cu" "F.Mask" "F.Paste")
			(net "SSD_ACT_DR3_R")
			(options
				(clearance outline)
				(anchor circle)
			)
			(primitives
				(gr_poly
					(pts
						(arc
							(start -0.1778 -0.2794)
							(mid -0.249642 -0.249642)
							(end -0.2794 -0.1778)
						)
						(arc
							(start -0.2794 0.1778)
							(mid -0.249642 0.249642)
							(end -0.1778 0.2794)
						)
						(arc
							(start 0.1778 0.2794)
							(mid 0.249642 0.249642)
							(end 0.2794 0.1778)
						)
						(arc
							(start 0.2794 -0.1778)
							(mid 0.249642 -0.249642)
							(end 0.1778 -0.2794)
						)
					)
					(width 0)
					(fill yes)
				)
			)
		)
		(pad "2" smd custom
			(at 0 0.4445 270)
			(size 0.1397 0.1397)
			(layers "F.Cu" "F.Mask" "F.Paste")
			(net "SSD_ACT_DR3")
			(options
				(clearance outline)
				(anchor circle)
			)
			(primitives
				(gr_poly
					(pts
						(arc
							(start -0.1778 -0.2794)
							(mid -0.249642 -0.249642)
							(end -0.2794 -0.1778)
						)
						(arc
							(start -0.2794 0.1778)
							(mid -0.249642 0.249642)
							(end -0.1778 0.2794)
						)
						(arc
							(start 0.1778 0.2794)
							(mid 0.249642 0.249642)
							(end 0.2794 0.1778)
						)
						(arc
							(start 0.2794 -0.1778)
							(mid 0.249642 -0.249642)
							(end 0.1778 -0.2794)
						)
					)
					(width 0)
					(fill yes)
				)
			)
		)
	)
	(footprint ""
		(layer "F.Cu")
		(at 24.003 -155.194 -90)
		(property "Reference" "R9422"
			(at 0 0 270)
			(layer "F.SilkS")
			(hide yes)
			(effects
				(font
					(size 1.27 1.27)
				)
			)
		)
		(property "Value" "100R2J-2-GP"
			(at 0.064008 -3.993896 270)
			(unlocked yes)
			(layer "F.Fab")
			(hide yes)
			(effects
				(font
					(size 1.016 1.016)
					(thickness 0.1524)
				)
			)
		)
		(property "Device Type" "R402H14"
			(at 0.064008 -5.517896 270)
			(unlocked yes)
			(layer "F.Fab")
			(hide yes)
			(effects
				(font
					(size 1.016 1.016)
					(thickness 0.1524)
				)
			)
		)
		(duplicate_pad_numbers_are_jumpers no)
		(fp_line
			(start -0.508 -0.9398)
			(end -0.508 0.9398)
			(stroke
				(width 0.1524)
				(type default)
			)
			(layer "F.SilkS")
		)
		(fp_line
			(start 0.508 -0.9398)
			(end -0.508 -0.9398)
			(stroke
				(width 0.1524)
				(type default)
			)
			(layer "F.SilkS")
		)
		(fp_rect
			(start -0.508 0.9398)
			(end 0.508 -0.9398)
			(stroke
				(width 0)
				(type default)
			)
			(fill no)
			(layer "F.CrtYd")
		)
		(fp_rect
			(start -0.508 0.9398)
			(end 0.508 -0.9398)
			(stroke
				(width 0)
				(type default)
			)
			(fill no)
			(layer "F.Fab")
		)
		(pad "1" smd custom
			(at 0 -0.4445 270)
			(size 0.1397 0.1397)
			(layers "F.Cu" "F.Mask" "F.Paste")
			(net "P3V3")
			(options
				(clearance outline)
				(anchor circle)
			)
			(primitives
				(gr_poly
					(pts
						(arc
							(start -0.1778 -0.2794)
							(mid -0.249642 -0.249642)
							(end -0.2794 -0.1778)
						)
						(arc
							(start -0.2794 0.1778)
							(mid -0.249642 0.249642)
							(end -0.1778 0.2794)
						)
						(arc
							(start 0.1778 0.2794)
							(mid 0.249642 0.249642)
							(end 0.2794 0.1778)
						)
						(arc
							(start 0.2794 -0.1778)
							(mid 0.249642 -0.249642)
							(end 0.1778 -0.2794)
						)
					)
					(width 0)
					(fill yes)
				)
			)
		)
		(pad "2" smd custom
			(at 0 0.4445 270)
			(size 0.1397 0.1397)
			(layers "F.Cu" "F.Mask" "F.Paste")
			(net "DRV_ACT_13")
			(options
				(clearance outline)
				(anchor circle)
			)
			(primitives
				(gr_poly
					(pts
						(arc
							(start -0.1778 -0.2794)
							(mid -0.249642 -0.249642)
							(end -0.2794 -0.1778)
						)
						(arc
							(start -0.2794 0.1778)
							(mid -0.249642 0.249642)
							(end -0.1778 0.2794)
						)
						(arc
							(start 0.1778 0.2794)
							(mid 0.249642 0.249642)
							(end 0.2794 0.1778)
						)
						(arc
							(start 0.2794 -0.1778)
							(mid 0.249642 -0.249642)
							(end 0.1778 -0.2794)
						)
					)
					(width 0)
					(fill yes)
				)
			)
		)
	)
	(footprint ""
		(layer "F.Cu")
		(at 84.455 -299.339 90)
		(property "Reference" "R9092"
			(at 0 0 90)
			(layer "F.SilkS")
			(hide yes)
			(effects
				(font
					(size 1.27 1.27)
				)
			)
		)
		(property "Value" "4K7R2F-GP"
			(at 0.064008 -3.993896 90)
			(unlocked yes)
			(layer "F.Fab")
			(hide yes)
			(effects
				(font
					(size 1.016 1.016)
					(thickness 0.1524)
				)
			)
		)
		(property "Device Type" "R402H16"
			(at 0.064008 -5.517896 90)
			(unlocked yes)
			(layer "F.Fab")
			(hide yes)
			(effects
				(font
					(size 1.016 1.016)
					(thickness 0.1524)
				)
			)
		)
		(duplicate_pad_numbers_are_jumpers no)
		(fp_line
			(start 0.508 -0.9398)
			(end -0.508 -0.9398)
			(stroke
				(width 0.1524)
				(type default)
			)
			(layer "F.SilkS")
		)
		(fp_line
			(start -0.508 -0.9398)
			(end -0.508 0.9398)
			(stroke
				(width 0.1524)
				(type default)
			)
			(layer "F.SilkS")
		)
		(fp_rect
			(start -0.508 0.9398)
			(end 0.508 -0.9398)
			(stroke
				(width 0)
				(type default)
			)
			(fill no)
			(layer "F.CrtYd")
		)
		(fp_rect
			(start -0.508 0.9398)
			(end 0.508 -0.9398)
			(stroke
				(width 0)
				(type default)
			)
			(fill no)
			(layer "F.Fab")
		)
		(pad "1" smd custom
			(at 0 -0.4445 90)
			(size 0.1397 0.1397)
			(layers "F.Cu" "F.Mask" "F.Paste")
			(net "VDD_DIFF_2")
			(options
				(clearance outline)
				(anchor circle)
			)
			(primitives
				(gr_poly
					(pts
						(arc
							(start -0.1778 -0.2794)
							(mid -0.249642 -0.249642)
							(end -0.2794 -0.1778)
						)
						(arc
							(start -0.2794 0.1778)
							(mid -0.249642 0.249642)
							(end -0.1778 0.2794)
						)
						(arc
							(start 0.1778 0.2794)
							(mid 0.249642 0.249642)
							(end 0.2794 0.1778)
						)
						(arc
							(start 0.2794 -0.1778)
							(mid 0.249642 -0.249642)
							(end 0.1778 -0.2794)
						)
					)
					(width 0)
					(fill yes)
				)
			)
		)
		(pad "2" smd custom
			(at 0 0.4445 90)
			(size 0.1397 0.1397)
			(layers "F.Cu" "F.Mask" "F.Paste")
			(net "CLK_BUF_EU2_SMB_A1_TRI")
			(options
				(clearance outline)
				(anchor circle)
			)
			(primitives
				(gr_poly
					(pts
						(arc
							(start -0.1778 -0.2794)
							(mid -0.249642 -0.249642)
							(end -0.2794 -0.1778)
						)
						(arc
							(start -0.2794 0.1778)
							(mid -0.249642 0.249642)
							(end -0.1778 0.2794)
						)
						(arc
							(start 0.1778 0.2794)
							(mid 0.249642 0.249642)
							(end 0.2794 0.1778)
						)
						(arc
							(start 0.2794 -0.1778)
							(mid 0.249642 -0.249642)
							(end 0.1778 -0.2794)
						)
					)
					(width 0)
					(fill yes)
				)
			)
		)
	)
	(footprint ""
		(layer "F.Cu")
		(at 90.297 -219.456 180)
		(property "Reference" "R9080"
			(at 0 0 180)
			(layer "F.SilkS")
			(hide yes)
			(effects
				(font
					(size 1.27 1.27)
				)
			)
		)
		(property "Value" "27R2F-GP"
			(at 0.064008 -3.993896 180)
			(unlocked yes)
			(layer "F.Fab")
			(hide yes)
			(effects
				(font
					(size 1.016 1.016)
					(thickness 0.1524)
				)
			)
		)
		(property "Device Type" "R402H16"
			(at 0.064008 -5.517896 180)
			(unlocked yes)
			(layer "F.Fab")
			(hide yes)
			(effects
				(font
					(size 1.016 1.016)
					(thickness 0.1524)
				)
			)
		)
		(duplicate_pad_numbers_are_jumpers no)
		(fp_line
			(start 0.508 -0.9398)
			(end -0.508 -0.9398)
			(stroke
				(width 0.1524)
				(type default)
			)
			(layer "F.SilkS")
		)
		(fp_line
			(start -0.508 -0.9398)
			(end -0.508 0.9398)
			(stroke
				(width 0.1524)
				(type default)
			)
			(layer "F.SilkS")
		)
		(fp_rect
			(start -0.508 0.9398)
			(end 0.508 -0.9398)
			(stroke
				(width 0)
				(type default)
			)
			(fill no)
			(layer "F.CrtYd")
		)
		(fp_rect
			(start -0.508 0.9398)
			(end 0.508 -0.9398)
			(stroke
				(width 0)
				(type default)
			)
			(fill no)
			(layer "F.Fab")
		)
		(pad "1" smd custom
			(at 0 -0.4445 180)
			(size 0.1397 0.1397)
			(layers "F.Cu" "F.Mask" "F.Paste")
			(net "PE_CLK_100M_DR12_2_R_N")
			(options
				(clearance outline)
				(anchor circle)
			)
			(primitives
				(gr_poly
					(pts
						(arc
							(start -0.1778 -0.2794)
							(mid -0.249642 -0.249642)
							(end -0.2794 -0.1778)
						)
						(arc
							(start -0.2794 0.1778)
							(mid -0.249642 0.249642)
							(end -0.1778 0.2794)
						)
						(arc
							(start 0.1778 0.2794)
							(mid 0.249642 0.249642)
							(end 0.2794 0.1778)
						)
						(arc
							(start 0.2794 -0.1778)
							(mid 0.249642 -0.249642)
							(end 0.1778 -0.2794)
						)
					)
					(width 0)
					(fill yes)
				)
			)
		)
		(pad "2" smd custom
			(at 0 0.4445 180)
			(size 0.1397 0.1397)
			(layers "F.Cu" "F.Mask" "F.Paste")
			(net "PE_CLK100M_DR12_2_N")
			(options
				(clearance outline)
				(anchor circle)
			)
			(primitives
				(gr_poly
					(pts
						(arc
							(start -0.1778 -0.2794)
							(mid -0.249642 -0.249642)
							(end -0.2794 -0.1778)
						)
						(arc
							(start -0.2794 0.1778)
							(mid -0.249642 0.249642)
							(end -0.1778 0.2794)
						)
						(arc
							(start 0.1778 0.2794)
							(mid 0.249642 0.249642)
							(end 0.2794 0.1778)
						)
						(arc
							(start 0.2794 -0.1778)
							(mid 0.249642 -0.249642)
							(end 0.1778 -0.2794)
						)
					)
					(width 0)
					(fill yes)
				)
			)
		)
	)
	(footprint ""
		(layer "F.Cu")
		(at 90.043 -89.535 90)
		(property "Reference" "C9339"
			(at 0 0 90)
			(layer "F.SilkS")
			(hide yes)
			(effects
				(font
					(size 1.27 1.27)
				)
			)
		)
		(property "Value" "SC1KP50V2KX-1GP"
			(at 1.1811 -2.7051 90)
			(unlocked yes)
			(layer "F.Fab")
			(hide yes)
			(effects
				(font
					(size 1.016 1.016)
					(thickness 0.1524)
				)
			)
		)
		(property "Device Type" "C402H22"
			(at 1.1811 -4.2291 90)
			(unlocked yes)
			(layer "F.Fab")
			(hide yes)
			(effects
				(font
					(size 1.016 1.016)
					(thickness 0.1524)
				)
			)
		)
		(duplicate_pad_numbers_are_jumpers no)
		(fp_rect
			(start -0.4318 0.9525)
			(end 0.4318 -0.9525)
			(stroke
				(width 0)
				(type default)
			)
			(fill no)
			(layer "F.CrtYd")
		)
		(fp_rect
			(start -0.4318 0.9525)
			(end 0.4318 -0.9525)
			(stroke
				(width 0)
				(type default)
			)
			(fill no)
			(layer "F.Fab")
		)
		(pad "1" smd custom
			(at 0 -0.4445 90)
			(size 0.1524 0.1524)
			(layers "F.Cu" "F.Mask" "F.Paste")
			(net "SSD9_CLK0_OE_R_N")
			(options
				(clearance outline)
				(anchor circle)
			)
			(primitives
				(gr_poly
					(pts
						(arc
							(start 0.3048 -0.2032)
							(mid 0.275042 -0.275042)
							(end 0.2032 -0.3048)
						)
						(arc
							(start -0.2032 -0.3048)
							(mid -0.275042 -0.275042)
							(end -0.3048 -0.2032)
						)
						(arc
							(start -0.3048 0.2032)
							(mid -0.275042 0.275042)
							(end -0.2032 0.3048)
						)
						(arc
							(start 0.2032 0.3048)
							(mid 0.275042 0.275042)
							(end 0.3048 0.2032)
						)
					)
					(width 0)
					(fill yes)
				)
			)
		)
		(pad "2" smd custom
			(at 0 0.4445 90)
			(size 0.1524 0.1524)
			(layers "F.Cu" "F.Mask" "F.Paste")
			(net "GND")
			(options
				(clearance outline)
				(anchor circle)
			)
			(primitives
				(gr_poly
					(pts
						(arc
							(start 0.3048 -0.2032)
							(mid 0.275042 -0.275042)
							(end 0.2032 -0.3048)
						)
						(arc
							(start -0.2032 -0.3048)
							(mid -0.275042 -0.275042)
							(end -0.3048 -0.2032)
						)
						(arc
							(start -0.3048 0.2032)
							(mid -0.275042 0.275042)
							(end -0.2032 0.3048)
						)
						(arc
							(start 0.2032 0.3048)
							(mid 0.275042 0.275042)
							(end 0.3048 0.2032)
						)
					)
					(width 0)
					(fill yes)
				)
			)
		)
	)
	(footprint ""
		(layer "F.Cu")
		(at 84.455 -95.758 90)
		(property "Reference" "PR9041"
			(at 0 0 90)
			(layer "F.SilkS")
			(hide yes)
			(effects
				(font
					(size 1.27 1.27)
				)
			)
		)
		(property "Value" "4K7R2F-GP"
			(at 0.064008 -3.993896 90)
			(unlocked yes)
			(layer "F.Fab")
			(hide yes)
			(effects
				(font
					(size 1.016 1.016)
					(thickness 0.1524)
				)
			)
		)
		(property "Device Type" "R402H16"
			(at 0.064008 -5.517896 90)
			(unlocked yes)
			(layer "F.Fab")
			(hide yes)
			(effects
				(font
					(size 1.016 1.016)
					(thickness 0.1524)
				)
			)
		)
		(duplicate_pad_numbers_are_jumpers no)
		(fp_line
			(start 0.508 -0.9398)
			(end -0.508 -0.9398)
			(stroke
				(width 0.1524)
				(type default)
			)
			(layer "F.SilkS")
		)
		(fp_line
			(start -0.508 -0.9398)
			(end -0.508 0.9398)
			(stroke
				(width 0.1524)
				(type default)
			)
			(layer "F.SilkS")
		)
		(fp_rect
			(start -0.508 0.9398)
			(end 0.508 -0.9398)
			(stroke
				(width 0)
				(type default)
			)
			(fill no)
			(layer "F.CrtYd")
		)
		(fp_rect
			(start -0.508 0.9398)
			(end 0.508 -0.9398)
			(stroke
				(width 0)
				(type default)
			)
			(fill no)
			(layer "F.Fab")
		)
		(pad "1" smd custom
			(at 0 -0.4445 90)
			(size 0.1397 0.1397)
			(layers "F.Cu" "F.Mask" "F.Paste")
			(net "VDD_DIFF_4")
			(options
				(clearance outline)
				(anchor circle)
			)
			(primitives
				(gr_poly
					(pts
						(arc
							(start -0.1778 -0.2794)
							(mid -0.249642 -0.249642)
							(end -0.2794 -0.1778)
						)
						(arc
							(start -0.2794 0.1778)
							(mid -0.249642 0.249642)
							(end -0.1778 0.2794)
						)
						(arc
							(start 0.1778 0.2794)
							(mid 0.249642 0.249642)
							(end 0.2794 0.1778)
						)
						(arc
							(start 0.2794 -0.1778)
							(mid 0.249642 -0.249642)
							(end 0.1778 -0.2794)
						)
					)
					(width 0)
					(fill yes)
				)
			)
		)
		(pad "2" smd custom
			(at 0 0.4445 90)
			(size 0.1397 0.1397)
			(layers "F.Cu" "F.Mask" "F.Paste")
			(net "CLK_BUF_EU4_SMB_A1_TRI")
			(options
				(clearance outline)
				(anchor circle)
			)
			(primitives
				(gr_poly
					(pts
						(arc
							(start -0.1778 -0.2794)
							(mid -0.249642 -0.249642)
							(end -0.2794 -0.1778)
						)
						(arc
							(start -0.2794 0.1778)
							(mid -0.249642 0.249642)
							(end -0.1778 0.2794)
						)
						(arc
							(start 0.1778 0.2794)
							(mid 0.249642 0.249642)
							(end 0.2794 0.1778)
						)
						(arc
							(start 0.2794 -0.1778)
							(mid 0.249642 -0.249642)
							(end 0.1778 -0.2794)
						)
					)
					(width 0)
					(fill yes)
				)
			)
		)
	)
	(footprint ""
		(layer "F.Cu")
		(at 84.455 -203.962 -90)
		(property "Reference" "R9118"
			(at 0 0 270)
			(layer "F.SilkS")
			(hide yes)
			(effects
				(font
					(size 1.27 1.27)
				)
			)
		)
		(property "Value" "4K7R2F-GP"
			(at 0.064008 -3.993896 270)
			(unlocked yes)
			(layer "F.Fab")
			(hide yes)
			(effects
				(font
					(size 1.016 1.016)
					(thickness 0.1524)
				)
			)
		)
		(property "Device Type" "R402H16"
			(at 0.064008 -5.517896 270)
			(unlocked yes)
			(layer "F.Fab")
			(hide yes)
			(effects
				(font
					(size 1.016 1.016)
					(thickness 0.1524)
				)
			)
		)
		(duplicate_pad_numbers_are_jumpers no)
		(fp_line
			(start -0.508 -0.9398)
			(end -0.508 0.9398)
			(stroke
				(width 0.1524)
				(type default)
			)
			(layer "F.SilkS")
		)
		(fp_line
			(start 0.508 -0.9398)
			(end -0.508 -0.9398)
			(stroke
				(width 0.1524)
				(type default)
			)
			(layer "F.SilkS")
		)
		(fp_rect
			(start -0.508 0.9398)
			(end 0.508 -0.9398)
			(stroke
				(width 0)
				(type default)
			)
			(fill no)
			(layer "F.CrtYd")
		)
		(fp_rect
			(start -0.508 0.9398)
			(end 0.508 -0.9398)
			(stroke
				(width 0)
				(type default)
			)
			(fill no)
			(layer "F.Fab")
		)
		(pad "1" smd custom
			(at 0 -0.4445 270)
			(size 0.1397 0.1397)
			(layers "F.Cu" "F.Mask" "F.Paste")
			(net "CLK_BUF_EU3_SMB_A1_TRI")
			(options
				(clearance outline)
				(anchor circle)
			)
			(primitives
				(gr_poly
					(pts
						(arc
							(start -0.1778 -0.2794)
							(mid -0.249642 -0.249642)
							(end -0.2794 -0.1778)
						)
						(arc
							(start -0.2794 0.1778)
							(mid -0.249642 0.249642)
							(end -0.1778 0.2794)
						)
						(arc
							(start 0.1778 0.2794)
							(mid 0.249642 0.249642)
							(end 0.2794 0.1778)
						)
						(arc
							(start 0.2794 -0.1778)
							(mid 0.249642 -0.249642)
							(end 0.1778 -0.2794)
						)
					)
					(width 0)
					(fill yes)
				)
			)
		)
		(pad "2" smd custom
			(at 0 0.4445 270)
			(size 0.1397 0.1397)
			(layers "F.Cu" "F.Mask" "F.Paste")
			(net "GND")
			(options
				(clearance outline)
				(anchor circle)
			)
			(primitives
				(gr_poly
					(pts
						(arc
							(start -0.1778 -0.2794)
							(mid -0.249642 -0.249642)
							(end -0.2794 -0.1778)
						)
						(arc
							(start -0.2794 0.1778)
							(mid -0.249642 0.249642)
							(end -0.1778 0.2794)
						)
						(arc
							(start 0.1778 0.2794)
							(mid 0.249642 0.249642)
							(end 0.2794 0.1778)
						)
						(arc
							(start 0.2794 -0.1778)
							(mid 0.249642 -0.249642)
							(end 0.1778 -0.2794)
						)
					)
					(width 0)
					(fill yes)
				)
			)
		)
	)
	(footprint ""
		(layer "F.Cu")
		(at 70.000114 -276.497542)
		(property "Reference" "H4"
			(at 0 0 0)
			(layer "F.SilkS")
			(hide yes)
			(effects
				(font
					(size 1.27 1.27)
				)
			)
		)
		(property "Value" "GEN276X162R197X296-6-F-A-GP"
			(at -6.7183 4.1402 0)
			(unlocked yes)
			(layer "F.Fab")
			(hide yes)
			(effects
				(font
					(size 1.016 1.016)
					(thickness 0.1524)
				)
			)
		)
		(property "Device Type" "GEN276X162R197X296-6-F-A"
			(at -6.7183 2.6162 0)
			(unlocked yes)
			(layer "F.Fab")
			(hide yes)
			(effects
				(font
					(size 1.016 1.016)
					(thickness 0.1524)
				)
			)
		)
		(duplicate_pad_numbers_are_jumpers no)
		(fp_poly
			(pts
				(arc
					(start 2.723642 4.777232)
					(mid -0.000169 6.508462)
					(end -2.723896 4.776978)
				)
				(arc
					(start -2.723896 4.776978)
					(mid 0.000173 -5.499012)
					(end 2.723642 4.777232)
				)
			)
			(stroke
				(width 0)
				(type default)
			)
			(fill no)
			(layer "B.CrtYd")
		)
		(fp_poly
			(pts
				(arc
					(start 2.723642 4.777232)
					(mid -0.000169 6.508462)
					(end -2.723896 4.776978)
				)
				(arc
					(start -2.723896 4.776978)
					(mid 0.000173 -5.499012)
					(end 2.723642 4.777232)
				)
			)
			(stroke
				(width 0)
				(type default)
			)
			(fill no)
			(layer "F.CrtYd")
		)
		(fp_poly
			(pts
				(arc
					(start 2.723642 4.777232)
					(mid -0.000169 6.508462)
					(end -2.723896 4.776978)
				)
				(arc
					(start -2.723896 4.776978)
					(mid 0.000173 -5.499012)
					(end 2.723642 4.777232)
				)
			)
			(stroke
				(width 0)
				(type default)
			)
			(fill no)
			(layer "B.Fab")
		)
		(fp_poly
			(pts
				(arc
					(start 2.723642 4.777232)
					(mid -0.000169 6.508462)
					(end -2.723896 4.776978)
				)
				(arc
					(start -2.723896 4.776978)
					(mid 0.000173 -5.499012)
					(end 2.723642 4.777232)
				)
			)
			(stroke
				(width 0)
				(type default)
			)
			(fill no)
			(layer "F.Fab")
		)
		(pad "" np_thru_hole circle
			(at 0 0)
			(size 0.254 0.254)
			(drill 0.0254)
			(layers "*.Cu" "*.Mask")
			(clearance 3.135376)
			(thermal_gap 3.135376)
		)
		(pad "1" thru_hole circle
			(at 2.549906 0)
			(size 0.8636 0.8636)
			(drill 0.508)
			(layers "*.Cu" "*.Mask")
			(remove_unused_layers no)
			(net "GND")
			(clearance 0.8255)
			(thermal_gap 0.8255)
		)
		(pad "2" thru_hole circle
			(at 2.210054 -1.27)
			(size 0.8636 0.8636)
			(drill 0.508)
			(layers "*.Cu" "*.Mask")
			(remove_unused_layers no)
			(net "GND")
			(clearance 0.8255)
			(thermal_gap 0.8255)
		)
		(pad "3" thru_hole circle
			(at 1.27 -2.210054)
			(size 0.8636 0.8636)
			(drill 0.508)
			(layers "*.Cu" "*.Mask")
			(remove_unused_layers no)
			(net "GND")
			(clearance 0.8255)
			(thermal_gap 0.8255)
		)
		(pad "4" thru_hole circle
			(at -1.279906 -2.210054)
			(size 0.8636 0.8636)
			(drill 0.508)
			(layers "*.Cu" "*.Mask")
			(remove_unused_layers no)
			(net "GND")
			(clearance 0.8255)
			(thermal_gap 0.8255)
		)
		(pad "5" thru_hole circle
			(at -2.210054 -1.27)
			(size 0.8636 0.8636)
			(drill 0.508)
			(layers "*.Cu" "*.Mask")
			(remove_unused_layers no)
			(net "GND")
			(clearance 0.8255)
			(thermal_gap 0.8255)
		)
		(pad "6" thru_hole circle
			(at -2.549906 0)
			(size 0.8636 0.8636)
			(drill 0.508)
			(layers "*.Cu" "*.Mask")
			(remove_unused_layers no)
			(net "GND")
			(clearance 0.8255)
			(thermal_gap 0.8255)
		)
		(zone
			(layers "F.Cu" "B.Cu" "In1.Cu" "In2.Cu" "In3.Cu" "In4.Cu" "In5.Cu" "In6.Cu")
			(hatch none 0.5)
			(connect_pads
				(clearance 0)
			)
			(min_thickness 0.25)
			(keepout
				(tracks allowed)
				(vias not_allowed)
				(pads allowed)
				(copperpour not_allowed)
				(footprints allowed)
			)
			(placement
				(enabled no)
				(sheetname "")
			)
			(fill
				(thermal_gap 0.5)
				(thermal_bridge_width 0.5)
				(island_removal_mode 0)
			)
			(polygon
				(pts
					(arc
						(start 74.318114 -276.50059)
						(mid 65.682114 -276.50059)
						(end 74.318114 -276.50059)
					)
				)
			)
		)
		(zone
			(layers "F.Cu" "B.Cu" "In1.Cu" "In2.Cu" "In3.Cu" "In4.Cu" "In5.Cu" "In6.Cu")
			(hatch none 0.5)
			(connect_pads
				(clearance 0)
			)
			(min_thickness 0.25)
			(keepout
				(tracks not_allowed)
				(vias allowed)
				(pads allowed)
				(copperpour not_allowed)
				(footprints allowed)
			)
			(placement
				(enabled no)
				(sheetname "")
			)
			(fill
				(thermal_gap 0.5)
				(thermal_bridge_width 0.5)
				(island_removal_mode 0)
			)
			(polygon
				(pts
					(arc
						(start 72.339454 -274.888198)
						(mid 70.000194 -269.989095)
						(end 67.66052 -274.888198)
					)
					(arc
						(start 67.66052 -274.888198)
						(mid 67.906487 -275.328564)
						(end 67.991736 -275.825712)
					)
					(arc
						(start 67.991736 -276.497542)
						(mid 70.000114 -278.50592)
						(end 72.008238 -276.497542)
					)
					(arc
						(start 72.008238 -275.825712)
						(mid 72.093473 -275.328558)
						(end 72.339454 -274.888198)
					)
				)
			)
		)
	)
	(footprint ""
		(layer "F.Cu")
		(at 220.726 -447.04)
		(property "Reference" "Q28"
			(at 0 0 0)
			(layer "F.SilkS")
			(hide yes)
			(effects
				(font
					(size 1.27 1.27)
				)
			)
		)
		(property "Value" "2N7002A-7-GP"
			(at 0.127 -8.9662 0)
			(unlocked yes)
			(layer "F.Fab")
			(hide yes)
			(effects
				(font
					(size 1.016 1.016)
					(thickness 0.1524)
				)
			)
		)
		(property "Device Type" "SOT23DGS2D4H48"
			(at 0.127 -10.4902 0)
			(unlocked yes)
			(layer "F.Fab")
			(hide yes)
			(effects
				(font
					(size 1.016 1.016)
					(thickness 0.1524)
				)
			)
		)
		(duplicate_pad_numbers_are_jumpers no)
		(fp_line
			(start -1.651 -1.778)
			(end -1.651 1.778)
			(stroke
				(width 0.1524)
				(type default)
			)
			(layer "F.SilkS")
		)
		(fp_line
			(start -1.651 1.778)
			(end 1.651 1.778)
			(stroke
				(width 0.1524)
				(type default)
			)
			(layer "F.SilkS")
		)
		(fp_line
			(start 1.651 -1.778)
			(end -1.651 -1.778)
			(stroke
				(width 0.1524)
				(type default)
			)
			(layer "F.SilkS")
		)
		(fp_line
			(start 1.651 1.778)
			(end 1.651 -1.778)
			(stroke
				(width 0.1524)
				(type default)
			)
			(layer "F.SilkS")
		)
		(fp_poly
			(pts
				(xy -1.778 1.8796) (xy -1.778 -1.8796) (xy 1.778 -1.8796) (xy 1.778 1.8796)
			)
			(stroke
				(width 0)
				(type default)
			)
			(fill no)
			(layer "F.CrtYd")
		)
		(fp_poly
			(pts
				(xy -1.778 1.8796) (xy -1.778 -1.8796) (xy 1.778 -1.8796) (xy 1.778 1.8796)
			)
			(stroke
				(width 0)
				(type default)
			)
			(fill no)
			(layer "F.Fab")
		)
		(pad "D" smd custom
			(at 0 -0.9525)
			(size 0.1905 0.1905)
			(layers "F.Cu" "F.Mask" "F.Paste")
			(net "SSD0_CLK0_OE_MOS_N")
			(options
				(clearance outline)
				(anchor circle)
			)
			(primitives
				(gr_poly
					(pts
						(arc
							(start -0.1778 0.5715)
							(mid -0.321484 0.511984)
							(end -0.381 0.3683)
						)
						(arc
							(start -0.381 -0.3683)
							(mid -0.321484 -0.511984)
							(end -0.1778 -0.5715)
						)
						(arc
							(start 0.1778 -0.5715)
							(mid 0.321484 -0.511984)
							(end 0.381 -0.3683)
						)
						(arc
							(start 0.381 0.3683)
							(mid 0.321484 0.511984)
							(end 0.1778 0.5715)
						)
					)
					(width 0)
					(fill yes)
				)
			)
		)
		(pad "G" smd custom
			(at -0.98425 0.9525)
			(size 0.1905 0.1905)
			(layers "F.Cu" "F.Mask" "F.Paste")
			(net "SSD0_CLK0_OE_R_N")
			(options
				(clearance outline)
				(anchor circle)
			)
			(primitives
				(gr_poly
					(pts
						(arc
							(start -0.1778 0.5715)
							(mid -0.321484 0.511984)
							(end -0.381 0.3683)
						)
						(arc
							(start -0.381 -0.3683)
							(mid -0.321484 -0.511984)
							(end -0.1778 -0.5715)
						)
						(arc
							(start 0.1778 -0.5715)
							(mid 0.321484 -0.511984)
							(end 0.381 -0.3683)
						)
						(arc
							(start 0.381 0.3683)
							(mid 0.321484 0.511984)
							(end 0.1778 0.5715)
						)
					)
					(width 0)
					(fill yes)
				)
			)
		)
		(pad "S" smd custom
			(at 0.98425 0.9525)
			(size 0.1905 0.1905)
			(layers "F.Cu" "F.Mask" "F.Paste")
			(net "GND")
			(options
				(clearance outline)
				(anchor circle)
			)
			(primitives
				(gr_poly
					(pts
						(arc
							(start -0.1778 0.5715)
							(mid -0.321484 0.511984)
							(end -0.381 0.3683)
						)
						(arc
							(start -0.381 -0.3683)
							(mid -0.321484 -0.511984)
							(end -0.1778 -0.5715)
						)
						(arc
							(start 0.1778 -0.5715)
							(mid 0.321484 -0.511984)
							(end 0.381 -0.3683)
						)
						(arc
							(start 0.381 0.3683)
							(mid 0.321484 0.511984)
							(end 0.1778 0.5715)
						)
					)
					(width 0)
					(fill yes)
				)
			)
		)
	)
	(footprint ""
		(layer "F.Cu")
		(at 42.203116 -35.167062 90)
		(property "Reference" "U206"
			(at 0 0 90)
			(layer "F.SilkS")
			(hide yes)
			(effects
				(font
					(size 1.27 1.27)
				)
			)
		)
		(property "Value" "SN74LVC1G08DCKR-GP"
			(at -2.3368 -8.6868 90)
			(unlocked yes)
			(layer "F.Fab")
			(hide yes)
			(effects
				(font
					(size 1.016 1.016)
					(thickness 0.1524)
				)
			)
		)
		(property "Device Type" "SC70-5H44"
			(at -2.3114 -10.414 90)
			(unlocked yes)
			(layer "F.Fab")
			(hide yes)
			(effects
				(font
					(size 1.016 1.016)
					(thickness 0.1524)
				)
			)
		)
		(duplicate_pad_numbers_are_jumpers no)
		(fp_line
			(start 1.3843 -1.8034)
			(end 1.3843 -1.1176)
			(stroke
				(width 0.3302)
				(type default)
			)
			(layer "F.SilkS")
		)
		(fp_line
			(start 0.6604 -1.8034)
			(end 1.3843 -1.8034)
			(stroke
				(width 0.3302)
				(type default)
			)
			(layer "F.SilkS")
		)
		(fp_line
			(start 1.27 -1.7018)
			(end 1.27 1.7018)
			(stroke
				(width 0.1524)
				(type default)
			)
			(layer "F.SilkS")
		)
		(fp_line
			(start -1.27 -1.7018)
			(end 1.27 -1.7018)
			(stroke
				(width 0.1524)
				(type default)
			)
			(layer "F.SilkS")
		)
		(fp_line
			(start 1.27 1.7018)
			(end -1.27 1.7018)
			(stroke
				(width 0.1524)
				(type default)
			)
			(layer "F.SilkS")
		)
		(fp_line
			(start -1.27 1.7018)
			(end -1.27 -1.7018)
			(stroke
				(width 0.1524)
				(type default)
			)
			(layer "F.SilkS")
		)
		(fp_rect
			(start -1.524 1.9558)
			(end 1.524 -1.9558)
			(stroke
				(width 0)
				(type default)
			)
			(fill no)
			(layer "F.CrtYd")
		)
		(fp_poly
			(pts
				(xy -1.524 -1.9558) (xy 1.524 -1.9558) (xy 1.524 1.9558) (xy -1.524 1.9558)
			)
			(stroke
				(width 0)
				(type default)
			)
			(fill no)
			(layer "F.Fab")
		)
		(pad "1" smd rect
			(at 0.65024 -0.8255 90)
			(size 0.4064 1.2192)
			(layers "F.Cu" "F.Mask" "F.Paste")
			(net "SSD9_CLK0_OE_MOS_N")
		)
		(pad "2" smd rect
			(at 0 -0.8255 90)
			(size 0.4064 1.2192)
			(layers "F.Cu" "F.Mask" "F.Paste")
			(net "ATTN_LED_DR9_N")
		)
		(pad "3" smd rect
			(at -0.65024 -0.8255 90)
			(size 0.4064 1.2192)
			(layers "F.Cu" "F.Mask" "F.Paste")
			(net "GND")
		)
		(pad "4" smd rect
			(at -0.65024 0.8255 90)
			(size 0.4064 1.2192)
			(layers "F.Cu" "F.Mask" "F.Paste")
			(net "ATTN_LED_DR9_AND")
		)
		(pad "5" smd rect
			(at 0.65024 0.8255 90)
			(size 0.4064 1.2192)
			(layers "F.Cu" "F.Mask" "F.Paste")
			(net "P3V3")
		)
	)
	(footprint ""
		(layer "F.Cu")
		(at 87.503 -313.817 180)
		(property "Reference" "R9102"
			(at 0 0 180)
			(layer "F.SilkS")
			(hide yes)
			(effects
				(font
					(size 1.27 1.27)
				)
			)
		)
		(property "Value" "27R2F-GP"
			(at 0.064008 -3.993896 180)
			(unlocked yes)
			(layer "F.Fab")
			(hide yes)
			(effects
				(font
					(size 1.016 1.016)
					(thickness 0.1524)
				)
			)
		)
		(property "Device Type" "R402H16"
			(at 0.064008 -5.517896 180)
			(unlocked yes)
			(layer "F.Fab")
			(hide yes)
			(effects
				(font
					(size 1.016 1.016)
					(thickness 0.1524)
				)
			)
		)
		(duplicate_pad_numbers_are_jumpers no)
		(fp_line
			(start 0.508 -0.9398)
			(end -0.508 -0.9398)
			(stroke
				(width 0.1524)
				(type default)
			)
			(layer "F.SilkS")
		)
		(fp_line
			(start -0.508 -0.9398)
			(end -0.508 0.9398)
			(stroke
				(width 0.1524)
				(type default)
			)
			(layer "F.SilkS")
		)
		(fp_rect
			(start -0.508 0.9398)
			(end 0.508 -0.9398)
			(stroke
				(width 0)
				(type default)
			)
			(fill no)
			(layer "F.CrtYd")
		)
		(fp_rect
			(start -0.508 0.9398)
			(end 0.508 -0.9398)
			(stroke
				(width 0)
				(type default)
			)
			(fill no)
			(layer "F.Fab")
		)
		(pad "1" smd custom
			(at 0 -0.4445 180)
			(size 0.1397 0.1397)
			(layers "F.Cu" "F.Mask" "F.Paste")
			(net "PE_CLK_100M_DR11_1_R_P")
			(options
				(clearance outline)
				(anchor circle)
			)
			(primitives
				(gr_poly
					(pts
						(arc
							(start -0.1778 -0.2794)
							(mid -0.249642 -0.249642)
							(end -0.2794 -0.1778)
						)
						(arc
							(start -0.2794 0.1778)
							(mid -0.249642 0.249642)
							(end -0.1778 0.2794)
						)
						(arc
							(start 0.1778 0.2794)
							(mid 0.249642 0.249642)
							(end 0.2794 0.1778)
						)
						(arc
							(start 0.2794 -0.1778)
							(mid 0.249642 -0.249642)
							(end 0.1778 -0.2794)
						)
					)
					(width 0)
					(fill yes)
				)
			)
		)
		(pad "2" smd custom
			(at 0 0.4445 180)
			(size 0.1397 0.1397)
			(layers "F.Cu" "F.Mask" "F.Paste")
			(net "PE_CLK100M_DR11_1_P")
			(options
				(clearance outline)
				(anchor circle)
			)
			(primitives
				(gr_poly
					(pts
						(arc
							(start -0.1778 -0.2794)
							(mid -0.249642 -0.249642)
							(end -0.2794 -0.1778)
						)
						(arc
							(start -0.2794 0.1778)
							(mid -0.249642 0.249642)
							(end -0.1778 0.2794)
						)
						(arc
							(start 0.1778 0.2794)
							(mid 0.249642 0.249642)
							(end 0.2794 0.1778)
						)
						(arc
							(start 0.2794 -0.1778)
							(mid 0.249642 -0.249642)
							(end 0.1778 -0.2794)
						)
					)
					(width 0)
					(fill yes)
				)
			)
		)
	)
	(footprint ""
		(layer "F.Cu")
		(at 211.455 -44.704 180)
		(property "Reference" "R328"
			(at 0 0 180)
			(layer "F.SilkS")
			(hide yes)
			(effects
				(font
					(size 1.27 1.27)
				)
			)
		)
		(property "Value" "4K7R2F-GP"
			(at 0.064008 -3.993896 180)
			(unlocked yes)
			(layer "F.Fab")
			(hide yes)
			(effects
				(font
					(size 1.016 1.016)
					(thickness 0.1524)
				)
			)
		)
		(property "Device Type" "R402H16"
			(at 0.064008 -5.517896 180)
			(unlocked yes)
			(layer "F.Fab")
			(hide yes)
			(effects
				(font
					(size 1.016 1.016)
					(thickness 0.1524)
				)
			)
		)
		(duplicate_pad_numbers_are_jumpers no)
		(fp_line
			(start 0.508 -0.9398)
			(end -0.508 -0.9398)
			(stroke
				(width 0.1524)
				(type default)
			)
			(layer "F.SilkS")
		)
		(fp_line
			(start -0.508 -0.9398)
			(end -0.508 0.9398)
			(stroke
				(width 0.1524)
				(type default)
			)
			(layer "F.SilkS")
		)
		(fp_rect
			(start -0.508 0.9398)
			(end 0.508 -0.9398)
			(stroke
				(width 0)
				(type default)
			)
			(fill no)
			(layer "F.CrtYd")
		)
		(fp_rect
			(start -0.508 0.9398)
			(end 0.508 -0.9398)
			(stroke
				(width 0)
				(type default)
			)
			(fill no)
			(layer "F.Fab")
		)
		(pad "1" smd custom
			(at 0 -0.4445 180)
			(size 0.1397 0.1397)
			(layers "F.Cu" "F.Mask" "F.Paste")
			(net "P3V3")
			(options
				(clearance outline)
				(anchor circle)
			)
			(primitives
				(gr_poly
					(pts
						(arc
							(start -0.1778 -0.2794)
							(mid -0.249642 -0.249642)
							(end -0.2794 -0.1778)
						)
						(arc
							(start -0.2794 0.1778)
							(mid -0.249642 0.249642)
							(end -0.1778 0.2794)
						)
						(arc
							(start 0.1778 0.2794)
							(mid 0.249642 0.249642)
							(end 0.2794 0.1778)
						)
						(arc
							(start 0.2794 -0.1778)
							(mid 0.249642 -0.249642)
							(end 0.1778 -0.2794)
						)
					)
					(width 0)
					(fill yes)
				)
			)
		)
		(pad "2" smd custom
			(at 0 0.4445 180)
			(size 0.1397 0.1397)
			(layers "F.Cu" "F.Mask" "F.Paste")
			(net "I2C_B_TMP3_A2")
			(options
				(clearance outline)
				(anchor circle)
			)
			(primitives
				(gr_poly
					(pts
						(arc
							(start -0.1778 -0.2794)
							(mid -0.249642 -0.249642)
							(end -0.2794 -0.1778)
						)
						(arc
							(start -0.2794 0.1778)
							(mid -0.249642 0.249642)
							(end -0.1778 0.2794)
						)
						(arc
							(start 0.1778 0.2794)
							(mid 0.249642 0.249642)
							(end 0.2794 0.1778)
						)
						(arc
							(start 0.2794 -0.1778)
							(mid 0.249642 -0.249642)
							(end 0.1778 -0.2794)
						)
					)
					(width 0)
					(fill yes)
				)
			)
		)
	)
	(footprint ""
		(layer "F.Cu")
		(at 24.3078 -194.183 180)
		(property "Reference" "Q16"
			(at 0 0 180)
			(layer "F.SilkS")
			(hide yes)
			(effects
				(font
					(size 1.27 1.27)
				)
			)
		)
		(property "Value" "2N7002A-7-GP"
			(at 0.127 -8.9662 180)
			(unlocked yes)
			(layer "F.Fab")
			(hide yes)
			(effects
				(font
					(size 1.016 1.016)
					(thickness 0.1524)
				)
			)
		)
		(property "Device Type" "SOT23DGS2D4H48"
			(at 0.127 -10.4902 180)
			(unlocked yes)
			(layer "F.Fab")
			(hide yes)
			(effects
				(font
					(size 1.016 1.016)
					(thickness 0.1524)
				)
			)
		)
		(duplicate_pad_numbers_are_jumpers no)
		(fp_line
			(start 1.651 1.778)
			(end 1.651 -1.778)
			(stroke
				(width 0.1524)
				(type default)
			)
			(layer "F.SilkS")
		)
		(fp_line
			(start 1.651 -1.778)
			(end -1.651 -1.778)
			(stroke
				(width 0.1524)
				(type default)
			)
			(layer "F.SilkS")
		)
		(fp_line
			(start -1.651 1.778)
			(end 1.651 1.778)
			(stroke
				(width 0.1524)
				(type default)
			)
			(layer "F.SilkS")
		)
		(fp_line
			(start -1.651 -1.778)
			(end -1.651 1.778)
			(stroke
				(width 0.1524)
				(type default)
			)
			(layer "F.SilkS")
		)
		(fp_poly
			(pts
				(xy -1.778 1.8796) (xy -1.778 -1.8796) (xy 1.778 -1.8796) (xy 1.778 1.8796)
			)
			(stroke
				(width 0)
				(type default)
			)
			(fill no)
			(layer "F.CrtYd")
		)
		(fp_poly
			(pts
				(xy -1.778 1.8796) (xy -1.778 -1.8796) (xy 1.778 -1.8796) (xy 1.778 1.8796)
			)
			(stroke
				(width 0)
				(type default)
			)
			(fill no)
			(layer "F.Fab")
		)
		(pad "D" smd custom
			(at 0 -0.9525 180)
			(size 0.1905 0.1905)
			(layers "F.Cu" "F.Mask" "F.Paste")
			(net "SW_SSD8_R")
			(options
				(clearance outline)
				(anchor circle)
			)
			(primitives
				(gr_poly
					(pts
						(arc
							(start -0.1778 0.5715)
							(mid -0.321484 0.511984)
							(end -0.381 0.3683)
						)
						(arc
							(start -0.381 -0.3683)
							(mid -0.321484 -0.511984)
							(end -0.1778 -0.5715)
						)
						(arc
							(start 0.1778 -0.5715)
							(mid 0.321484 -0.511984)
							(end 0.381 -0.3683)
						)
						(arc
							(start 0.381 0.3683)
							(mid 0.321484 0.511984)
							(end 0.1778 0.5715)
						)
					)
					(width 0)
					(fill yes)
				)
			)
		)
		(pad "G" smd custom
			(at -0.98425 0.9525 180)
			(size 0.1905 0.1905)
			(layers "F.Cu" "F.Mask" "F.Paste")
			(net "SSD8_PWREN")
			(options
				(clearance outline)
				(anchor circle)
			)
			(primitives
				(gr_poly
					(pts
						(arc
							(start -0.1778 0.5715)
							(mid -0.321484 0.511984)
							(end -0.381 0.3683)
						)
						(arc
							(start -0.381 -0.3683)
							(mid -0.321484 -0.511984)
							(end -0.1778 -0.5715)
						)
						(arc
							(start 0.1778 -0.5715)
							(mid 0.321484 -0.511984)
							(end 0.381 -0.3683)
						)
						(arc
							(start 0.381 0.3683)
							(mid 0.321484 0.511984)
							(end 0.1778 0.5715)
						)
					)
					(width 0)
					(fill yes)
				)
			)
		)
		(pad "S" smd custom
			(at 0.98425 0.9525 180)
			(size 0.1905 0.1905)
			(layers "F.Cu" "F.Mask" "F.Paste")
			(net "GND")
			(options
				(clearance outline)
				(anchor circle)
			)
			(primitives
				(gr_poly
					(pts
						(arc
							(start -0.1778 0.5715)
							(mid -0.321484 0.511984)
							(end -0.381 0.3683)
						)
						(arc
							(start -0.381 -0.3683)
							(mid -0.321484 -0.511984)
							(end -0.1778 -0.5715)
						)
						(arc
							(start 0.1778 -0.5715)
							(mid 0.321484 -0.511984)
							(end 0.381 -0.3683)
						)
						(arc
							(start 0.381 0.3683)
							(mid 0.321484 0.511984)
							(end 0.1778 0.5715)
						)
					)
					(width 0)
					(fill yes)
				)
			)
		)
	)
	(footprint ""
		(layer "F.Cu")
		(at 42.203116 -343.912952 90)
		(property "Reference" "U203"
			(at 0 0 90)
			(layer "F.SilkS")
			(hide yes)
			(effects
				(font
					(size 1.27 1.27)
				)
			)
		)
		(property "Value" "SN74LVC1G08DCKR-GP"
			(at -2.3368 -8.6868 90)
			(unlocked yes)
			(layer "F.Fab")
			(hide yes)
			(effects
				(font
					(size 1.016 1.016)
					(thickness 0.1524)
				)
			)
		)
		(property "Device Type" "SC70-5H44"
			(at -2.3114 -10.414 90)
			(unlocked yes)
			(layer "F.Fab")
			(hide yes)
			(effects
				(font
					(size 1.016 1.016)
					(thickness 0.1524)
				)
			)
		)
		(duplicate_pad_numbers_are_jumpers no)
		(fp_line
			(start 1.3843 -1.8034)
			(end 1.3843 -1.1176)
			(stroke
				(width 0.3302)
				(type default)
			)
			(layer "F.SilkS")
		)
		(fp_line
			(start 0.6604 -1.8034)
			(end 1.3843 -1.8034)
			(stroke
				(width 0.3302)
				(type default)
			)
			(layer "F.SilkS")
		)
		(fp_line
			(start 1.27 -1.7018)
			(end 1.27 1.7018)
			(stroke
				(width 0.1524)
				(type default)
			)
			(layer "F.SilkS")
		)
		(fp_line
			(start -1.27 -1.7018)
			(end 1.27 -1.7018)
			(stroke
				(width 0.1524)
				(type default)
			)
			(layer "F.SilkS")
		)
		(fp_line
			(start 1.27 1.7018)
			(end -1.27 1.7018)
			(stroke
				(width 0.1524)
				(type default)
			)
			(layer "F.SilkS")
		)
		(fp_line
			(start -1.27 1.7018)
			(end -1.27 -1.7018)
			(stroke
				(width 0.1524)
				(type default)
			)
			(layer "F.SilkS")
		)
		(fp_rect
			(start -1.524 1.9558)
			(end 1.524 -1.9558)
			(stroke
				(width 0)
				(type default)
			)
			(fill no)
			(layer "F.CrtYd")
		)
		(fp_poly
			(pts
				(xy -1.524 -1.9558) (xy 1.524 -1.9558) (xy 1.524 1.9558) (xy -1.524 1.9558)
			)
			(stroke
				(width 0)
				(type default)
			)
			(fill no)
			(layer "F.Fab")
		)
		(pad "1" smd rect
			(at 0.65024 -0.8255 90)
			(size 0.4064 1.2192)
			(layers "F.Cu" "F.Mask" "F.Paste")
			(net "SSD6_CLK0_OE_MOS_N")
		)
		(pad "2" smd rect
			(at 0 -0.8255 90)
			(size 0.4064 1.2192)
			(layers "F.Cu" "F.Mask" "F.Paste")
			(net "ATTN_LED_DR6_N")
		)
		(pad "3" smd rect
			(at -0.65024 -0.8255 90)
			(size 0.4064 1.2192)
			(layers "F.Cu" "F.Mask" "F.Paste")
			(net "GND")
		)
		(pad "4" smd rect
			(at -0.65024 0.8255 90)
			(size 0.4064 1.2192)
			(layers "F.Cu" "F.Mask" "F.Paste")
			(net "ATTN_LED_DR6_AND")
		)
		(pad "5" smd rect
			(at 0.65024 0.8255 90)
			(size 0.4064 1.2192)
			(layers "F.Cu" "F.Mask" "F.Paste")
			(net "P3V3")
		)
	)
	(footprint ""
		(layer "F.Cu")
		(at 25.4 -414.7566)
		(property "Reference" "PC1181"
			(at 0 0 0)
			(layer "F.SilkS")
			(hide yes)
			(effects
				(font
					(size 1.27 1.27)
				)
			)
		)
		(property "Value" "SC22U25V6KX-GP-U"
			(at -2.860802 -5.279644 0)
			(unlocked yes)
			(layer "F.Fab")
			(hide yes)
			(effects
				(font
					(size 1.016 1.016)
					(thickness 0.1524)
				)
			)
		)
		(property "Device Type" "C1206-TO0D3H75"
			(at -2.860802 -6.803644 0)
			(unlocked yes)
			(layer "F.Fab")
			(hide yes)
			(effects
				(font
					(size 1.016 1.016)
					(thickness 0.1524)
				)
			)
		)
		(duplicate_pad_numbers_are_jumpers no)
		(fp_line
			(start -1.3081 -2.3749)
			(end 1.3081 -2.3749)
			(stroke
				(width 0.1524)
				(type default)
			)
			(layer "F.SilkS")
		)
		(fp_line
			(start -1.3081 2.3749)
			(end -1.3081 -2.3749)
			(stroke
				(width 0.1524)
				(type default)
			)
			(layer "F.SilkS")
		)
		(fp_line
			(start 1.3081 -2.3749)
			(end 1.3081 2.3749)
			(stroke
				(width 0.1524)
				(type default)
			)
			(layer "F.SilkS")
		)
		(fp_line
			(start 1.3081 2.3749)
			(end -1.3081 2.3749)
			(stroke
				(width 0.1524)
				(type default)
			)
			(layer "F.SilkS")
		)
		(fp_rect
			(start -0.8001 1.6002)
			(end 0.8001 -1.6002)
			(stroke
				(width 0)
				(type default)
			)
			(fill no)
			(layer "F.CrtYd")
		)
		(fp_poly
			(pts
				(xy -1.5621 2.4511) (xy -1.5621 1.6002) (xy 0.8001 1.6002) (xy 0.8001 -1.6002) (xy -0.8001 -1.6002)
				(xy -0.8001 1.5875) (xy -1.5621 1.5875) (xy -1.5621 -2.4511) (xy 1.5621 -2.4511) (xy 1.5621 2.4511)
			)
			(stroke
				(width 0)
				(type default)
			)
			(fill no)
			(layer "F.CrtYd")
		)
		(fp_rect
			(start -1.5621 2.4511)
			(end 1.5621 -2.4511)
			(stroke
				(width 0)
				(type default)
			)
			(fill no)
			(layer "F.Fab")
		)
		(pad "1" smd rect
			(at 0 -1.392936)
			(size 2.1082 1.4478)
			(layers "F.Cu" "F.Mask" "F.Paste")
			(net "P12V_SSD10")
		)
		(pad "2" smd rect
			(at 0 1.392936)
			(size 2.1082 1.4478)
			(layers "F.Cu" "F.Mask" "F.Paste")
			(net "GND")
		)
	)
	(footprint ""
		(layer "F.Cu")
		(at 90.043 -416.814 -90)
		(property "Reference" "R124"
			(at 0 0 270)
			(layer "F.SilkS")
			(hide yes)
			(effects
				(font
					(size 1.27 1.27)
				)
			)
		)
		(property "Value" "4K7R2J-2-GP"
			(at 0.064008 -3.993896 270)
			(unlocked yes)
			(layer "F.Fab")
			(hide yes)
			(effects
				(font
					(size 1.016 1.016)
					(thickness 0.1524)
				)
			)
		)
		(property "Device Type" "R402H16"
			(at 0.064008 -5.517896 270)
			(unlocked yes)
			(layer "F.Fab")
			(hide yes)
			(effects
				(font
					(size 1.016 1.016)
					(thickness 0.1524)
				)
			)
		)
		(duplicate_pad_numbers_are_jumpers no)
		(fp_line
			(start -0.508 -0.9398)
			(end -0.508 0.9398)
			(stroke
				(width 0.1524)
				(type default)
			)
			(layer "F.SilkS")
		)
		(fp_line
			(start 0.508 -0.9398)
			(end -0.508 -0.9398)
			(stroke
				(width 0.1524)
				(type default)
			)
			(layer "F.SilkS")
		)
		(fp_rect
			(start -0.508 0.9398)
			(end 0.508 -0.9398)
			(stroke
				(width 0)
				(type default)
			)
			(fill no)
			(layer "F.CrtYd")
		)
		(fp_rect
			(start -0.508 0.9398)
			(end 0.508 -0.9398)
			(stroke
				(width 0)
				(type default)
			)
			(fill no)
			(layer "F.Fab")
		)
		(pad "1" smd custom
			(at 0 -0.4445 270)
			(size 0.1397 0.1397)
			(layers "F.Cu" "F.Mask" "F.Paste")
			(net "P3V3")
			(options
				(clearance outline)
				(anchor circle)
			)
			(primitives
				(gr_poly
					(pts
						(arc
							(start -0.1778 -0.2794)
							(mid -0.249642 -0.249642)
							(end -0.2794 -0.1778)
						)
						(arc
							(start -0.2794 0.1778)
							(mid -0.249642 0.249642)
							(end -0.1778 0.2794)
						)
						(arc
							(start 0.1778 0.2794)
							(mid 0.249642 0.249642)
							(end 0.2794 0.1778)
						)
						(arc
							(start 0.2794 -0.1778)
							(mid 0.249642 -0.249642)
							(end 0.1778 -0.2794)
						)
					)
					(width 0)
					(fill yes)
				)
			)
		)
		(pad "2" smd custom
			(at 0 0.4445 270)
			(size 0.1397 0.1397)
			(layers "F.Cu" "F.Mask" "F.Paste")
			(net "SSD10_CLK0_OE_N")
			(options
				(clearance outline)
				(anchor circle)
			)
			(primitives
				(gr_poly
					(pts
						(arc
							(start -0.1778 -0.2794)
							(mid -0.249642 -0.249642)
							(end -0.2794 -0.1778)
						)
						(arc
							(start -0.2794 0.1778)
							(mid -0.249642 0.249642)
							(end -0.1778 0.2794)
						)
						(arc
							(start 0.1778 0.2794)
							(mid 0.249642 0.249642)
							(end 0.2794 0.1778)
						)
						(arc
							(start 0.2794 -0.1778)
							(mid 0.249642 -0.249642)
							(end 0.1778 -0.2794)
						)
					)
					(width 0)
					(fill yes)
				)
			)
		)
	)
	(footprint ""
		(layer "F.Cu")
		(at 21.30425 -401.79625)
		(property "Reference" "R9766"
			(at 0 0 0)
			(layer "F.SilkS")
			(hide yes)
			(effects
				(font
					(size 1.27 1.27)
				)
			)
		)
		(property "Value" "4K7R2J-2-GP"
			(at 0.064008 -3.993896 0)
			(unlocked yes)
			(layer "F.Fab")
			(hide yes)
			(effects
				(font
					(size 1.016 1.016)
					(thickness 0.1524)
				)
			)
		)
		(property "Device Type" "R402H16"
			(at 0.064008 -5.517896 0)
			(unlocked yes)
			(layer "F.Fab")
			(hide yes)
			(effects
				(font
					(size 1.016 1.016)
					(thickness 0.1524)
				)
			)
		)
		(duplicate_pad_numbers_are_jumpers no)
		(fp_line
			(start -0.508 -0.9398)
			(end -0.508 0.9398)
			(stroke
				(width 0.1524)
				(type default)
			)
			(layer "F.SilkS")
		)
		(fp_line
			(start 0.508 -0.9398)
			(end -0.508 -0.9398)
			(stroke
				(width 0.1524)
				(type default)
			)
			(layer "F.SilkS")
		)
		(fp_rect
			(start -0.508 0.9398)
			(end 0.508 -0.9398)
			(stroke
				(width 0)
				(type default)
			)
			(fill no)
			(layer "F.CrtYd")
		)
		(fp_rect
			(start -0.508 0.9398)
			(end 0.508 -0.9398)
			(stroke
				(width 0)
				(type default)
			)
			(fill no)
			(layer "F.Fab")
		)
		(pad "1" smd custom
			(at 0 -0.4445)
			(size 0.1397 0.1397)
			(layers "F.Cu" "F.Mask" "F.Paste")
			(net "SSD6_PWREN")
			(options
				(clearance outline)
				(anchor circle)
			)
			(primitives
				(gr_poly
					(pts
						(arc
							(start -0.1778 -0.2794)
							(mid -0.249642 -0.249642)
							(end -0.2794 -0.1778)
						)
						(arc
							(start -0.2794 0.1778)
							(mid -0.249642 0.249642)
							(end -0.1778 0.2794)
						)
						(arc
							(start 0.1778 0.2794)
							(mid 0.249642 0.249642)
							(end 0.2794 0.1778)
						)
						(arc
							(start 0.2794 -0.1778)
							(mid 0.249642 -0.249642)
							(end 0.1778 -0.2794)
						)
					)
					(width 0)
					(fill yes)
				)
			)
		)
		(pad "2" smd custom
			(at 0 0.4445)
			(size 0.1397 0.1397)
			(layers "F.Cu" "F.Mask" "F.Paste")
			(net "GND")
			(options
				(clearance outline)
				(anchor circle)
			)
			(primitives
				(gr_poly
					(pts
						(arc
							(start -0.1778 -0.2794)
							(mid -0.249642 -0.249642)
							(end -0.2794 -0.1778)
						)
						(arc
							(start -0.2794 0.1778)
							(mid -0.249642 0.249642)
							(end -0.1778 0.2794)
						)
						(arc
							(start 0.1778 0.2794)
							(mid 0.249642 0.249642)
							(end 0.2794 0.1778)
						)
						(arc
							(start 0.2794 -0.1778)
							(mid 0.249642 -0.249642)
							(end 0.1778 -0.2794)
						)
					)
					(width 0)
					(fill yes)
				)
			)
		)
	)
	(footprint ""
		(layer "F.Cu")
		(at 102.616 -310.515 90)
		(property "Reference" "R9071"
			(at 0 0 90)
			(layer "F.SilkS")
			(hide yes)
			(effects
				(font
					(size 1.27 1.27)
				)
			)
		)
		(property "Value" "27R2F-GP"
			(at 0.064008 -3.993896 90)
			(unlocked yes)
			(layer "F.Fab")
			(hide yes)
			(effects
				(font
					(size 1.016 1.016)
					(thickness 0.1524)
				)
			)
		)
		(property "Device Type" "R402H16"
			(at 0.064008 -5.517896 90)
			(unlocked yes)
			(layer "F.Fab")
			(hide yes)
			(effects
				(font
					(size 1.016 1.016)
					(thickness 0.1524)
				)
			)
		)
		(duplicate_pad_numbers_are_jumpers no)
		(fp_line
			(start 0.508 -0.9398)
			(end -0.508 -0.9398)
			(stroke
				(width 0.1524)
				(type default)
			)
			(layer "F.SilkS")
		)
		(fp_line
			(start -0.508 -0.9398)
			(end -0.508 0.9398)
			(stroke
				(width 0.1524)
				(type default)
			)
			(layer "F.SilkS")
		)
		(fp_rect
			(start -0.508 0.9398)
			(end 0.508 -0.9398)
			(stroke
				(width 0)
				(type default)
			)
			(fill no)
			(layer "F.CrtYd")
		)
		(fp_rect
			(start -0.508 0.9398)
			(end 0.508 -0.9398)
			(stroke
				(width 0)
				(type default)
			)
			(fill no)
			(layer "F.Fab")
		)
		(pad "1" smd custom
			(at 0 -0.4445 90)
			(size 0.1397 0.1397)
			(layers "F.Cu" "F.Mask" "F.Paste")
			(net "PE_CLK_100M_DR1_1_R_P")
			(options
				(clearance outline)
				(anchor circle)
			)
			(primitives
				(gr_poly
					(pts
						(arc
							(start -0.1778 -0.2794)
							(mid -0.249642 -0.249642)
							(end -0.2794 -0.1778)
						)
						(arc
							(start -0.2794 0.1778)
							(mid -0.249642 0.249642)
							(end -0.1778 0.2794)
						)
						(arc
							(start 0.1778 0.2794)
							(mid 0.249642 0.249642)
							(end 0.2794 0.1778)
						)
						(arc
							(start 0.2794 -0.1778)
							(mid 0.249642 -0.249642)
							(end 0.1778 -0.2794)
						)
					)
					(width 0)
					(fill yes)
				)
			)
		)
		(pad "2" smd custom
			(at 0 0.4445 90)
			(size 0.1397 0.1397)
			(layers "F.Cu" "F.Mask" "F.Paste")
			(net "PE_CLK100M_DR1_1_P")
			(options
				(clearance outline)
				(anchor circle)
			)
			(primitives
				(gr_poly
					(pts
						(arc
							(start -0.1778 -0.2794)
							(mid -0.249642 -0.249642)
							(end -0.2794 -0.1778)
						)
						(arc
							(start -0.2794 0.1778)
							(mid -0.249642 0.249642)
							(end -0.1778 0.2794)
						)
						(arc
							(start 0.1778 0.2794)
							(mid 0.249642 0.249642)
							(end 0.2794 0.1778)
						)
						(arc
							(start 0.2794 -0.1778)
							(mid 0.249642 -0.249642)
							(end 0.1778 -0.2794)
						)
					)
					(width 0)
					(fill yes)
				)
			)
		)
	)
	(footprint ""
		(layer "F.Cu")
		(at 19.910298 -470.984072 -90)
		(property "Reference" "C9528"
			(at 0 0 270)
			(layer "F.SilkS")
			(hide yes)
			(effects
				(font
					(size 1.27 1.27)
				)
			)
		)
		(property "Value" "SCD1U16V2KX-3GP"
			(at 1.1811 -2.7051 270)
			(unlocked yes)
			(layer "F.Fab")
			(hide yes)
			(effects
				(font
					(size 1.016 1.016)
					(thickness 0.1524)
				)
			)
		)
		(property "Device Type" "C402H22"
			(at 1.1811 -4.2291 270)
			(unlocked yes)
			(layer "F.Fab")
			(hide yes)
			(effects
				(font
					(size 1.016 1.016)
					(thickness 0.1524)
				)
			)
		)
		(duplicate_pad_numbers_are_jumpers no)
		(fp_rect
			(start -0.4318 0.9525)
			(end 0.4318 -0.9525)
			(stroke
				(width 0)
				(type default)
			)
			(fill no)
			(layer "F.CrtYd")
		)
		(fp_rect
			(start -0.4318 0.9525)
			(end 0.4318 -0.9525)
			(stroke
				(width 0)
				(type default)
			)
			(fill no)
			(layer "F.Fab")
		)
		(pad "1" smd custom
			(at 0 -0.4445 270)
			(size 0.1524 0.1524)
			(layers "F.Cu" "F.Mask" "F.Paste")
			(net "P3V3")
			(options
				(clearance outline)
				(anchor circle)
			)
			(primitives
				(gr_poly
					(pts
						(arc
							(start 0.3048 -0.2032)
							(mid 0.275042 -0.275042)
							(end 0.2032 -0.3048)
						)
						(arc
							(start -0.2032 -0.3048)
							(mid -0.275042 -0.275042)
							(end -0.3048 -0.2032)
						)
						(arc
							(start -0.3048 0.2032)
							(mid -0.275042 0.275042)
							(end -0.2032 0.3048)
						)
						(arc
							(start 0.2032 0.3048)
							(mid 0.275042 0.275042)
							(end 0.3048 0.2032)
						)
					)
					(width 0)
					(fill yes)
				)
			)
		)
		(pad "2" smd custom
			(at 0 0.4445 270)
			(size 0.1524 0.1524)
			(layers "F.Cu" "F.Mask" "F.Paste")
			(net "GND")
			(options
				(clearance outline)
				(anchor circle)
			)
			(primitives
				(gr_poly
					(pts
						(arc
							(start 0.3048 -0.2032)
							(mid 0.275042 -0.275042)
							(end 0.2032 -0.3048)
						)
						(arc
							(start -0.2032 -0.3048)
							(mid -0.275042 -0.275042)
							(end -0.3048 -0.2032)
						)
						(arc
							(start -0.3048 0.2032)
							(mid -0.275042 0.275042)
							(end -0.2032 0.3048)
						)
						(arc
							(start 0.2032 0.3048)
							(mid 0.275042 0.275042)
							(end 0.3048 0.2032)
						)
					)
					(width 0)
					(fill yes)
				)
			)
		)
	)
	(footprint ""
		(layer "F.Cu")
		(at 234.061 -246.634 -90)
		(property "Reference" "R9401"
			(at 0 0 270)
			(layer "F.SilkS")
			(hide yes)
			(effects
				(font
					(size 1.27 1.27)
				)
			)
		)
		(property "Value" "100R2J-2-GP"
			(at 0.064008 -3.993896 270)
			(unlocked yes)
			(layer "F.Fab")
			(hide yes)
			(effects
				(font
					(size 1.016 1.016)
					(thickness 0.1524)
				)
			)
		)
		(property "Device Type" "R402H14"
			(at 0.064008 -5.517896 270)
			(unlocked yes)
			(layer "F.Fab")
			(hide yes)
			(effects
				(font
					(size 1.016 1.016)
					(thickness 0.1524)
				)
			)
		)
		(duplicate_pad_numbers_are_jumpers no)
		(fp_line
			(start -0.508 -0.9398)
			(end -0.508 0.9398)
			(stroke
				(width 0.1524)
				(type default)
			)
			(layer "F.SilkS")
		)
		(fp_line
			(start 0.508 -0.9398)
			(end -0.508 -0.9398)
			(stroke
				(width 0.1524)
				(type default)
			)
			(layer "F.SilkS")
		)
		(fp_rect
			(start -0.508 0.9398)
			(end 0.508 -0.9398)
			(stroke
				(width 0)
				(type default)
			)
			(fill no)
			(layer "F.CrtYd")
		)
		(fp_rect
			(start -0.508 0.9398)
			(end 0.508 -0.9398)
			(stroke
				(width 0)
				(type default)
			)
			(fill no)
			(layer "F.Fab")
		)
		(pad "1" smd custom
			(at 0 -0.4445 270)
			(size 0.1397 0.1397)
			(layers "F.Cu" "F.Mask" "F.Paste")
			(net "P3V3")
			(options
				(clearance outline)
				(anchor circle)
			)
			(primitives
				(gr_poly
					(pts
						(arc
							(start -0.1778 -0.2794)
							(mid -0.249642 -0.249642)
							(end -0.2794 -0.1778)
						)
						(arc
							(start -0.2794 0.1778)
							(mid -0.249642 0.249642)
							(end -0.1778 0.2794)
						)
						(arc
							(start 0.1778 0.2794)
							(mid 0.249642 0.249642)
							(end 0.2794 0.1778)
						)
						(arc
							(start 0.2794 -0.1778)
							(mid 0.249642 -0.249642)
							(end 0.1778 -0.2794)
						)
					)
					(width 0)
					(fill yes)
				)
			)
		)
		(pad "2" smd custom
			(at 0 0.4445 270)
			(size 0.1397 0.1397)
			(layers "F.Cu" "F.Mask" "F.Paste")
			(net "DRV_ACT_2")
			(options
				(clearance outline)
				(anchor circle)
			)
			(primitives
				(gr_poly
					(pts
						(arc
							(start -0.1778 -0.2794)
							(mid -0.249642 -0.249642)
							(end -0.2794 -0.1778)
						)
						(arc
							(start -0.2794 0.1778)
							(mid -0.249642 0.249642)
							(end -0.1778 0.2794)
						)
						(arc
							(start 0.1778 0.2794)
							(mid 0.249642 0.249642)
							(end 0.2794 0.1778)
						)
						(arc
							(start 0.2794 -0.1778)
							(mid 0.249642 -0.249642)
							(end 0.1778 -0.2794)
						)
					)
					(width 0)
					(fill yes)
				)
			)
		)
	)
	(footprint ""
		(layer "F.Cu")
		(at 225.1075 -142.42161 90)
		(property "Reference" "R9915"
			(at 0 0 90)
			(layer "F.SilkS")
			(hide yes)
			(effects
				(font
					(size 1.27 1.27)
				)
			)
		)
		(property "Value" "47KR2J-2-GP"
			(at 0.064008 -3.993896 90)
			(unlocked yes)
			(layer "F.Fab")
			(hide yes)
			(effects
				(font
					(size 1.016 1.016)
					(thickness 0.1524)
				)
			)
		)
		(property "Device Type" "R402H16"
			(at 0.064008 -5.517896 90)
			(unlocked yes)
			(layer "F.Fab")
			(hide yes)
			(effects
				(font
					(size 1.016 1.016)
					(thickness 0.1524)
				)
			)
		)
		(duplicate_pad_numbers_are_jumpers no)
		(fp_line
			(start 0.508 -0.9398)
			(end -0.508 -0.9398)
			(stroke
				(width 0.1524)
				(type default)
			)
			(layer "F.SilkS")
		)
		(fp_line
			(start -0.508 -0.9398)
			(end -0.508 0.9398)
			(stroke
				(width 0.1524)
				(type default)
			)
			(layer "F.SilkS")
		)
		(fp_rect
			(start -0.508 0.9398)
			(end 0.508 -0.9398)
			(stroke
				(width 0)
				(type default)
			)
			(fill no)
			(layer "F.CrtYd")
		)
		(fp_rect
			(start -0.508 0.9398)
			(end 0.508 -0.9398)
			(stroke
				(width 0)
				(type default)
			)
			(fill no)
			(layer "F.Fab")
		)
		(pad "1" smd custom
			(at 0 -0.4445 90)
			(size 0.1397 0.1397)
			(layers "F.Cu" "F.Mask" "F.Paste")
			(net "P3V3")
			(options
				(clearance outline)
				(anchor circle)
			)
			(primitives
				(gr_poly
					(pts
						(arc
							(start -0.1778 -0.2794)
							(mid -0.249642 -0.249642)
							(end -0.2794 -0.1778)
						)
						(arc
							(start -0.2794 0.1778)
							(mid -0.249642 0.249642)
							(end -0.1778 0.2794)
						)
						(arc
							(start 0.1778 0.2794)
							(mid 0.249642 0.249642)
							(end 0.2794 0.1778)
						)
						(arc
							(start 0.2794 -0.1778)
							(mid 0.249642 -0.249642)
							(end 0.1778 -0.2794)
						)
					)
					(width 0)
					(fill yes)
				)
			)
		)
		(pad "2" smd custom
			(at 0 0.4445 90)
			(size 0.1397 0.1397)
			(layers "F.Cu" "F.Mask" "F.Paste")
			(net "ATTN_LED_DR3_N")
			(options
				(clearance outline)
				(anchor circle)
			)
			(primitives
				(gr_poly
					(pts
						(arc
							(start -0.1778 -0.2794)
							(mid -0.249642 -0.249642)
							(end -0.2794 -0.1778)
						)
						(arc
							(start -0.2794 0.1778)
							(mid -0.249642 0.249642)
							(end -0.1778 0.2794)
						)
						(arc
							(start 0.1778 0.2794)
							(mid 0.249642 0.249642)
							(end 0.2794 0.1778)
						)
						(arc
							(start 0.2794 -0.1778)
							(mid 0.249642 -0.249642)
							(end 0.1778 -0.2794)
						)
					)
					(width 0)
					(fill yes)
				)
			)
		)
	)
	(footprint ""
		(layer "F.Cu")
		(at 32.131 -184.531 -90)
		(property "Reference" "R403"
			(at 0 0 270)
			(layer "F.SilkS")
			(hide yes)
			(effects
				(font
					(size 1.27 1.27)
				)
			)
		)
		(property "Value" "0R2J-2-GP"
			(at 0.064008 -3.993896 270)
			(unlocked yes)
			(layer "F.Fab")
			(hide yes)
			(effects
				(font
					(size 1.016 1.016)
					(thickness 0.1524)
				)
			)
		)
		(property "Device Type" "R402H16"
			(at 0.064008 -5.517896 270)
			(unlocked yes)
			(layer "F.Fab")
			(hide yes)
			(effects
				(font
					(size 1.016 1.016)
					(thickness 0.1524)
				)
			)
		)
		(duplicate_pad_numbers_are_jumpers no)
		(fp_line
			(start -0.508 -0.9398)
			(end -0.508 0.9398)
			(stroke
				(width 0.1524)
				(type default)
			)
			(layer "F.SilkS")
		)
		(fp_line
			(start 0.508 -0.9398)
			(end -0.508 -0.9398)
			(stroke
				(width 0.1524)
				(type default)
			)
			(layer "F.SilkS")
		)
		(fp_rect
			(start -0.508 0.9398)
			(end 0.508 -0.9398)
			(stroke
				(width 0)
				(type default)
			)
			(fill no)
			(layer "F.CrtYd")
		)
		(fp_rect
			(start -0.508 0.9398)
			(end 0.508 -0.9398)
			(stroke
				(width 0)
				(type default)
			)
			(fill no)
			(layer "F.Fab")
		)
		(pad "1" smd custom
			(at 0 -0.4445 270)
			(size 0.1397 0.1397)
			(layers "F.Cu" "F.Mask" "F.Paste")
			(net "SCL_DR8_R")
			(options
				(clearance outline)
				(anchor circle)
			)
			(primitives
				(gr_poly
					(pts
						(arc
							(start -0.1778 -0.2794)
							(mid -0.249642 -0.249642)
							(end -0.2794 -0.1778)
						)
						(arc
							(start -0.2794 0.1778)
							(mid -0.249642 0.249642)
							(end -0.1778 0.2794)
						)
						(arc
							(start 0.1778 0.2794)
							(mid 0.249642 0.249642)
							(end 0.2794 0.1778)
						)
						(arc
							(start 0.2794 -0.1778)
							(mid 0.249642 -0.249642)
							(end 0.1778 -0.2794)
						)
					)
					(width 0)
					(fill yes)
				)
			)
		)
		(pad "2" smd custom
			(at 0 0.4445 270)
			(size 0.1397 0.1397)
			(layers "F.Cu" "F.Mask" "F.Paste")
			(net "SCL_DR8")
			(options
				(clearance outline)
				(anchor circle)
			)
			(primitives
				(gr_poly
					(pts
						(arc
							(start -0.1778 -0.2794)
							(mid -0.249642 -0.249642)
							(end -0.2794 -0.1778)
						)
						(arc
							(start -0.2794 0.1778)
							(mid -0.249642 0.249642)
							(end -0.1778 0.2794)
						)
						(arc
							(start 0.1778 0.2794)
							(mid 0.249642 0.249642)
							(end 0.2794 0.1778)
						)
						(arc
							(start 0.2794 -0.1778)
							(mid 0.249642 -0.249642)
							(end 0.1778 -0.2794)
						)
					)
					(width 0)
					(fill yes)
				)
			)
		)
	)
	(footprint ""
		(layer "F.Cu")
		(at 85.471 -208.026 90)
		(property "Reference" "R9119"
			(at 0 0 90)
			(layer "F.SilkS")
			(hide yes)
			(effects
				(font
					(size 1.27 1.27)
				)
			)
		)
		(property "Value" "4K7R2F-GP"
			(at 0.064008 -3.993896 90)
			(unlocked yes)
			(layer "F.Fab")
			(hide yes)
			(effects
				(font
					(size 1.016 1.016)
					(thickness 0.1524)
				)
			)
		)
		(property "Device Type" "R402H16"
			(at 0.064008 -5.517896 90)
			(unlocked yes)
			(layer "F.Fab")
			(hide yes)
			(effects
				(font
					(size 1.016 1.016)
					(thickness 0.1524)
				)
			)
		)
		(duplicate_pad_numbers_are_jumpers no)
		(fp_line
			(start 0.508 -0.9398)
			(end -0.508 -0.9398)
			(stroke
				(width 0.1524)
				(type default)
			)
			(layer "F.SilkS")
		)
		(fp_line
			(start -0.508 -0.9398)
			(end -0.508 0.9398)
			(stroke
				(width 0.1524)
				(type default)
			)
			(layer "F.SilkS")
		)
		(fp_rect
			(start -0.508 0.9398)
			(end 0.508 -0.9398)
			(stroke
				(width 0)
				(type default)
			)
			(fill no)
			(layer "F.CrtYd")
		)
		(fp_rect
			(start -0.508 0.9398)
			(end 0.508 -0.9398)
			(stroke
				(width 0)
				(type default)
			)
			(fill no)
			(layer "F.Fab")
		)
		(pad "1" smd custom
			(at 0 -0.4445 90)
			(size 0.1397 0.1397)
			(layers "F.Cu" "F.Mask" "F.Paste")
			(net "VDD_DIFF_3")
			(options
				(clearance outline)
				(anchor circle)
			)
			(primitives
				(gr_poly
					(pts
						(arc
							(start -0.1778 -0.2794)
							(mid -0.249642 -0.249642)
							(end -0.2794 -0.1778)
						)
						(arc
							(start -0.2794 0.1778)
							(mid -0.249642 0.249642)
							(end -0.1778 0.2794)
						)
						(arc
							(start 0.1778 0.2794)
							(mid 0.249642 0.249642)
							(end 0.2794 0.1778)
						)
						(arc
							(start 0.2794 -0.1778)
							(mid 0.249642 -0.249642)
							(end 0.1778 -0.2794)
						)
					)
					(width 0)
					(fill yes)
				)
			)
		)
		(pad "2" smd custom
			(at 0 0.4445 90)
			(size 0.1397 0.1397)
			(layers "F.Cu" "F.Mask" "F.Paste")
			(net "CLK_BUF_EU3_SMB_A0_TRI")
			(options
				(clearance outline)
				(anchor circle)
			)
			(primitives
				(gr_poly
					(pts
						(arc
							(start -0.1778 -0.2794)
							(mid -0.249642 -0.249642)
							(end -0.2794 -0.1778)
						)
						(arc
							(start -0.2794 0.1778)
							(mid -0.249642 0.249642)
							(end -0.1778 0.2794)
						)
						(arc
							(start 0.1778 0.2794)
							(mid 0.249642 0.249642)
							(end 0.2794 0.1778)
						)
						(arc
							(start 0.2794 -0.1778)
							(mid 0.249642 -0.249642)
							(end 0.1778 -0.2794)
						)
					)
					(width 0)
					(fill yes)
				)
			)
		)
	)
	(footprint ""
		(layer "F.Cu")
		(at 43.282108 -37.961062 180)
		(property "Reference" "SR1140"
			(at 0 0 180)
			(layer "F.SilkS")
			(hide yes)
			(effects
				(font
					(size 1.27 1.27)
				)
			)
		)
		(property "Value" "4K7R2J-2-GP"
			(at 0.064008 -3.993896 180)
			(unlocked yes)
			(layer "F.Fab")
			(hide yes)
			(effects
				(font
					(size 1.016 1.016)
					(thickness 0.1524)
				)
			)
		)
		(property "Device Type" "R402H16"
			(at 0.064008 -5.517896 180)
			(unlocked yes)
			(layer "F.Fab")
			(hide yes)
			(effects
				(font
					(size 1.016 1.016)
					(thickness 0.1524)
				)
			)
		)
		(duplicate_pad_numbers_are_jumpers no)
		(fp_line
			(start 0.508 -0.9398)
			(end -0.508 -0.9398)
			(stroke
				(width 0.1524)
				(type default)
			)
			(layer "F.SilkS")
		)
		(fp_line
			(start -0.508 -0.9398)
			(end -0.508 0.9398)
			(stroke
				(width 0.1524)
				(type default)
			)
			(layer "F.SilkS")
		)
		(fp_rect
			(start -0.508 0.9398)
			(end 0.508 -0.9398)
			(stroke
				(width 0)
				(type default)
			)
			(fill no)
			(layer "F.CrtYd")
		)
		(fp_rect
			(start -0.508 0.9398)
			(end 0.508 -0.9398)
			(stroke
				(width 0)
				(type default)
			)
			(fill no)
			(layer "F.Fab")
		)
		(pad "1" smd custom
			(at 0 -0.4445 180)
			(size 0.1397 0.1397)
			(layers "F.Cu" "F.Mask" "F.Paste")
			(net "P3V3")
			(options
				(clearance outline)
				(anchor circle)
			)
			(primitives
				(gr_poly
					(pts
						(arc
							(start -0.1778 -0.2794)
							(mid -0.249642 -0.249642)
							(end -0.2794 -0.1778)
						)
						(arc
							(start -0.2794 0.1778)
							(mid -0.249642 0.249642)
							(end -0.1778 0.2794)
						)
						(arc
							(start 0.1778 0.2794)
							(mid 0.249642 0.249642)
							(end 0.2794 0.1778)
						)
						(arc
							(start 0.2794 -0.1778)
							(mid 0.249642 -0.249642)
							(end 0.1778 -0.2794)
						)
					)
					(width 0)
					(fill yes)
				)
			)
		)
		(pad "2" smd custom
			(at 0 0.4445 180)
			(size 0.1397 0.1397)
			(layers "F.Cu" "F.Mask" "F.Paste")
			(net "SSD_ACT_DR9")
			(options
				(clearance outline)
				(anchor circle)
			)
			(primitives
				(gr_poly
					(pts
						(arc
							(start -0.1778 -0.2794)
							(mid -0.249642 -0.249642)
							(end -0.2794 -0.1778)
						)
						(arc
							(start -0.2794 0.1778)
							(mid -0.249642 0.249642)
							(end -0.1778 0.2794)
						)
						(arc
							(start 0.1778 0.2794)
							(mid 0.249642 0.249642)
							(end 0.2794 0.1778)
						)
						(arc
							(start 0.2794 -0.1778)
							(mid 0.249642 -0.249642)
							(end 0.1778 -0.2794)
						)
					)
					(width 0)
					(fill yes)
				)
			)
		)
	)
	(footprint ""
		(layer "F.Cu")
		(at 82.931 -435.102 -90)
		(property "Reference" "PR9061"
			(at 0 0 270)
			(layer "F.SilkS")
			(hide yes)
			(effects
				(font
					(size 1.27 1.27)
				)
			)
		)
		(property "Value" "1K4R2F-1-GP"
			(at 0.064008 -3.993896 270)
			(unlocked yes)
			(layer "F.Fab")
			(hide yes)
			(effects
				(font
					(size 1.016 1.016)
					(thickness 0.1524)
				)
			)
		)
		(property "Device Type" "R402H16"
			(at 0.064008 -5.517896 270)
			(unlocked yes)
			(layer "F.Fab")
			(hide yes)
			(effects
				(font
					(size 1.016 1.016)
					(thickness 0.1524)
				)
			)
		)
		(duplicate_pad_numbers_are_jumpers no)
		(fp_line
			(start -0.508 -0.9398)
			(end -0.508 0.9398)
			(stroke
				(width 0.1524)
				(type default)
			)
			(layer "F.SilkS")
		)
		(fp_line
			(start 0.508 -0.9398)
			(end -0.508 -0.9398)
			(stroke
				(width 0.1524)
				(type default)
			)
			(layer "F.SilkS")
		)
		(fp_rect
			(start -0.508 0.9398)
			(end 0.508 -0.9398)
			(stroke
				(width 0)
				(type default)
			)
			(fill no)
			(layer "F.CrtYd")
		)
		(fp_rect
			(start -0.508 0.9398)
			(end 0.508 -0.9398)
			(stroke
				(width 0)
				(type default)
			)
			(fill no)
			(layer "F.Fab")
		)
		(pad "1" smd custom
			(at 0 -0.4445 270)
			(size 0.1397 0.1397)
			(layers "F.Cu" "F.Mask" "F.Paste")
			(net "CLK_BUF_EU1_HIBW_BYPM_LOBW#")
			(options
				(clearance outline)
				(anchor circle)
			)
			(primitives
				(gr_poly
					(pts
						(arc
							(start -0.1778 -0.2794)
							(mid -0.249642 -0.249642)
							(end -0.2794 -0.1778)
						)
						(arc
							(start -0.2794 0.1778)
							(mid -0.249642 0.249642)
							(end -0.1778 0.2794)
						)
						(arc
							(start 0.1778 0.2794)
							(mid 0.249642 0.249642)
							(end 0.2794 0.1778)
						)
						(arc
							(start 0.2794 -0.1778)
							(mid 0.249642 -0.249642)
							(end 0.1778 -0.2794)
						)
					)
					(width 0)
					(fill yes)
				)
			)
		)
		(pad "2" smd custom
			(at 0 0.4445 270)
			(size 0.1397 0.1397)
			(layers "F.Cu" "F.Mask" "F.Paste")
			(net "GND")
			(options
				(clearance outline)
				(anchor circle)
			)
			(primitives
				(gr_poly
					(pts
						(arc
							(start -0.1778 -0.2794)
							(mid -0.249642 -0.249642)
							(end -0.2794 -0.1778)
						)
						(arc
							(start -0.2794 0.1778)
							(mid -0.249642 0.249642)
							(end -0.1778 0.2794)
						)
						(arc
							(start 0.1778 0.2794)
							(mid 0.249642 0.249642)
							(end 0.2794 0.1778)
						)
						(arc
							(start 0.2794 -0.1778)
							(mid 0.249642 -0.249642)
							(end 0.1778 -0.2794)
						)
					)
					(width 0)
					(fill yes)
				)
			)
		)
	)
	(footprint ""
		(layer "F.Cu")
		(at 206.359506 -493.168178 -90)
		(property "Reference" "U9"
			(at 0 0 270)
			(layer "F.SilkS")
			(hide yes)
			(effects
				(font
					(size 1.27 1.27)
				)
			)
		)
		(property "Value" "P2003EVG-GP"
			(at 0 -11.1252 270)
			(unlocked yes)
			(layer "F.Fab")
			(hide yes)
			(effects
				(font
					(size 1.016 1.016)
					(thickness 0.1524)
				)
			)
		)
		(property "Device Type" "SOIC8H79"
			(at 0 -12.6492 270)
			(unlocked yes)
			(layer "F.Fab")
			(hide yes)
			(effects
				(font
					(size 1.016 1.016)
					(thickness 0.1524)
				)
			)
		)
		(duplicate_pad_numbers_are_jumpers no)
		(fp_line
			(start -2.6162 3.429)
			(end -2.6162 1.4732)
			(stroke
				(width 0.4064)
				(type default)
			)
			(layer "F.SilkS")
		)
		(fp_line
			(start -2.7432 1.4224)
			(end 2.1336 1.4224)
			(stroke
				(width 0.1524)
				(type default)
			)
			(layer "F.SilkS")
		)
		(fp_line
			(start 2.1336 1.4224)
			(end 2.1336 -1.4224)
			(stroke
				(width 0.1524)
				(type default)
			)
			(layer "F.SilkS")
		)
		(fp_line
			(start -2.2352 0)
			(end -2.7432 0.508)
			(stroke
				(width 0.1524)
				(type default)
			)
			(layer "F.SilkS")
		)
		(fp_line
			(start -2.7432 -0.508)
			(end -2.2352 0)
			(stroke
				(width 0.1524)
				(type default)
			)
			(layer "F.SilkS")
		)
		(fp_line
			(start -2.7432 -1.4224)
			(end -2.7432 1.4224)
			(stroke
				(width 0.1524)
				(type default)
			)
			(layer "F.SilkS")
		)
		(fp_line
			(start 2.1336 -1.4224)
			(end -2.7432 -1.4224)
			(stroke
				(width 0.1524)
				(type default)
			)
			(layer "F.SilkS")
		)
		(fp_poly
			(pts
				(xy 2.2098 -1.4224) (xy 2.2098 1.4224) (xy -2.2225 1.4224) (xy -2.2225 -1.4224)
			)
			(stroke
				(width 0)
				(type default)
			)
			(fill yes)
			(layer "F.SilkS")
		)
		(fp_rect
			(start -2.4511 2.9972)
			(end 2.4511 -2.9972)
			(stroke
				(width 0)
				(type default)
			)
			(fill no)
			(layer "F.CrtYd")
		)
		(fp_poly
			(pts
				(xy -2.8194 3.6322) (xy -2.8194 -3.6322) (xy 2.8194 -3.6322) (xy 2.8194 -2.2987) (xy 2.4511 -2.2987)
				(xy 2.4511 -2.9972) (xy -2.4511 -2.9972) (xy -2.4511 2.9972) (xy 2.4511 2.9972) (xy 2.4511 -2.286)
				(xy 2.8194 -2.286) (xy 2.8194 3.6322)
			)
			(stroke
				(width 0)
				(type default)
			)
			(fill no)
			(layer "F.CrtYd")
		)
		(fp_rect
			(start -2.8194 3.6322)
			(end 2.8194 -3.6322)
			(stroke
				(width 0)
				(type default)
			)
			(fill no)
			(layer "F.Fab")
		)
		(pad "1" smd rect
			(at -1.905 2.54 270)
			(size 0.635 1.651)
			(layers "F.Cu" "F.Mask" "F.Paste")
			(net "P12V")
		)
		(pad "2" smd rect
			(at -0.635 2.54 270)
			(size 0.635 1.651)
			(layers "F.Cu" "F.Mask" "F.Paste")
			(net "P12V")
		)
		(pad "3" smd rect
			(at 0.635 2.54 270)
			(size 0.635 1.651)
			(layers "F.Cu" "F.Mask" "F.Paste")
			(net "P12V")
		)
		(pad "4" smd rect
			(at 1.905 2.54 270)
			(size 0.635 1.651)
			(layers "F.Cu" "F.Mask" "F.Paste")
			(net "SW_SSD0_N")
		)
		(pad "5" smd rect
			(at 1.905 -2.54 270)
			(size 0.635 1.651)
			(layers "F.Cu" "F.Mask" "F.Paste")
			(net "P12V_SSD0")
		)
		(pad "6" smd rect
			(at 0.635 -2.54 270)
			(size 0.635 1.651)
			(layers "F.Cu" "F.Mask" "F.Paste")
			(net "P12V_SSD0")
		)
		(pad "7" smd rect
			(at -0.635 -2.54 270)
			(size 0.635 1.651)
			(layers "F.Cu" "F.Mask" "F.Paste")
			(net "P12V_SSD0")
		)
		(pad "8" smd rect
			(at -1.905 -2.54 270)
			(size 0.635 1.651)
			(layers "F.Cu" "F.Mask" "F.Paste")
			(net "P12V_SSD0")
		)
	)
	(footprint ""
		(layer "F.Cu")
		(at 25.3238 -293.2176)
		(property "Reference" "C389"
			(at 0 0 0)
			(layer "F.SilkS")
			(hide yes)
			(effects
				(font
					(size 1.27 1.27)
				)
			)
		)
		(property "Value" "SCD1U25V2KX-2-GP"
			(at 1.1811 -2.7051 0)
			(unlocked yes)
			(layer "F.Fab")
			(hide yes)
			(effects
				(font
					(size 1.016 1.016)
					(thickness 0.1524)
				)
			)
		)
		(property "Device Type" "C402H22"
			(at 1.1811 -4.2291 0)
			(unlocked yes)
			(layer "F.Fab")
			(hide yes)
			(effects
				(font
					(size 1.016 1.016)
					(thickness 0.1524)
				)
			)
		)
		(duplicate_pad_numbers_are_jumpers no)
		(fp_rect
			(start -0.4318 0.9525)
			(end 0.4318 -0.9525)
			(stroke
				(width 0)
				(type default)
			)
			(fill no)
			(layer "F.CrtYd")
		)
		(fp_rect
			(start -0.4318 0.9525)
			(end 0.4318 -0.9525)
			(stroke
				(width 0)
				(type default)
			)
			(fill no)
			(layer "F.Fab")
		)
		(pad "1" smd custom
			(at 0 -0.4445)
			(size 0.1524 0.1524)
			(layers "F.Cu" "F.Mask" "F.Paste")
			(net "P12V")
			(options
				(clearance outline)
				(anchor circle)
			)
			(primitives
				(gr_poly
					(pts
						(arc
							(start 0.3048 -0.2032)
							(mid 0.275042 -0.275042)
							(end 0.2032 -0.3048)
						)
						(arc
							(start -0.2032 -0.3048)
							(mid -0.275042 -0.275042)
							(end -0.3048 -0.2032)
						)
						(arc
							(start -0.3048 0.2032)
							(mid -0.275042 0.275042)
							(end -0.2032 0.3048)
						)
						(arc
							(start 0.2032 0.3048)
							(mid 0.275042 0.275042)
							(end 0.3048 0.2032)
						)
					)
					(width 0)
					(fill yes)
				)
			)
		)
		(pad "2" smd custom
			(at 0 0.4445)
			(size 0.1524 0.1524)
			(layers "F.Cu" "F.Mask" "F.Paste")
			(net "SW_SSD7_N")
			(options
				(clearance outline)
				(anchor circle)
			)
			(primitives
				(gr_poly
					(pts
						(arc
							(start 0.3048 -0.2032)
							(mid 0.275042 -0.275042)
							(end 0.2032 -0.3048)
						)
						(arc
							(start -0.2032 -0.3048)
							(mid -0.275042 -0.275042)
							(end -0.3048 -0.2032)
						)
						(arc
							(start -0.3048 0.2032)
							(mid -0.275042 0.275042)
							(end -0.2032 0.3048)
						)
						(arc
							(start 0.2032 0.3048)
							(mid 0.275042 0.275042)
							(end 0.3048 0.2032)
						)
					)
					(width 0)
					(fill yes)
				)
			)
		)
	)
	(footprint ""
		(layer "F.Cu")
		(at 90.17 -224.282)
		(property "Reference" "R9613"
			(at 0 0 0)
			(layer "F.SilkS")
			(hide yes)
			(effects
				(font
					(size 1.27 1.27)
				)
			)
		)
		(property "Value" "10R2F-L-GP"
			(at 0.064008 -3.993896 0)
			(unlocked yes)
			(layer "F.Fab")
			(hide yes)
			(effects
				(font
					(size 1.016 1.016)
					(thickness 0.1524)
				)
			)
		)
		(property "Device Type" "R402H14"
			(at 0.064008 -5.517896 0)
			(unlocked yes)
			(layer "F.Fab")
			(hide yes)
			(effects
				(font
					(size 1.016 1.016)
					(thickness 0.1524)
				)
			)
		)
		(duplicate_pad_numbers_are_jumpers no)
		(fp_line
			(start -0.508 -0.9398)
			(end -0.508 0.9398)
			(stroke
				(width 0.1524)
				(type default)
			)
			(layer "F.SilkS")
		)
		(fp_line
			(start 0.508 -0.9398)
			(end -0.508 -0.9398)
			(stroke
				(width 0.1524)
				(type default)
			)
			(layer "F.SilkS")
		)
		(fp_rect
			(start -0.508 0.9398)
			(end 0.508 -0.9398)
			(stroke
				(width 0)
				(type default)
			)
			(fill no)
			(layer "F.CrtYd")
		)
		(fp_rect
			(start -0.508 0.9398)
			(end 0.508 -0.9398)
			(stroke
				(width 0)
				(type default)
			)
			(fill no)
			(layer "F.Fab")
		)
		(pad "1" smd custom
			(at 0 -0.4445)
			(size 0.1397 0.1397)
			(layers "F.Cu" "F.Mask" "F.Paste")
			(net "SSD_PRSNT_NET12")
			(options
				(clearance outline)
				(anchor circle)
			)
			(primitives
				(gr_poly
					(pts
						(arc
							(start -0.1778 -0.2794)
							(mid -0.249642 -0.249642)
							(end -0.2794 -0.1778)
						)
						(arc
							(start -0.2794 0.1778)
							(mid -0.249642 0.249642)
							(end -0.1778 0.2794)
						)
						(arc
							(start 0.1778 0.2794)
							(mid 0.249642 0.249642)
							(end 0.2794 0.1778)
						)
						(arc
							(start 0.2794 -0.1778)
							(mid 0.249642 -0.249642)
							(end 0.1778 -0.2794)
						)
					)
					(width 0)
					(fill yes)
				)
			)
		)
		(pad "2" smd custom
			(at 0 0.4445)
			(size 0.1397 0.1397)
			(layers "F.Cu" "F.Mask" "F.Paste")
			(net "SSD_PRSNT12")
			(options
				(clearance outline)
				(anchor circle)
			)
			(primitives
				(gr_poly
					(pts
						(arc
							(start -0.1778 -0.2794)
							(mid -0.249642 -0.249642)
							(end -0.2794 -0.1778)
						)
						(arc
							(start -0.2794 0.1778)
							(mid -0.249642 0.249642)
							(end -0.1778 0.2794)
						)
						(arc
							(start 0.1778 0.2794)
							(mid 0.249642 0.249642)
							(end 0.2794 0.1778)
						)
						(arc
							(start 0.2794 -0.1778)
							(mid 0.249642 -0.249642)
							(end 0.1778 -0.2794)
						)
					)
					(width 0)
					(fill yes)
				)
			)
		)
	)
	(gr_poly
		(pts
			(arc
				(start 0.999998 -488.391962)
				(mid 5.500116 -492.903779)
				(end 10.000234 -488.391962)
			)
			(xy 10.000234 -487.800142) (xy 7.500366 -487.800142)
			(arc
				(start 7.500366 -488.395772)
				(mid 5.500116 -490.404167)
				(end 3.499866 -488.395772)
			)
			(xy 3.499866 -487.800142) (xy 0.999998 -487.800142)
		)
		(stroke
			(width 0)
			(type solid)
		)
		(fill yes)
		(layer "F.Cu")
		(net "GND")
	)
	(gr_poly
		(pts
			(arc
				(start 3.999992 -71.491856)
				(mid 8.50011 -76.003673)
				(end 13.000228 -71.491856)
			)
			(xy 13.000228 -70.900036) (xy 10.50036 -70.900036)
			(arc
				(start 10.50036 -71.495666)
				(mid 8.50011 -73.504061)
				(end 6.49986 -71.495666)
			)
			(xy 6.49986 -70.900036) (xy 3.999992 -70.900036)
		)
		(stroke
			(width 0)
			(type solid)
		)
		(fill yes)
		(layer "F.Cu")
		(net "GND")
	)
	(gr_poly
		(pts
			(arc
				(start 29.499814 -4.49199)
				(mid 33.999932 -9.003807)
				(end 38.50005 -4.49199)
			)
			(xy 38.50005 -3.90017) (xy 36.000182 -3.90017)
			(arc
				(start 36.000182 -4.4958)
				(mid 33.999932 -6.504195)
				(end 31.999682 -4.4958)
			)
			(xy 31.999682 -3.90017) (xy 29.499814 -3.90017)
		)
		(stroke
			(width 0)
			(type solid)
		)
		(fill yes)
		(layer "F.Cu")
		(net "GND")
	)
	(gr_poly
		(pts
			(arc
				(start 65.499996 -483.489508)
				(mid 70.000114 -488.001325)
				(end 74.500232 -483.489508)
			)
			(xy 74.500232 -482.897688) (xy 72.000364 -482.897688)
			(arc
				(start 72.000364 -483.493318)
				(mid 70.000114 -485.501713)
				(end 67.999864 -483.493318)
			)
			(xy 67.999864 -482.897688) (xy 65.499996 -482.897688)
		)
		(stroke
			(width 0)
			(type solid)
		)
		(fill yes)
		(layer "F.Cu")
		(net "GND")
	)
	(gr_poly
		(pts
			(arc
				(start 65.499996 -276.489414)
				(mid 70.000114 -281.001231)
				(end 74.500232 -276.489414)
			)
			(xy 74.500232 -275.897594) (xy 72.000364 -275.897594)
			(arc
				(start 72.000364 -276.493224)
				(mid 70.000114 -278.501619)
				(end 67.999864 -276.493224)
			)
			(xy 67.999864 -275.897594) (xy 65.499996 -275.897594)
		)
		(stroke
			(width 0)
			(type solid)
		)
		(fill yes)
		(layer "F.Cu")
		(net "GND")
	)
	(gr_poly
		(pts
			(arc
				(start 65.499996 -173.989492)
				(mid 70.000114 -178.501309)
				(end 74.500232 -173.989492)
			)
			(xy 74.500232 -173.397672) (xy 72.000364 -173.397672)
			(arc
				(start 72.000364 -173.993302)
				(mid 70.000114 -176.001697)
				(end 67.999864 -173.993302)
			)
			(xy 67.999864 -173.397672) (xy 65.499996 -173.397672)
		)
		(stroke
			(width 0)
			(type solid)
		)
		(fill yes)
		(layer "F.Cu")
		(net "GND")
	)
	(gr_poly
		(pts
			(arc
				(start 65.499996 -70.991984)
				(mid 70.000114 -75.503801)
				(end 74.500232 -70.991984)
			)
			(xy 74.500232 -70.400164) (xy 72.000364 -70.400164)
			(arc
				(start 72.000364 -70.995794)
				(mid 70.000114 -73.004189)
				(end 67.999864 -70.995794)
			)
			(xy 67.999864 -70.400164) (xy 65.499996 -70.400164)
		)
		(stroke
			(width 0)
			(type solid)
		)
		(fill yes)
		(layer "F.Cu")
		(net "GND")
	)
	(gr_poly
		(pts
			(arc
				(start 248.999756 -483.489508)
				(mid 253.499874 -488.001325)
				(end 257.999992 -483.489508)
			)
			(xy 257.999992 -482.897688) (xy 255.500124 -482.897688)
			(arc
				(start 255.500124 -483.493318)
				(mid 253.499874 -485.501713)
				(end 251.499624 -483.493318)
			)
			(xy 251.499624 -482.897688) (xy 248.999756 -482.897688)
		)
		(stroke
			(width 0)
			(type solid)
		)
		(fill yes)
		(layer "F.Cu")
		(net "GND")
	)
	(gr_poly
		(pts
			(arc
				(start 248.999756 -274.98929)
				(mid 253.499874 -279.501107)
				(end 257.999992 -274.98929)
			)
			(xy 257.999992 -274.39747) (xy 255.500124 -274.39747)
			(arc
				(start 255.500124 -274.9931)
				(mid 253.499874 -277.001495)
				(end 251.499624 -274.9931)
			)
			(xy 251.499624 -274.39747) (xy 248.999756 -274.39747)
		)
		(stroke
			(width 0)
			(type solid)
		)
		(fill yes)
		(layer "F.Cu")
		(net "GND")
	)
	(gr_poly
		(pts
			(arc
				(start 248.999756 -174.489364)
				(mid 253.499874 -179.001181)
				(end 257.999992 -174.489364)
			)
			(xy 257.999992 -173.897544) (xy 255.500124 -173.897544)
			(arc
				(start 255.500124 -174.493174)
				(mid 253.499874 -176.501569)
				(end 251.499624 -174.493174)
			)
			(xy 251.499624 -173.897544) (xy 248.999756 -173.897544)
		)
		(stroke
			(width 0)
			(type solid)
		)
		(fill yes)
		(layer "F.Cu")
		(net "GND")
	)
	(gr_poly
		(pts
			(arc
				(start 248.999756 -41.489376)
				(mid 253.499874 -46.001193)
				(end 257.999992 -41.489376)
			)
			(xy 257.999992 -40.897556) (xy 255.500124 -40.897556)
			(arc
				(start 255.500124 -41.493186)
				(mid 253.499874 -43.501581)
				(end 251.499624 -41.493186)
			)
			(xy 251.499624 -40.897556) (xy 248.999756 -40.897556)
		)
		(stroke
			(width 0)
			(type solid)
		)
		(fill yes)
		(layer "F.Cu")
		(net "GND")
	)
	(gr_line
		(start 2.249932 -456.741784)
		(end 3.70459 -456.741784)
		(stroke
			(width 0.085598)
			(type default)
		)
		(layer "F.Cu")
	)
	(gr_line
		(start 2.249932 -455.941938)
		(end 3.690366 -455.941938)
		(stroke
			(width 0.085598)
			(type default)
		)
		(layer "F.Cu")
	)
	(gr_line
		(start 2.249932 -454.341992)
		(end 3.657092 -454.341992)
		(stroke
			(width 0.085598)
			(type default)
		)
		(layer "F.Cu")
	)
	(gr_line
		(start 2.249932 -453.541892)
		(end 3.657092 -453.541892)
		(stroke
			(width 0.085598)
			(type default)
		)
		(layer "F.Cu")
	)
	(gr_line
		(start 2.249932 -451.941946)
		(end 3.657092 -451.941946)
		(stroke
			(width 0.085598)
			(type default)
		)
		(layer "F.Cu")
	)
	(gr_line
		(start 2.249932 -451.141846)
		(end 3.604514 -451.141846)
		(stroke
			(width 0.085598)
			(type default)
		)
		(layer "F.Cu")
	)
	(gr_line
		(start 2.249932 -449.5419)
		(end 3.658108 -449.5419)
		(stroke
			(width 0.087376)
			(type default)
		)
		(layer "F.Cu")
	)
	(gr_line
		(start 2.249932 -448.7418)
		(end 3.657854 -448.7418)
		(stroke
			(width 0.087376)
			(type default)
		)
		(layer "F.Cu")
	)
	(gr_line
		(start 2.249932 -447.141854)
		(end 3.657854 -447.141854)
		(stroke
			(width 0.087376)
			(type default)
		)
		(layer "F.Cu")
	)
	(gr_line
		(start 2.249932 -446.342008)
		(end 3.657854 -446.342008)
		(stroke
			(width 0.087376)
			(type default)
		)
		(layer "F.Cu")
	)
	(gr_line
		(start 2.249932 -443.941962)
		(end 3.658108 -443.941962)
		(stroke
			(width 0.087376)
			(type default)
		)
		(layer "F.Cu")
	)
	(gr_line
		(start 2.249932 -443.141862)
		(end 3.657854 -443.141862)
		(stroke
			(width 0.087376)
			(type default)
		)
		(layer "F.Cu")
	)
	(gr_line
		(start 2.249932 -440.741816)
		(end 3.657854 -440.741816)
		(stroke
			(width 0.087376)
			(type default)
		)
		(layer "F.Cu")
	)
	(gr_line
		(start 2.249932 -439.94197)
		(end 3.657854 -439.94197)
		(stroke
			(width 0.087376)
			(type default)
		)
		(layer "F.Cu")
	)
	(gr_line
		(start 2.249932 -437.541924)
		(end 3.658108 -437.541924)
		(stroke
			(width 0.087376)
			(type default)
		)
		(layer "F.Cu")
	)
	(gr_line
		(start 2.249932 -436.741824)
		(end 3.570224 -436.741824)
		(stroke
			(width 0.087376)
			(type default)
		)
		(layer "F.Cu")
	)
	(gr_line
		(start 2.249932 -431.941986)
		(end 3.658108 -431.941986)
		(stroke
			(width 0.087376)
			(type default)
		)
		(layer "F.Cu")
	)
	(gr_line
		(start 2.249932 -431.141886)
		(end 3.657854 -431.141886)
		(stroke
			(width 0.087376)
			(type default)
		)
		(layer "F.Cu")
	)
	(gr_line
		(start 2.249932 -428.74184)
		(end 3.657854 -428.74184)
		(stroke
			(width 0.087376)
			(type default)
		)
		(layer "F.Cu")
	)
	(gr_line
		(start 2.249932 -427.941994)
		(end 3.657854 -427.941994)
		(stroke
			(width 0.087376)
			(type default)
		)
		(layer "F.Cu")
	)
	(gr_line
		(start 2.249932 -425.541948)
		(end 3.658108 -425.541948)
		(stroke
			(width 0.087376)
			(type default)
		)
		(layer "F.Cu")
	)
	(gr_line
		(start 2.249932 -424.741848)
		(end 3.657854 -424.741848)
		(stroke
			(width 0.087376)
			(type default)
		)
		(layer "F.Cu")
	)
	(gr_line
		(start 2.249932 -415.942018)
		(end 3.657854 -415.942018)
		(stroke
			(width 0.087376)
			(type default)
		)
		(layer "F.Cu")
	)
	(gr_line
		(start 2.249932 -415.141918)
		(end 3.658108 -415.141918)
		(stroke
			(width 0.087376)
			(type default)
		)
		(layer "F.Cu")
	)
	(gr_line
		(start 2.249932 -412.741872)
		(end 3.657854 -412.741872)
		(stroke
			(width 0.087376)
			(type default)
		)
		(layer "F.Cu")
	)
	(gr_line
		(start 2.249932 -411.941772)
		(end 3.658108 -411.941772)
		(stroke
			(width 0.087376)
			(type default)
		)
		(layer "F.Cu")
	)
	(gr_line
		(start 2.249932 -409.54198)
		(end 3.657854 -409.54198)
		(stroke
			(width 0.087376)
			(type default)
		)
		(layer "F.Cu")
	)
	(gr_line
		(start 2.249932 -408.74188)
		(end 3.658108 -408.74188)
		(stroke
			(width 0.087376)
			(type default)
		)
		(layer "F.Cu")
	)
	(gr_line
		(start 2.249932 -406.341834)
		(end 3.657854 -406.341834)
		(stroke
			(width 0.087376)
			(type default)
		)
		(layer "F.Cu")
	)
	(gr_line
		(start 2.249932 -405.541988)
		(end 3.657854 -405.541988)
		(stroke
			(width 0.087376)
			(type default)
		)
		(layer "F.Cu")
	)
	(gr_line
		(start 2.249932 -403.141942)
		(end 3.657854 -403.141942)
		(stroke
			(width 0.087376)
			(type default)
		)
		(layer "F.Cu")
	)
	(gr_line
		(start 2.249932 -402.341842)
		(end 3.658108 -402.341842)
		(stroke
			(width 0.087376)
			(type default)
		)
		(layer "F.Cu")
	)
	(gr_line
		(start 2.249932 -397.542004)
		(end 3.657854 -397.542004)
		(stroke
			(width 0.087376)
			(type default)
		)
		(layer "F.Cu")
	)
	(gr_line
		(start 2.249932 -396.741904)
		(end 3.658108 -396.741904)
		(stroke
			(width 0.087376)
			(type default)
		)
		(layer "F.Cu")
	)
	(gr_line
		(start 2.249932 -394.341858)
		(end 3.657854 -394.341858)
		(stroke
			(width 0.087376)
			(type default)
		)
		(layer "F.Cu")
	)
	(gr_line
		(start 2.249932 -393.542012)
		(end 3.657854 -393.542012)
		(stroke
			(width 0.087376)
			(type default)
		)
		(layer "F.Cu")
	)
	(gr_line
		(start 2.249932 -391.141966)
		(end 3.657854 -391.141966)
		(stroke
			(width 0.087376)
			(type default)
		)
		(layer "F.Cu")
	)
	(gr_line
		(start 2.249932 -390.341866)
		(end 3.658108 -390.341866)
		(stroke
			(width 0.087376)
			(type default)
		)
		(layer "F.Cu")
	)
	(gr_line
		(start 2.249932 -387.94182)
		(end 3.657854 -387.94182)
		(stroke
			(width 0.087376)
			(type default)
		)
		(layer "F.Cu")
	)
	(gr_line
		(start 2.249932 -387.141974)
		(end 3.657854 -387.141974)
		(stroke
			(width 0.087376)
			(type default)
		)
		(layer "F.Cu")
	)
	(gr_line
		(start 2.249932 -385.541774)
		(end 3.657854 -385.541774)
		(stroke
			(width 0.087376)
			(type default)
		)
		(layer "F.Cu")
	)
	(gr_line
		(start 2.249932 -384.741928)
		(end 3.657854 -384.741928)
		(stroke
			(width 0.087376)
			(type default)
		)
		(layer "F.Cu")
	)
	(gr_line
		(start 2.249932 -357.142034)
		(end 3.657854 -357.142034)
		(stroke
			(width 0.087376)
			(type default)
		)
		(layer "F.Cu")
	)
	(gr_line
		(start 2.249932 -356.342188)
		(end 3.657854 -356.342188)
		(stroke
			(width 0.087376)
			(type default)
		)
		(layer "F.Cu")
	)
	(gr_line
		(start 2.249932 -353.942142)
		(end 3.657854 -353.942142)
		(stroke
			(width 0.087376)
			(type default)
		)
		(layer "F.Cu")
	)
	(gr_line
		(start 2.249932 -353.142042)
		(end 3.658108 -353.142042)
		(stroke
			(width 0.087376)
			(type default)
		)
		(layer "F.Cu")
	)
	(gr_line
		(start 2.249932 -350.741996)
		(end 3.657854 -350.741996)
		(stroke
			(width 0.087376)
			(type default)
		)
		(layer "F.Cu")
	)
	(gr_line
		(start 2.249932 -349.94215)
		(end 3.658362 -349.94215)
		(stroke
			(width 0.087376)
			(type default)
		)
		(layer "F.Cu")
	)
	(gr_line
		(start 2.249932 -347.542104)
		(end 3.657854 -347.542104)
		(stroke
			(width 0.087376)
			(type default)
		)
		(layer "F.Cu")
	)
	(gr_line
		(start 2.249932 -346.742004)
		(end 3.658108 -346.742004)
		(stroke
			(width 0.087376)
			(type default)
		)
		(layer "F.Cu")
	)
	(gr_line
		(start 2.249932 -344.342212)
		(end 3.6576 -344.342212)
		(stroke
			(width 0.087376)
			(type default)
		)
		(layer "F.Cu")
	)
	(gr_line
		(start 2.249932 -343.542112)
		(end 3.657854 -343.542112)
		(stroke
			(width 0.087376)
			(type default)
		)
		(layer "F.Cu")
	)
	(gr_line
		(start 2.249932 -341.142066)
		(end 3.657854 -341.142066)
		(stroke
			(width 0.087376)
			(type default)
		)
		(layer "F.Cu")
	)
	(gr_line
		(start 2.249932 -340.34222)
		(end 3.657854 -340.34222)
		(stroke
			(width 0.087376)
			(type default)
		)
		(layer "F.Cu")
	)
	(gr_line
		(start 2.249932 -337.942174)
		(end 3.6576 -337.942174)
		(stroke
			(width 0.087376)
			(type default)
		)
		(layer "F.Cu")
	)
	(gr_line
		(start 2.249932 -337.142074)
		(end 3.657854 -337.142074)
		(stroke
			(width 0.087376)
			(type default)
		)
		(layer "F.Cu")
	)
	(gr_line
		(start 2.249932 -334.742028)
		(end 3.657854 -334.742028)
		(stroke
			(width 0.087376)
			(type default)
		)
		(layer "F.Cu")
	)
	(gr_line
		(start 2.249932 -333.942182)
		(end 3.657854 -333.942182)
		(stroke
			(width 0.087376)
			(type default)
		)
		(layer "F.Cu")
	)
	(gr_line
		(start 2.249932 -329.14209)
		(end 3.657854 -329.14209)
		(stroke
			(width 0.087376)
			(type default)
		)
		(layer "F.Cu")
	)
	(gr_line
		(start 2.249932 -328.34199)
		(end 3.658108 -328.34199)
		(stroke
			(width 0.087376)
			(type default)
		)
		(layer "F.Cu")
	)
	(gr_line
		(start 2.249932 -325.942198)
		(end 3.657854 -325.942198)
		(stroke
			(width 0.087376)
			(type default)
		)
		(layer "F.Cu")
	)
	(gr_line
		(start 2.249932 -325.142098)
		(end 3.658108 -325.142098)
		(stroke
			(width 0.087376)
			(type default)
		)
		(layer "F.Cu")
	)
	(gr_line
		(start 2.249932 -322.742052)
		(end 3.657854 -322.742052)
		(stroke
			(width 0.087376)
			(type default)
		)
		(layer "F.Cu")
	)
	(gr_line
		(start 2.249932 -321.942206)
		(end 3.658362 -321.942206)
		(stroke
			(width 0.087376)
			(type default)
		)
		(layer "F.Cu")
	)
	(gr_line
		(start 2.249932 -319.54216)
		(end 3.657854 -319.54216)
		(stroke
			(width 0.087376)
			(type default)
		)
		(layer "F.Cu")
	)
	(gr_line
		(start 2.249932 -318.74206)
		(end 3.658108 -318.74206)
		(stroke
			(width 0.087376)
			(type default)
		)
		(layer "F.Cu")
	)
	(gr_line
		(start 2.249932 -311.542176)
		(end 3.657854 -311.542176)
		(stroke
			(width 0.087376)
			(type default)
		)
		(layer "F.Cu")
	)
	(gr_line
		(start 2.249932 -310.742076)
		(end 3.658108 -310.742076)
		(stroke
			(width 0.087376)
			(type default)
		)
		(layer "F.Cu")
	)
	(gr_line
		(start 2.249932 -308.34203)
		(end 3.657854 -308.34203)
		(stroke
			(width 0.087376)
			(type default)
		)
		(layer "F.Cu")
	)
	(gr_line
		(start 2.249932 -307.542184)
		(end 3.658362 -307.542184)
		(stroke
			(width 0.087376)
			(type default)
		)
		(layer "F.Cu")
	)
	(gr_line
		(start 2.249932 -305.142138)
		(end 3.657854 -305.142138)
		(stroke
			(width 0.087376)
			(type default)
		)
		(layer "F.Cu")
	)
	(gr_line
		(start 2.249932 -304.342038)
		(end 3.658108 -304.342038)
		(stroke
			(width 0.087376)
			(type default)
		)
		(layer "F.Cu")
	)
	(gr_line
		(start 2.249932 -301.941992)
		(end 3.657854 -301.941992)
		(stroke
			(width 0.087376)
			(type default)
		)
		(layer "F.Cu")
	)
	(gr_line
		(start 2.249932 -301.142146)
		(end 3.658362 -301.142146)
		(stroke
			(width 0.087376)
			(type default)
		)
		(layer "F.Cu")
	)
	(gr_line
		(start 2.249932 -298.7421)
		(end 3.657854 -298.7421)
		(stroke
			(width 0.087376)
			(type default)
		)
		(layer "F.Cu")
	)
	(gr_line
		(start 2.249932 -297.942)
		(end 3.658108 -297.942)
		(stroke
			(width 0.087376)
			(type default)
		)
		(layer "F.Cu")
	)
	(gr_line
		(start 2.249932 -295.542208)
		(end 3.657854 -295.542208)
		(stroke
			(width 0.087376)
			(type default)
		)
		(layer "F.Cu")
	)
	(gr_line
		(start 2.249932 -294.742108)
		(end 3.658108 -294.742108)
		(stroke
			(width 0.087376)
			(type default)
		)
		(layer "F.Cu")
	)
	(gr_line
		(start 2.249932 -292.342062)
		(end 3.657854 -292.342062)
		(stroke
			(width 0.087376)
			(type default)
		)
		(layer "F.Cu")
	)
	(gr_line
		(start 2.249932 -291.542216)
		(end 3.658362 -291.542216)
		(stroke
			(width 0.087376)
			(type default)
		)
		(layer "F.Cu")
	)
	(gr_line
		(start 2.249932 -289.14217)
		(end 3.657854 -289.14217)
		(stroke
			(width 0.087376)
			(type default)
		)
		(layer "F.Cu")
	)
	(gr_line
		(start 2.249932 -288.34207)
		(end 3.658108 -288.34207)
		(stroke
			(width 0.087376)
			(type default)
		)
		(layer "F.Cu")
	)
	(gr_line
		(start 2.249932 -282.742132)
		(end 3.6576 -282.742132)
		(stroke
			(width 0.087376)
			(type default)
		)
		(layer "F.Cu")
	)
	(gr_line
		(start 2.249932 -281.942032)
		(end 3.657854 -281.942032)
		(stroke
			(width 0.087376)
			(type default)
		)
		(layer "F.Cu")
	)
	(gr_line
		(start 2.249932 -279.541986)
		(end 3.657854 -279.541986)
		(stroke
			(width 0.087376)
			(type default)
		)
		(layer "F.Cu")
	)
	(gr_line
		(start 2.249932 -278.74214)
		(end 3.58394 -278.74214)
		(stroke
			(width 0.087376)
			(type default)
		)
		(layer "F.Cu")
	)
	(gr_line
		(start 2.249932 -231.142032)
		(end 3.657854 -231.142032)
		(stroke
			(width 0.087376)
			(type default)
		)
		(layer "F.Cu")
	)
	(gr_line
		(start 2.249932 -230.342186)
		(end 3.658362 -230.342186)
		(stroke
			(width 0.087376)
			(type default)
		)
		(layer "F.Cu")
	)
	(gr_line
		(start 2.249932 -227.94214)
		(end 3.657854 -227.94214)
		(stroke
			(width 0.087376)
			(type default)
		)
		(layer "F.Cu")
	)
	(gr_line
		(start 2.249932 -227.14204)
		(end 3.658108 -227.14204)
		(stroke
			(width 0.087376)
			(type default)
		)
		(layer "F.Cu")
	)
	(gr_line
		(start 2.249932 -224.741994)
		(end 3.619754 -224.741994)
		(stroke
			(width 0.087376)
			(type default)
		)
		(layer "F.Cu")
	)
	(gr_line
		(start 2.249932 -223.942148)
		(end 3.696462 -223.942148)
		(stroke
			(width 0.087376)
			(type default)
		)
		(layer "F.Cu")
	)
	(gr_line
		(start 2.249932 -221.542102)
		(end 3.607054 -221.542102)
		(stroke
			(width 0.087376)
			(type default)
		)
		(layer "F.Cu")
	)
	(gr_line
		(start 2.249932 -220.742002)
		(end 3.708908 -220.742002)
		(stroke
			(width 0.087376)
			(type default)
		)
		(layer "F.Cu")
	)
	(gr_line
		(start 2.249932 -218.34221)
		(end 3.607054 -218.34221)
		(stroke
			(width 0.087376)
			(type default)
		)
		(layer "F.Cu")
	)
	(gr_line
		(start 2.249932 -217.54211)
		(end 3.708908 -217.54211)
		(stroke
			(width 0.087376)
			(type default)
		)
		(layer "F.Cu")
	)
	(gr_line
		(start 2.249932 -215.142064)
		(end 3.607054 -215.142064)
		(stroke
			(width 0.087376)
			(type default)
		)
		(layer "F.Cu")
	)
	(gr_line
		(start 2.249932 -214.342218)
		(end 3.709162 -214.342218)
		(stroke
			(width 0.087376)
			(type default)
		)
		(layer "F.Cu")
	)
	(gr_line
		(start 2.249932 -211.942172)
		(end 3.657854 -211.942172)
		(stroke
			(width 0.087376)
			(type default)
		)
		(layer "F.Cu")
	)
	(gr_line
		(start 2.249932 -211.142072)
		(end 3.658108 -211.142072)
		(stroke
			(width 0.087376)
			(type default)
		)
		(layer "F.Cu")
	)
	(gr_line
		(start 2.249932 -208.742026)
		(end 3.657854 -208.742026)
		(stroke
			(width 0.087376)
			(type default)
		)
		(layer "F.Cu")
	)
	(gr_line
		(start 2.249932 -207.94218)
		(end 3.658362 -207.94218)
		(stroke
			(width 0.087376)
			(type default)
		)
		(layer "F.Cu")
	)
	(gr_line
		(start 2.249932 -205.542134)
		(end 3.657854 -205.542134)
		(stroke
			(width 0.087376)
			(type default)
		)
		(layer "F.Cu")
	)
	(gr_line
		(start 2.249932 -204.742034)
		(end 3.658108 -204.742034)
		(stroke
			(width 0.087376)
			(type default)
		)
		(layer "F.Cu")
	)
	(gr_line
		(start 2.249932 -202.341988)
		(end 3.657854 -202.341988)
		(stroke
			(width 0.087376)
			(type default)
		)
		(layer "F.Cu")
	)
	(gr_line
		(start 2.249932 -201.542142)
		(end 3.658362 -201.542142)
		(stroke
			(width 0.087376)
			(type default)
		)
		(layer "F.Cu")
	)
	(gr_line
		(start 2.249932 -196.74205)
		(end 3.657854 -196.74205)
		(stroke
			(width 0.087376)
			(type default)
		)
		(layer "F.Cu")
	)
	(gr_line
		(start 2.249932 -195.942204)
		(end 3.658362 -195.942204)
		(stroke
			(width 0.087376)
			(type default)
		)
		(layer "F.Cu")
	)
	(gr_line
		(start 2.249932 -193.542158)
		(end 3.657854 -193.542158)
		(stroke
			(width 0.087376)
			(type default)
		)
		(layer "F.Cu")
	)
	(gr_line
		(start 2.249932 -192.742058)
		(end 3.658108 -192.742058)
		(stroke
			(width 0.087376)
			(type default)
		)
		(layer "F.Cu")
	)
	(gr_line
		(start 2.249932 -185.542174)
		(end 3.657854 -185.542174)
		(stroke
			(width 0.087376)
			(type default)
		)
		(layer "F.Cu")
	)
	(gr_line
		(start 2.249932 -184.742074)
		(end 3.658108 -184.742074)
		(stroke
			(width 0.087376)
			(type default)
		)
		(layer "F.Cu")
	)
	(gr_line
		(start 2.249932 -182.342028)
		(end 3.657854 -182.342028)
		(stroke
			(width 0.087376)
			(type default)
		)
		(layer "F.Cu")
	)
	(gr_line
		(start 2.249932 -181.542182)
		(end 3.658362 -181.542182)
		(stroke
			(width 0.087376)
			(type default)
		)
		(layer "F.Cu")
	)
	(gr_line
		(start 2.249932 -179.142136)
		(end 3.6576 -179.142136)
		(stroke
			(width 0.087376)
			(type default)
		)
		(layer "F.Cu")
	)
	(gr_line
		(start 2.249932 -178.342036)
		(end 3.657854 -178.342036)
		(stroke
			(width 0.087376)
			(type default)
		)
		(layer "F.Cu")
	)
	(gr_line
		(start 2.249932 -175.94199)
		(end 3.657854 -175.94199)
		(stroke
			(width 0.087376)
			(type default)
		)
		(layer "F.Cu")
	)
	(gr_line
		(start 2.249932 -175.142144)
		(end 3.657854 -175.142144)
		(stroke
			(width 0.087376)
			(type default)
		)
		(layer "F.Cu")
	)
	(gr_line
		(start 2.249932 -172.742098)
		(end 3.6576 -172.742098)
		(stroke
			(width 0.087376)
			(type default)
		)
		(layer "F.Cu")
	)
	(gr_line
		(start 2.249932 -171.941998)
		(end 3.657854 -171.941998)
		(stroke
			(width 0.087376)
			(type default)
		)
		(layer "F.Cu")
	)
	(gr_line
		(start 2.249932 -169.542206)
		(end 3.6576 -169.542206)
		(stroke
			(width 0.087376)
			(type default)
		)
		(layer "F.Cu")
	)
	(gr_line
		(start 2.249932 -168.742106)
		(end 3.657854 -168.742106)
		(stroke
			(width 0.087376)
			(type default)
		)
		(layer "F.Cu")
	)
	(gr_line
		(start 2.249932 -163.142168)
		(end 3.6576 -163.142168)
		(stroke
			(width 0.087376)
			(type default)
		)
		(layer "F.Cu")
	)
	(gr_line
		(start 2.249932 -162.342068)
		(end 3.657854 -162.342068)
		(stroke
			(width 0.087376)
			(type default)
		)
		(layer "F.Cu")
	)
	(gr_line
		(start 2.249932 -159.942022)
		(end 3.657854 -159.942022)
		(stroke
			(width 0.087376)
			(type default)
		)
		(layer "F.Cu")
	)
	(gr_line
		(start 2.249932 -159.142176)
		(end 3.657854 -159.142176)
		(stroke
			(width 0.087376)
			(type default)
		)
		(layer "F.Cu")
	)
	(gr_line
		(start 2.249932 -156.74213)
		(end 3.695954 -156.74213)
		(stroke
			(width 0.087376)
			(type default)
		)
		(layer "F.Cu")
	)
	(gr_line
		(start 2.249932 -155.94203)
		(end 3.620008 -155.94203)
		(stroke
			(width 0.087376)
			(type default)
		)
		(layer "F.Cu")
	)
	(gr_line
		(start 2.249932 -153.541984)
		(end 3.657854 -153.541984)
		(stroke
			(width 0.087376)
			(type default)
		)
		(layer "F.Cu")
	)
	(gr_line
		(start 2.249932 -152.742138)
		(end 3.657854 -152.742138)
		(stroke
			(width 0.087376)
			(type default)
		)
		(layer "F.Cu")
	)
	(gr_line
		(start 3.570224 -436.741824)
		(end 3.796792 -436.968392)
		(stroke
			(width 0.087376)
			(type default)
		)
		(layer "F.Cu")
	)
	(gr_line
		(start 3.58394 -278.74214)
		(end 3.803396 -278.961596)
		(stroke
			(width 0.087376)
			(type default)
		)
		(layer "F.Cu")
	)
	(gr_line
		(start 3.604514 -451.141846)
		(end 3.638296 -451.175628)
		(stroke
			(width 0.085598)
			(type default)
		)
		(layer "F.Cu")
	)
	(gr_line
		(start 3.607054 -221.542102)
		(end 3.84048 -221.308676)
		(stroke
			(width 0.087376)
			(type default)
		)
		(layer "F.Cu")
	)
	(gr_line
		(start 3.607054 -218.34221)
		(end 3.84048 -218.108784)
		(stroke
			(width 0.087376)
			(type default)
		)
		(layer "F.Cu")
	)
	(gr_line
		(start 3.607054 -215.142064)
		(end 3.84048 -214.908638)
		(stroke
			(width 0.087376)
			(type default)
		)
		(layer "F.Cu")
	)
	(gr_line
		(start 3.619754 -224.741994)
		(end 3.84048 -224.521268)
		(stroke
			(width 0.087376)
			(type default)
		)
		(layer "F.Cu")
	)
	(gr_line
		(start 3.620008 -155.94203)
		(end 3.84048 -156.162502)
		(stroke
			(width 0.087376)
			(type default)
		)
		(layer "F.Cu")
	)
	(gr_line
		(start 3.657092 -454.341992)
		(end 3.664712 -454.334372)
		(stroke
			(width 0.085598)
			(type default)
		)
		(layer "F.Cu")
	)
	(gr_line
		(start 3.657092 -453.541892)
		(end 3.664712 -453.549512)
		(stroke
			(width 0.085598)
			(type default)
		)
		(layer "F.Cu")
	)
	(gr_line
		(start 3.6576 -344.342212)
		(end 3.840226 -344.159586)
		(stroke
			(width 0.087376)
			(type default)
		)
		(layer "F.Cu")
	)
	(gr_line
		(start 3.6576 -337.942174)
		(end 3.840226 -337.759548)
		(stroke
			(width 0.087376)
			(type default)
		)
		(layer "F.Cu")
	)
	(gr_line
		(start 3.6576 -282.742132)
		(end 3.840226 -282.559506)
		(stroke
			(width 0.087376)
			(type default)
		)
		(layer "F.Cu")
	)
	(gr_line
		(start 3.6576 -179.142136)
		(end 3.840226 -178.95951)
		(stroke
			(width 0.087376)
			(type default)
		)
		(layer "F.Cu")
	)
	(gr_line
		(start 3.6576 -172.742098)
		(end 3.840226 -172.559472)
		(stroke
			(width 0.087376)
			(type default)
		)
		(layer "F.Cu")
	)
	(gr_line
		(start 3.6576 -169.542206)
		(end 3.840226 -169.35958)
		(stroke
			(width 0.087376)
			(type default)
		)
		(layer "F.Cu")
	)
	(gr_line
		(start 3.6576 -163.142168)
		(end 3.840226 -162.959542)
		(stroke
			(width 0.087376)
			(type default)
		)
		(layer "F.Cu")
	)
	(gr_line
		(start 3.657854 -448.7418)
		(end 3.84048 -448.924426)
		(stroke
			(width 0.087376)
			(type default)
		)
		(layer "F.Cu")
	)
	(gr_line
		(start 3.657854 -447.141854)
		(end 3.840226 -446.959482)
		(stroke
			(width 0.087376)
			(type default)
		)
		(layer "F.Cu")
	)
	(gr_line
		(start 3.657854 -446.342008)
		(end 3.840226 -446.52438)
		(stroke
			(width 0.087376)
			(type default)
		)
		(layer "F.Cu")
	)
	(gr_line
		(start 3.657854 -443.141862)
		(end 3.84048 -443.324488)
		(stroke
			(width 0.087376)
			(type default)
		)
		(layer "F.Cu")
	)
	(gr_line
		(start 3.657854 -440.741816)
		(end 3.840226 -440.559444)
		(stroke
			(width 0.087376)
			(type default)
		)
		(layer "F.Cu")
	)
	(gr_line
		(start 3.657854 -439.94197)
		(end 3.840226 -440.124342)
		(stroke
			(width 0.087376)
			(type default)
		)
		(layer "F.Cu")
	)
	(gr_line
		(start 3.657854 -431.141886)
		(end 3.84048 -431.324512)
		(stroke
			(width 0.087376)
			(type default)
		)
		(layer "F.Cu")
	)
	(gr_line
		(start 3.657854 -428.74184)
		(end 3.840226 -428.559468)
		(stroke
			(width 0.087376)
			(type default)
		)
		(layer "F.Cu")
	)
	(gr_line
		(start 3.657854 -427.941994)
		(end 3.840226 -428.124366)
		(stroke
			(width 0.087376)
			(type default)
		)
		(layer "F.Cu")
	)
	(gr_line
		(start 3.657854 -424.741848)
		(end 3.84048 -424.924474)
		(stroke
			(width 0.087376)
			(type default)
		)
		(layer "F.Cu")
	)
	(gr_line
		(start 3.657854 -415.942018)
		(end 3.84048 -415.759392)
		(stroke
			(width 0.087376)
			(type default)
		)
		(layer "F.Cu")
	)
	(gr_line
		(start 3.657854 -412.741872)
		(end 3.84048 -412.559246)
		(stroke
			(width 0.087376)
			(type default)
		)
		(layer "F.Cu")
	)
	(gr_line
		(start 3.657854 -409.54198)
		(end 3.84048 -409.359354)
		(stroke
			(width 0.087376)
			(type default)
		)
		(layer "F.Cu")
	)
	(gr_line
		(start 3.657854 -406.341834)
		(end 3.840226 -406.159462)
		(stroke
			(width 0.087376)
			(type default)
		)
		(layer "F.Cu")
	)
	(gr_line
		(start 3.657854 -405.541988)
		(end 3.840226 -405.72436)
		(stroke
			(width 0.087376)
			(type default)
		)
		(layer "F.Cu")
	)
	(gr_line
		(start 3.657854 -403.141942)
		(end 3.84048 -402.959316)
		(stroke
			(width 0.087376)
			(type default)
		)
		(layer "F.Cu")
	)
	(gr_line
		(start 3.657854 -397.542004)
		(end 3.84048 -397.359378)
		(stroke
			(width 0.087376)
			(type default)
		)
		(layer "F.Cu")
	)
	(gr_line
		(start 3.657854 -394.341858)
		(end 3.840226 -394.159486)
		(stroke
			(width 0.087376)
			(type default)
		)
		(layer "F.Cu")
	)
	(gr_line
		(start 3.657854 -393.542012)
		(end 3.840226 -393.724384)
		(stroke
			(width 0.087376)
			(type default)
		)
		(layer "F.Cu")
	)
	(gr_line
		(start 3.657854 -391.141966)
		(end 3.84048 -390.95934)
		(stroke
			(width 0.087376)
			(type default)
		)
		(layer "F.Cu")
	)
	(gr_line
		(start 3.657854 -387.94182)
		(end 3.840226 -387.759448)
		(stroke
			(width 0.087376)
			(type default)
		)
		(layer "F.Cu")
	)
	(gr_line
		(start 3.657854 -387.141974)
		(end 3.840226 -387.324346)
		(stroke
			(width 0.087376)
			(type default)
		)
		(layer "F.Cu")
	)
	(gr_line
		(start 3.657854 -385.541774)
		(end 3.840226 -385.359402)
		(stroke
			(width 0.087376)
			(type default)
		)
		(layer "F.Cu")
	)
	(gr_line
		(start 3.657854 -384.741928)
		(end 3.840226 -384.9243)
		(stroke
			(width 0.087376)
			(type default)
		)
		(layer "F.Cu")
	)
	(gr_line
		(start 3.657854 -357.142034)
		(end 3.840226 -356.959662)
		(stroke
			(width 0.087376)
			(type default)
		)
		(layer "F.Cu")
	)
	(gr_line
		(start 3.657854 -356.342188)
		(end 3.840226 -356.52456)
		(stroke
			(width 0.087376)
			(type default)
		)
		(layer "F.Cu")
	)
	(gr_line
		(start 3.657854 -353.942142)
		(end 3.84048 -353.759516)
		(stroke
			(width 0.087376)
			(type default)
		)
		(layer "F.Cu")
	)
	(gr_line
		(start 3.657854 -350.741996)
		(end 3.84048 -350.55937)
		(stroke
			(width 0.087376)
			(type default)
		)
		(layer "F.Cu")
	)
	(gr_line
		(start 3.657854 -347.542104)
		(end 3.84048 -347.359478)
		(stroke
			(width 0.087376)
			(type default)
		)
		(layer "F.Cu")
	)
	(gr_line
		(start 3.657854 -343.542112)
		(end 3.840226 -343.724484)
		(stroke
			(width 0.087376)
			(type default)
		)
		(layer "F.Cu")
	)
	(gr_line
		(start 3.657854 -341.142066)
		(end 3.840226 -340.959694)
		(stroke
			(width 0.087376)
			(type default)
		)
		(layer "F.Cu")
	)
	(gr_line
		(start 3.657854 -340.34222)
		(end 3.840226 -340.524592)
		(stroke
			(width 0.087376)
			(type default)
		)
		(layer "F.Cu")
	)
	(gr_line
		(start 3.657854 -337.142074)
		(end 3.840226 -337.324446)
		(stroke
			(width 0.087376)
			(type default)
		)
		(layer "F.Cu")
	)
	(gr_line
		(start 3.657854 -334.742028)
		(end 3.840226 -334.559656)
		(stroke
			(width 0.087376)
			(type default)
		)
		(layer "F.Cu")
	)
	(gr_line
		(start 3.657854 -333.942182)
		(end 3.840226 -334.124554)
		(stroke
			(width 0.087376)
			(type default)
		)
		(layer "F.Cu")
	)
	(gr_line
		(start 3.657854 -329.14209)
		(end 3.84048 -328.959464)
		(stroke
			(width 0.087376)
			(type default)
		)
		(layer "F.Cu")
	)
	(gr_line
		(start 3.657854 -325.942198)
		(end 3.84048 -325.759572)
		(stroke
			(width 0.087376)
			(type default)
		)
		(layer "F.Cu")
	)
	(gr_line
		(start 3.657854 -322.742052)
		(end 3.84048 -322.559426)
		(stroke
			(width 0.087376)
			(type default)
		)
		(layer "F.Cu")
	)
	(gr_line
		(start 3.657854 -319.54216)
		(end 3.84048 -319.359534)
		(stroke
			(width 0.087376)
			(type default)
		)
		(layer "F.Cu")
	)
	(gr_line
		(start 3.657854 -311.542176)
		(end 3.84048 -311.35955)
		(stroke
			(width 0.087376)
			(type default)
		)
		(layer "F.Cu")
	)
	(gr_line
		(start 3.657854 -308.34203)
		(end 3.84048 -308.159404)
		(stroke
			(width 0.087376)
			(type default)
		)
		(layer "F.Cu")
	)
	(gr_line
		(start 3.657854 -305.142138)
		(end 3.84048 -304.959512)
		(stroke
			(width 0.087376)
			(type default)
		)
		(layer "F.Cu")
	)
	(gr_line
		(start 3.657854 -301.941992)
		(end 3.84048 -301.759366)
		(stroke
			(width 0.087376)
			(type default)
		)
		(layer "F.Cu")
	)
	(gr_line
		(start 3.657854 -298.7421)
		(end 3.84048 -298.559474)
		(stroke
			(width 0.087376)
			(type default)
		)
		(layer "F.Cu")
	)
	(gr_line
		(start 3.657854 -295.542208)
		(end 3.84048 -295.359582)
		(stroke
			(width 0.087376)
			(type default)
		)
		(layer "F.Cu")
	)
	(gr_line
		(start 3.657854 -292.342062)
		(end 3.84048 -292.159436)
		(stroke
			(width 0.087376)
			(type default)
		)
		(layer "F.Cu")
	)
	(gr_line
		(start 3.657854 -289.14217)
		(end 3.84048 -288.959544)
		(stroke
			(width 0.087376)
			(type default)
		)
		(layer "F.Cu")
	)
	(gr_line
		(start 3.657854 -281.942032)
		(end 3.840226 -282.124404)
		(stroke
			(width 0.087376)
			(type default)
		)
		(layer "F.Cu")
	)
	(gr_line
		(start 3.657854 -279.541986)
		(end 3.803396 -279.396444)
		(stroke
			(width 0.087376)
			(type default)
		)
		(layer "F.Cu")
	)
	(gr_line
		(start 3.657854 -231.142032)
		(end 3.84048 -230.959406)
		(stroke
			(width 0.087376)
			(type default)
		)
		(layer "F.Cu")
	)
	(gr_line
		(start 3.657854 -227.94214)
		(end 3.84048 -227.759514)
		(stroke
			(width 0.087376)
			(type default)
		)
		(layer "F.Cu")
	)
	(gr_line
		(start 3.657854 -211.942172)
		(end 3.84048 -211.759546)
		(stroke
			(width 0.087376)
			(type default)
		)
		(layer "F.Cu")
	)
	(gr_line
		(start 3.657854 -208.742026)
		(end 3.84048 -208.5594)
		(stroke
			(width 0.087376)
			(type default)
		)
		(layer "F.Cu")
	)
	(gr_line
		(start 3.657854 -205.542134)
		(end 3.84048 -205.359508)
		(stroke
			(width 0.087376)
			(type default)
		)
		(layer "F.Cu")
	)
	(gr_line
		(start 3.657854 -202.341988)
		(end 3.84048 -202.159362)
		(stroke
			(width 0.087376)
			(type default)
		)
		(layer "F.Cu")
	)
	(gr_line
		(start 3.657854 -196.74205)
		(end 3.84048 -196.559424)
		(stroke
			(width 0.087376)
			(type default)
		)
		(layer "F.Cu")
	)
	(gr_line
		(start 3.657854 -193.542158)
		(end 3.84048 -193.359532)
		(stroke
			(width 0.087376)
			(type default)
		)
		(layer "F.Cu")
	)
	(gr_line
		(start 3.657854 -185.542174)
		(end 3.84048 -185.359548)
		(stroke
			(width 0.087376)
			(type default)
		)
		(layer "F.Cu")
	)
	(gr_line
		(start 3.657854 -182.342028)
		(end 3.84048 -182.159402)
		(stroke
			(width 0.087376)
			(type default)
		)
		(layer "F.Cu")
	)
	(gr_line
		(start 3.657854 -178.342036)
		(end 3.840226 -178.524408)
		(stroke
			(width 0.087376)
			(type default)
		)
		(layer "F.Cu")
	)
	(gr_line
		(start 3.657854 -175.94199)
		(end 3.840226 -175.759618)
		(stroke
			(width 0.087376)
			(type default)
		)
		(layer "F.Cu")
	)
	(gr_line
		(start 3.657854 -175.142144)
		(end 3.840226 -175.324516)
		(stroke
			(width 0.087376)
			(type default)
		)
		(layer "F.Cu")
	)
	(gr_line
		(start 3.657854 -171.941998)
		(end 3.840226 -172.12437)
		(stroke
			(width 0.087376)
			(type default)
		)
		(layer "F.Cu")
	)
	(gr_line
		(start 3.657854 -168.742106)
		(end 3.840226 -168.924478)
		(stroke
			(width 0.087376)
			(type default)
		)
		(layer "F.Cu")
	)
	(gr_line
		(start 3.657854 -162.342068)
		(end 3.840226 -162.52444)
		(stroke
			(width 0.087376)
			(type default)
		)
		(layer "F.Cu")
	)
	(gr_line
		(start 3.657854 -159.942022)
		(end 3.840226 -159.75965)
		(stroke
			(width 0.087376)
			(type default)
		)
		(layer "F.Cu")
	)
	(gr_line
		(start 3.657854 -159.142176)
		(end 3.840226 -159.324548)
		(stroke
			(width 0.087376)
			(type default)
		)
		(layer "F.Cu")
	)
	(gr_line
		(start 3.657854 -153.541984)
		(end 3.840226 -153.359612)
		(stroke
			(width 0.087376)
			(type default)
		)
		(layer "F.Cu")
	)
	(gr_line
		(start 3.657854 -152.742138)
		(end 3.840226 -152.92451)
		(stroke
			(width 0.087376)
			(type default)
		)
		(layer "F.Cu")
	)
	(gr_line
		(start 3.658108 -449.5419)
		(end 3.84048 -449.359528)
		(stroke
			(width 0.087376)
			(type default)
		)
		(layer "F.Cu")
	)
	(gr_line
		(start 3.658108 -443.941962)
		(end 3.84048 -443.75959)
		(stroke
			(width 0.087376)
			(type default)
		)
		(layer "F.Cu")
	)
	(gr_line
		(start 3.658108 -437.541924)
		(end 3.796792 -437.40324)
		(stroke
			(width 0.087376)
			(type default)
		)
		(layer "F.Cu")
	)
	(gr_line
		(start 3.658108 -431.941986)
		(end 3.84048 -431.759614)
		(stroke
			(width 0.087376)
			(type default)
		)
		(layer "F.Cu")
	)
	(gr_line
		(start 3.658108 -425.541948)
		(end 3.84048 -425.359576)
		(stroke
			(width 0.087376)
			(type default)
		)
		(layer "F.Cu")
	)
	(gr_line
		(start 3.658108 -415.141918)
		(end 3.84048 -415.32429)
		(stroke
			(width 0.087376)
			(type default)
		)
		(layer "F.Cu")
	)
	(gr_line
		(start 3.658108 -411.941772)
		(end 3.84048 -412.124144)
		(stroke
			(width 0.087376)
			(type default)
		)
		(layer "F.Cu")
	)
	(gr_line
		(start 3.658108 -408.74188)
		(end 3.84048 -408.924252)
		(stroke
			(width 0.087376)
			(type default)
		)
		(layer "F.Cu")
	)
	(gr_line
		(start 3.658108 -402.341842)
		(end 3.84048 -402.524214)
		(stroke
			(width 0.087376)
			(type default)
		)
		(layer "F.Cu")
	)
	(gr_line
		(start 3.658108 -396.741904)
		(end 3.84048 -396.924276)
		(stroke
			(width 0.087376)
			(type default)
		)
		(layer "F.Cu")
	)
	(gr_line
		(start 3.658108 -390.341866)
		(end 3.84048 -390.524238)
		(stroke
			(width 0.087376)
			(type default)
		)
		(layer "F.Cu")
	)
	(gr_line
		(start 3.658108 -353.142042)
		(end 3.84048 -353.324414)
		(stroke
			(width 0.087376)
			(type default)
		)
		(layer "F.Cu")
	)
	(gr_line
		(start 3.658108 -346.742004)
		(end 3.84048 -346.924376)
		(stroke
			(width 0.087376)
			(type default)
		)
		(layer "F.Cu")
	)
	(gr_line
		(start 3.658108 -328.34199)
		(end 3.84048 -328.524362)
		(stroke
			(width 0.087376)
			(type default)
		)
		(layer "F.Cu")
	)
	(gr_line
		(start 3.658108 -325.142098)
		(end 3.84048 -325.32447)
		(stroke
			(width 0.087376)
			(type default)
		)
		(layer "F.Cu")
	)
	(gr_line
		(start 3.658108 -318.74206)
		(end 3.84048 -318.924432)
		(stroke
			(width 0.087376)
			(type default)
		)
		(layer "F.Cu")
	)
	(gr_line
		(start 3.658108 -310.742076)
		(end 3.84048 -310.924448)
		(stroke
			(width 0.087376)
			(type default)
		)
		(layer "F.Cu")
	)
	(gr_line
		(start 3.658108 -304.342038)
		(end 3.84048 -304.52441)
		(stroke
			(width 0.087376)
			(type default)
		)
		(layer "F.Cu")
	)
	(gr_line
		(start 3.658108 -297.942)
		(end 3.84048 -298.124372)
		(stroke
			(width 0.087376)
			(type default)
		)
		(layer "F.Cu")
	)
	(gr_line
		(start 3.658108 -294.742108)
		(end 3.84048 -294.92448)
		(stroke
			(width 0.087376)
			(type default)
		)
		(layer "F.Cu")
	)
	(gr_line
		(start 3.658108 -288.34207)
		(end 3.84048 -288.524442)
		(stroke
			(width 0.087376)
			(type default)
		)
		(layer "F.Cu")
	)
	(gr_line
		(start 3.658108 -227.14204)
		(end 3.84048 -227.324412)
		(stroke
			(width 0.087376)
			(type default)
		)
		(layer "F.Cu")
	)
	(gr_line
		(start 3.658108 -211.142072)
		(end 3.84048 -211.324444)
		(stroke
			(width 0.087376)
			(type default)
		)
		(layer "F.Cu")
	)
	(gr_line
		(start 3.658108 -204.742034)
		(end 3.84048 -204.924406)
		(stroke
			(width 0.087376)
			(type default)
		)
		(layer "F.Cu")
	)
	(gr_line
		(start 3.658108 -192.742058)
		(end 3.84048 -192.92443)
		(stroke
			(width 0.087376)
			(type default)
		)
		(layer "F.Cu")
	)
	(gr_line
		(start 3.658108 -184.742074)
		(end 3.84048 -184.924446)
		(stroke
			(width 0.087376)
			(type default)
		)
		(layer "F.Cu")
	)
	(gr_line
		(start 3.658362 -349.94215)
		(end 3.84048 -350.124268)
		(stroke
			(width 0.087376)
			(type default)
		)
		(layer "F.Cu")
	)
	(gr_line
		(start 3.658362 -321.942206)
		(end 3.84048 -322.124324)
		(stroke
			(width 0.087376)
			(type default)
		)
		(layer "F.Cu")
	)
	(gr_line
		(start 3.658362 -307.542184)
		(end 3.84048 -307.724302)
		(stroke
			(width 0.087376)
			(type default)
		)
		(layer "F.Cu")
	)
	(gr_line
		(start 3.658362 -301.142146)
		(end 3.84048 -301.324264)
		(stroke
			(width 0.087376)
			(type default)
		)
		(layer "F.Cu")
	)
	(gr_line
		(start 3.658362 -291.542216)
		(end 3.84048 -291.724334)
		(stroke
			(width 0.087376)
			(type default)
		)
		(layer "F.Cu")
	)
	(gr_line
		(start 3.658362 -230.342186)
		(end 3.84048 -230.524304)
		(stroke
			(width 0.087376)
			(type default)
		)
		(layer "F.Cu")
	)
	(gr_line
		(start 3.658362 -207.94218)
		(end 3.84048 -208.124298)
		(stroke
			(width 0.087376)
			(type default)
		)
		(layer "F.Cu")
	)
	(gr_line
		(start 3.658362 -201.542142)
		(end 3.84048 -201.72426)
		(stroke
			(width 0.087376)
			(type default)
		)
		(layer "F.Cu")
	)
	(gr_line
		(start 3.658362 -195.942204)
		(end 3.84048 -196.124322)
		(stroke
			(width 0.087376)
			(type default)
		)
		(layer "F.Cu")
	)
	(gr_line
		(start 3.658362 -181.542182)
		(end 3.84048 -181.7243)
		(stroke
			(width 0.087376)
			(type default)
		)
		(layer "F.Cu")
	)
	(gr_line
		(start 3.690366 -455.941938)
		(end 3.704844 -455.956416)
		(stroke
			(width 0.085598)
			(type default)
		)
		(layer "F.Cu")
	)
	(gr_line
		(start 3.695954 -156.74213)
		(end 3.84048 -156.597604)
		(stroke
			(width 0.087376)
			(type default)
		)
		(layer "F.Cu")
	)
	(gr_line
		(start 3.696462 -223.942148)
		(end 3.84048 -224.086166)
		(stroke
			(width 0.087376)
			(type default)
		)
		(layer "F.Cu")
	)
	(gr_line
		(start 3.70459 -456.741784)
		(end 3.704844 -456.74153)
		(stroke
			(width 0.085598)
			(type default)
		)
		(layer "F.Cu")
	)
	(gr_line
		(start 3.708908 -220.742002)
		(end 3.84048 -220.873574)
		(stroke
			(width 0.087376)
			(type default)
		)
		(layer "F.Cu")
	)
	(gr_line
		(start 3.708908 -217.54211)
		(end 3.84048 -217.673682)
		(stroke
			(width 0.087376)
			(type default)
		)
		(layer "F.Cu")
	)
	(gr_line
		(start 3.709162 -214.342218)
		(end 3.84048 -214.473536)
		(stroke
			(width 0.087376)
			(type default)
		)
		(layer "F.Cu")
	)
	(gr_line
		(start 4.481068 -385.035806)
		(end 4.60629 -384.910584)
		(stroke
			(width 0.087376)
			(type default)
		)
		(layer "F.Cu")
	)
	(gr_line
		(start 4.60629 -384.910584)
		(end 5.130546 -384.910584)
		(stroke
			(width 0.087376)
			(type default)
		)
		(layer "F.Cu")
	)
	(gr_line
		(start 4.786122 -385.3434)
		(end 4.950714 -385.3434)
		(stroke
			(width 0.087376)
			(type default)
		)
		(layer "F.Cu")
	)
	(gr_line
		(start 5.130546 -384.910584)
		(end 5.255768 -385.035806)
		(stroke
			(width 0.087376)
			(type default)
		)
		(layer "F.Cu")
	)
	(gr_line
		(start 6.477 -449.467732)
		(end 6.665976 -449.278756)
		(stroke
			(width 0.087376)
			(type default)
		)
		(layer "F.Cu")
	)
	(gr_line
		(start 6.7564 -378.9299)
		(end 6.996176 -379.169676)
		(stroke
			(width 0.087376)
			(type default)
		)
		(layer "F.Cu")
	)
	(gr_line
		(start 6.7564 -378.0409)
		(end 6.996176 -377.801124)
		(stroke
			(width 0.087376)
			(type default)
		)
		(layer "F.Cu")
	)
	(gr_line
		(start 6.80339 -447.007996)
		(end 6.992366 -447.196972)
		(stroke
			(width 0.087376)
			(type default)
		)
		(layer "F.Cu")
	)
	(gr_line
		(start 6.80339 -446.573148)
		(end 6.992366 -446.384172)
		(stroke
			(width 0.087376)
			(type default)
		)
		(layer "F.Cu")
	)
	(gr_line
		(start 6.80339 -443.808104)
		(end 6.992366 -443.99708)
		(stroke
			(width 0.087376)
			(type default)
		)
		(layer "F.Cu")
	)
	(gr_line
		(start 6.80339 -443.373256)
		(end 6.992366 -443.18428)
		(stroke
			(width 0.087376)
			(type default)
		)
		(layer "F.Cu")
	)
	(gr_line
		(start 6.80339 -440.607958)
		(end 6.992366 -440.796934)
		(stroke
			(width 0.087376)
			(type default)
		)
		(layer "F.Cu")
	)
	(gr_line
		(start 6.80339 -440.17311)
		(end 6.992366 -439.984134)
		(stroke
			(width 0.087376)
			(type default)
		)
		(layer "F.Cu")
	)
	(gr_line
		(start 6.80339 -437.408066)
		(end 6.992366 -437.597042)
		(stroke
			(width 0.087376)
			(type default)
		)
		(layer "F.Cu")
	)
	(gr_line
		(start 6.80339 -436.973218)
		(end 6.992366 -436.784242)
		(stroke
			(width 0.087376)
			(type default)
		)
		(layer "F.Cu")
	)
	(gr_line
		(start 6.80339 -431.808128)
		(end 6.992366 -431.997104)
		(stroke
			(width 0.087376)
			(type default)
		)
		(layer "F.Cu")
	)
	(gr_line
		(start 6.80339 -431.37328)
		(end 6.992366 -431.184304)
		(stroke
			(width 0.087376)
			(type default)
		)
		(layer "F.Cu")
	)
	(gr_line
		(start 6.80339 -428.607982)
		(end 6.992366 -428.796958)
		(stroke
			(width 0.087376)
			(type default)
		)
		(layer "F.Cu")
	)
	(gr_line
		(start 6.80339 -428.173134)
		(end 6.992366 -427.984158)
		(stroke
			(width 0.087376)
			(type default)
		)
		(layer "F.Cu")
	)
	(gr_line
		(start 6.80339 -425.40809)
		(end 6.992366 -425.597066)
		(stroke
			(width 0.087376)
			(type default)
		)
		(layer "F.Cu")
	)
	(gr_line
		(start 6.80339 -424.973242)
		(end 6.992366 -424.784266)
		(stroke
			(width 0.087376)
			(type default)
		)
		(layer "F.Cu")
	)
	(gr_line
		(start 6.80339 -415.759646)
		(end 6.992366 -415.948622)
		(stroke
			(width 0.087376)
			(type default)
		)
		(layer "F.Cu")
	)
	(gr_line
		(start 6.80339 -415.324798)
		(end 6.992366 -415.135822)
		(stroke
			(width 0.087376)
			(type default)
		)
		(layer "F.Cu")
	)
	(gr_line
		(start 6.80339 -412.5595)
		(end 6.992366 -412.748476)
		(stroke
			(width 0.087376)
			(type default)
		)
		(layer "F.Cu")
	)
	(gr_line
		(start 6.80339 -412.124652)
		(end 6.992366 -411.935676)
		(stroke
			(width 0.087376)
			(type default)
		)
		(layer "F.Cu")
	)
	(gr_line
		(start 6.80339 -409.359608)
		(end 6.992366 -409.548584)
		(stroke
			(width 0.087376)
			(type default)
		)
		(layer "F.Cu")
	)
	(gr_line
		(start 6.80339 -408.92476)
		(end 6.992366 -408.735784)
		(stroke
			(width 0.087376)
			(type default)
		)
		(layer "F.Cu")
	)
	(gr_line
		(start 6.80339 -406.159462)
		(end 6.992366 -406.348438)
		(stroke
			(width 0.087376)
			(type default)
		)
		(layer "F.Cu")
	)
	(gr_line
		(start 6.80339 -405.724614)
		(end 6.992366 -405.535638)
		(stroke
			(width 0.087376)
			(type default)
		)
		(layer "F.Cu")
	)
	(gr_line
		(start 6.80339 -402.95957)
		(end 6.992366 -403.148546)
		(stroke
			(width 0.087376)
			(type default)
		)
		(layer "F.Cu")
	)
	(gr_line
		(start 6.80339 -402.524722)
		(end 6.992366 -402.335746)
		(stroke
			(width 0.087376)
			(type default)
		)
		(layer "F.Cu")
	)
	(gr_line
		(start 6.80339 -397.359632)
		(end 6.992366 -397.548608)
		(stroke
			(width 0.087376)
			(type default)
		)
		(layer "F.Cu")
	)
	(gr_line
		(start 6.80339 -396.924784)
		(end 6.992366 -396.735808)
		(stroke
			(width 0.087376)
			(type default)
		)
		(layer "F.Cu")
	)
	(gr_line
		(start 6.80339 -394.159486)
		(end 6.992366 -394.348462)
		(stroke
			(width 0.087376)
			(type default)
		)
		(layer "F.Cu")
	)
	(gr_line
		(start 6.80339 -393.724638)
		(end 6.992366 -393.535662)
		(stroke
			(width 0.087376)
			(type default)
		)
		(layer "F.Cu")
	)
	(gr_line
		(start 6.80339 -390.959594)
		(end 6.992366 -391.14857)
		(stroke
			(width 0.087376)
			(type default)
		)
		(layer "F.Cu")
	)
	(gr_line
		(start 6.80339 -390.524746)
		(end 6.992366 -390.33577)
		(stroke
			(width 0.087376)
			(type default)
		)
		(layer "F.Cu")
	)
	(gr_line
		(start 6.80339 -387.759448)
		(end 6.992366 -387.948424)
		(stroke
			(width 0.087376)
			(type default)
		)
		(layer "F.Cu")
	)
	(gr_line
		(start 6.80339 -387.3246)
		(end 6.992366 -387.135624)
		(stroke
			(width 0.087376)
			(type default)
		)
		(layer "F.Cu")
	)
	(gr_line
		(start 6.80339 -356.959662)
		(end 6.992366 -357.148638)
		(stroke
			(width 0.087376)
			(type default)
		)
		(layer "F.Cu")
	)
	(gr_line
		(start 6.80339 -356.524814)
		(end 6.992366 -356.335838)
		(stroke
			(width 0.087376)
			(type default)
		)
		(layer "F.Cu")
	)
	(gr_line
		(start 6.80339 -353.75977)
		(end 6.992366 -353.948746)
		(stroke
			(width 0.087376)
			(type default)
		)
		(layer "F.Cu")
	)
	(gr_line
		(start 6.80339 -353.324922)
		(end 6.992366 -353.135946)
		(stroke
			(width 0.087376)
			(type default)
		)
		(layer "F.Cu")
	)
	(gr_line
		(start 6.80339 -350.559624)
		(end 6.992366 -350.7486)
		(stroke
			(width 0.087376)
			(type default)
		)
		(layer "F.Cu")
	)
	(gr_line
		(start 6.80339 -350.124776)
		(end 6.992366 -349.9358)
		(stroke
			(width 0.087376)
			(type default)
		)
		(layer "F.Cu")
	)
	(gr_line
		(start 6.80339 -347.359732)
		(end 6.992366 -347.548708)
		(stroke
			(width 0.087376)
			(type default)
		)
		(layer "F.Cu")
	)
	(gr_line
		(start 6.80339 -346.924884)
		(end 6.992366 -346.735908)
		(stroke
			(width 0.087376)
			(type default)
		)
		(layer "F.Cu")
	)
	(gr_line
		(start 6.80339 -344.21064)
		(end 6.992366 -344.399616)
		(stroke
			(width 0.087376)
			(type default)
		)
		(layer "F.Cu")
	)
	(gr_line
		(start 6.80339 -343.775792)
		(end 6.992366 -343.586816)
		(stroke
			(width 0.087376)
			(type default)
		)
		(layer "F.Cu")
	)
	(gr_line
		(start 6.80339 -341.010494)
		(end 6.992366 -341.19947)
		(stroke
			(width 0.087376)
			(type default)
		)
		(layer "F.Cu")
	)
	(gr_line
		(start 6.80339 -340.575646)
		(end 6.992366 -340.38667)
		(stroke
			(width 0.087376)
			(type default)
		)
		(layer "F.Cu")
	)
	(gr_line
		(start 6.80339 -337.810602)
		(end 6.992366 -337.999578)
		(stroke
			(width 0.087376)
			(type default)
		)
		(layer "F.Cu")
	)
	(gr_line
		(start 6.80339 -337.375754)
		(end 6.992366 -337.186778)
		(stroke
			(width 0.087376)
			(type default)
		)
		(layer "F.Cu")
	)
	(gr_line
		(start 6.80339 -334.610456)
		(end 6.992366 -334.799432)
		(stroke
			(width 0.087376)
			(type default)
		)
		(layer "F.Cu")
	)
	(gr_line
		(start 6.80339 -334.175608)
		(end 6.992366 -333.986632)
		(stroke
			(width 0.087376)
			(type default)
		)
		(layer "F.Cu")
	)
	(gr_line
		(start 6.80339 -328.959718)
		(end 6.992366 -329.148694)
		(stroke
			(width 0.087376)
			(type default)
		)
		(layer "F.Cu")
	)
	(gr_line
		(start 6.80339 -328.52487)
		(end 6.992366 -328.335894)
		(stroke
			(width 0.087376)
			(type default)
		)
		(layer "F.Cu")
	)
	(gr_line
		(start 6.80339 -325.759826)
		(end 6.992366 -325.948802)
		(stroke
			(width 0.087376)
			(type default)
		)
		(layer "F.Cu")
	)
	(gr_line
		(start 6.80339 -325.324978)
		(end 6.992366 -325.136002)
		(stroke
			(width 0.087376)
			(type default)
		)
		(layer "F.Cu")
	)
	(gr_line
		(start 6.80339 -322.55968)
		(end 6.992366 -322.748656)
		(stroke
			(width 0.087376)
			(type default)
		)
		(layer "F.Cu")
	)
	(gr_line
		(start 6.80339 -322.124832)
		(end 6.992366 -321.935856)
		(stroke
			(width 0.087376)
			(type default)
		)
		(layer "F.Cu")
	)
	(gr_line
		(start 6.80339 -319.359788)
		(end 6.992366 -319.548764)
		(stroke
			(width 0.087376)
			(type default)
		)
		(layer "F.Cu")
	)
	(gr_line
		(start 6.80339 -318.92494)
		(end 6.992366 -318.735964)
		(stroke
			(width 0.087376)
			(type default)
		)
		(layer "F.Cu")
	)
	(gr_line
		(start 6.80339 -311.359804)
		(end 6.992366 -311.54878)
		(stroke
			(width 0.087376)
			(type default)
		)
		(layer "F.Cu")
	)
	(gr_line
		(start 6.80339 -310.924956)
		(end 6.992366 -310.73598)
		(stroke
			(width 0.087376)
			(type default)
		)
		(layer "F.Cu")
	)
	(gr_line
		(start 6.80339 -308.159658)
		(end 6.992366 -308.348634)
		(stroke
			(width 0.087376)
			(type default)
		)
		(layer "F.Cu")
	)
	(gr_line
		(start 6.80339 -307.72481)
		(end 6.992366 -307.535834)
		(stroke
			(width 0.087376)
			(type default)
		)
		(layer "F.Cu")
	)
	(gr_line
		(start 6.80339 -304.959766)
		(end 6.992366 -305.148742)
		(stroke
			(width 0.087376)
			(type default)
		)
		(layer "F.Cu")
	)
	(gr_line
		(start 6.80339 -304.524918)
		(end 6.992366 -304.335942)
		(stroke
			(width 0.087376)
			(type default)
		)
		(layer "F.Cu")
	)
	(gr_line
		(start 6.80339 -301.75962)
		(end 6.992366 -301.948596)
		(stroke
			(width 0.087376)
			(type default)
		)
		(layer "F.Cu")
	)
	(gr_line
		(start 6.80339 -301.324772)
		(end 6.992366 -301.135796)
		(stroke
			(width 0.087376)
			(type default)
		)
		(layer "F.Cu")
	)
	(gr_line
		(start 6.80339 -298.559728)
		(end 6.992366 -298.748704)
		(stroke
			(width 0.087376)
			(type default)
		)
		(layer "F.Cu")
	)
	(gr_line
		(start 6.80339 -298.12488)
		(end 6.992366 -297.935904)
		(stroke
			(width 0.087376)
			(type default)
		)
		(layer "F.Cu")
	)
	(gr_line
		(start 6.80339 -295.359836)
		(end 6.992366 -295.548812)
		(stroke
			(width 0.087376)
			(type default)
		)
		(layer "F.Cu")
	)
	(gr_line
		(start 6.80339 -294.924988)
		(end 6.992366 -294.736012)
		(stroke
			(width 0.087376)
			(type default)
		)
		(layer "F.Cu")
	)
	(gr_line
		(start 6.80339 -292.15969)
		(end 6.992366 -292.348666)
		(stroke
			(width 0.087376)
			(type default)
		)
		(layer "F.Cu")
	)
	(gr_line
		(start 6.80339 -291.724842)
		(end 6.992366 -291.535866)
		(stroke
			(width 0.087376)
			(type default)
		)
		(layer "F.Cu")
	)
	(gr_line
		(start 6.80339 -288.959798)
		(end 6.992366 -289.148774)
		(stroke
			(width 0.087376)
			(type default)
		)
		(layer "F.Cu")
	)
	(gr_line
		(start 6.80339 -288.52495)
		(end 6.992366 -288.335974)
		(stroke
			(width 0.087376)
			(type default)
		)
		(layer "F.Cu")
	)
	(gr_line
		(start 6.80339 -282.61056)
		(end 6.992366 -282.799536)
		(stroke
			(width 0.087376)
			(type default)
		)
		(layer "F.Cu")
	)
	(gr_line
		(start 6.80339 -282.175712)
		(end 6.992366 -281.986736)
		(stroke
			(width 0.087376)
			(type default)
		)
		(layer "F.Cu")
	)
	(gr_line
		(start 6.80339 -279.410414)
		(end 6.992366 -279.59939)
		(stroke
			(width 0.087376)
			(type default)
		)
		(layer "F.Cu")
	)
	(gr_line
		(start 6.80339 -278.975566)
		(end 6.992366 -278.78659)
		(stroke
			(width 0.087376)
			(type default)
		)
		(layer "F.Cu")
	)
	(gr_line
		(start 6.80339 -230.95966)
		(end 6.992366 -231.148636)
		(stroke
			(width 0.087376)
			(type default)
		)
		(layer "F.Cu")
	)
	(gr_line
		(start 6.80339 -230.524812)
		(end 6.992366 -230.335836)
		(stroke
			(width 0.087376)
			(type default)
		)
		(layer "F.Cu")
	)
	(gr_line
		(start 6.80339 -227.759768)
		(end 6.992366 -227.948744)
		(stroke
			(width 0.087376)
			(type default)
		)
		(layer "F.Cu")
	)
	(gr_line
		(start 6.80339 -227.32492)
		(end 6.992366 -227.135944)
		(stroke
			(width 0.087376)
			(type default)
		)
		(layer "F.Cu")
	)
	(gr_line
		(start 6.80339 -224.521522)
		(end 6.992366 -224.710498)
		(stroke
			(width 0.087376)
			(type default)
		)
		(layer "F.Cu")
	)
	(gr_line
		(start 6.80339 -224.086674)
		(end 6.992366 -223.897698)
		(stroke
			(width 0.087376)
			(type default)
		)
		(layer "F.Cu")
	)
	(gr_line
		(start 6.80339 -221.30893)
		(end 6.992366 -221.497906)
		(stroke
			(width 0.087376)
			(type default)
		)
		(layer "F.Cu")
	)
	(gr_line
		(start 6.80339 -220.874082)
		(end 6.992366 -220.685106)
		(stroke
			(width 0.087376)
			(type default)
		)
		(layer "F.Cu")
	)
	(gr_line
		(start 6.80339 -218.109038)
		(end 6.992366 -218.298014)
		(stroke
			(width 0.087376)
			(type default)
		)
		(layer "F.Cu")
	)
	(gr_line
		(start 6.80339 -217.67419)
		(end 6.992366 -217.485214)
		(stroke
			(width 0.087376)
			(type default)
		)
		(layer "F.Cu")
	)
	(gr_line
		(start 6.80339 -214.908892)
		(end 6.992366 -215.097868)
		(stroke
			(width 0.087376)
			(type default)
		)
		(layer "F.Cu")
	)
	(gr_line
		(start 6.80339 -214.474044)
		(end 6.992366 -214.285068)
		(stroke
			(width 0.087376)
			(type default)
		)
		(layer "F.Cu")
	)
	(gr_line
		(start 6.80339 -211.7598)
		(end 6.992366 -211.948776)
		(stroke
			(width 0.087376)
			(type default)
		)
		(layer "F.Cu")
	)
	(gr_line
		(start 6.80339 -211.324952)
		(end 6.992366 -211.135976)
		(stroke
			(width 0.087376)
			(type default)
		)
		(layer "F.Cu")
	)
	(gr_line
		(start 6.80339 -208.559654)
		(end 6.992366 -208.74863)
		(stroke
			(width 0.087376)
			(type default)
		)
		(layer "F.Cu")
	)
	(gr_line
		(start 6.80339 -208.124806)
		(end 6.992366 -207.93583)
		(stroke
			(width 0.087376)
			(type default)
		)
		(layer "F.Cu")
	)
	(gr_line
		(start 6.80339 -205.359762)
		(end 6.992366 -205.548738)
		(stroke
			(width 0.087376)
			(type default)
		)
		(layer "F.Cu")
	)
	(gr_line
		(start 6.80339 -204.924914)
		(end 6.992366 -204.735938)
		(stroke
			(width 0.087376)
			(type default)
		)
		(layer "F.Cu")
	)
	(gr_line
		(start 6.80339 -202.159616)
		(end 6.992366 -202.348592)
		(stroke
			(width 0.087376)
			(type default)
		)
		(layer "F.Cu")
	)
	(gr_line
		(start 6.80339 -201.724768)
		(end 6.992366 -201.535792)
		(stroke
			(width 0.087376)
			(type default)
		)
		(layer "F.Cu")
	)
	(gr_line
		(start 6.80339 -196.559678)
		(end 6.992366 -196.748654)
		(stroke
			(width 0.087376)
			(type default)
		)
		(layer "F.Cu")
	)
	(gr_line
		(start 6.80339 -196.12483)
		(end 6.992366 -195.935854)
		(stroke
			(width 0.087376)
			(type default)
		)
		(layer "F.Cu")
	)
	(gr_line
		(start 6.80339 -193.359786)
		(end 6.992366 -193.548762)
		(stroke
			(width 0.087376)
			(type default)
		)
		(layer "F.Cu")
	)
	(gr_line
		(start 6.80339 -192.924938)
		(end 6.992366 -192.735962)
		(stroke
			(width 0.087376)
			(type default)
		)
		(layer "F.Cu")
	)
	(gr_line
		(start 6.80339 -185.359802)
		(end 6.992366 -185.548778)
		(stroke
			(width 0.087376)
			(type default)
		)
		(layer "F.Cu")
	)
	(gr_line
		(start 6.80339 -184.924954)
		(end 6.992366 -184.735978)
		(stroke
			(width 0.087376)
			(type default)
		)
		(layer "F.Cu")
	)
	(gr_line
		(start 6.80339 -182.159656)
		(end 6.992366 -182.348632)
		(stroke
			(width 0.087376)
			(type default)
		)
		(layer "F.Cu")
	)
	(gr_line
		(start 6.80339 -181.724808)
		(end 6.992366 -181.535832)
		(stroke
			(width 0.087376)
			(type default)
		)
		(layer "F.Cu")
	)
	(gr_line
		(start 6.80339 -179.010564)
		(end 6.992366 -179.19954)
		(stroke
			(width 0.087376)
			(type default)
		)
		(layer "F.Cu")
	)
	(gr_line
		(start 6.80339 -178.575716)
		(end 6.992366 -178.38674)
		(stroke
			(width 0.087376)
			(type default)
		)
		(layer "F.Cu")
	)
	(gr_line
		(start 6.80339 -175.810418)
		(end 6.992366 -175.999394)
		(stroke
			(width 0.087376)
			(type default)
		)
		(layer "F.Cu")
	)
	(gr_line
		(start 6.80339 -175.37557)
		(end 6.992366 -175.186594)
		(stroke
			(width 0.087376)
			(type default)
		)
		(layer "F.Cu")
	)
	(gr_line
		(start 6.80339 -172.610526)
		(end 6.992366 -172.799502)
		(stroke
			(width 0.087376)
			(type default)
		)
		(layer "F.Cu")
	)
	(gr_line
		(start 6.80339 -172.175678)
		(end 6.992366 -171.986702)
		(stroke
			(width 0.087376)
			(type default)
		)
		(layer "F.Cu")
	)
	(gr_line
		(start 6.80339 -169.410634)
		(end 6.992366 -169.59961)
		(stroke
			(width 0.087376)
			(type default)
		)
		(layer "F.Cu")
	)
	(gr_line
		(start 6.80339 -168.975786)
		(end 6.992366 -168.78681)
		(stroke
			(width 0.087376)
			(type default)
		)
		(layer "F.Cu")
	)
	(gr_line
		(start 6.80339 -163.010596)
		(end 6.992366 -163.199572)
		(stroke
			(width 0.087376)
			(type default)
		)
		(layer "F.Cu")
	)
	(gr_line
		(start 6.80339 -162.575748)
		(end 6.992366 -162.386772)
		(stroke
			(width 0.087376)
			(type default)
		)
		(layer "F.Cu")
	)
	(gr_line
		(start 6.80339 -159.81045)
		(end 6.992366 -159.999426)
		(stroke
			(width 0.087376)
			(type default)
		)
		(layer "F.Cu")
	)
	(gr_line
		(start 6.80339 -159.375602)
		(end 6.992366 -159.186626)
		(stroke
			(width 0.087376)
			(type default)
		)
		(layer "F.Cu")
	)
	(gr_line
		(start 6.80339 -156.597858)
		(end 6.992366 -156.786834)
		(stroke
			(width 0.087376)
			(type default)
		)
		(layer "F.Cu")
	)
	(gr_line
		(start 6.80339 -156.16301)
		(end 6.992366 -155.974034)
		(stroke
			(width 0.087376)
			(type default)
		)
		(layer "F.Cu")
	)
	(gr_line
		(start 6.80339 -153.410412)
		(end 6.992366 -153.599388)
		(stroke
			(width 0.087376)
			(type default)
		)
		(layer "F.Cu")
	)
	(gr_line
		(start 6.80339 -152.975564)
		(end 6.992366 -152.786588)
		(stroke
			(width 0.087376)
			(type default)
		)
		(layer "F.Cu")
	)
	(gr_line
		(start 6.907784 -383.701036)
		(end 7.058406 -383.851658)
		(stroke
			(width 0.087376)
			(type default)
		)
		(layer "F.Cu")
	)
	(gr_line
		(start 6.907784 -383.22758)
		(end 6.907784 -383.701036)
		(stroke
			(width 0.087376)
			(type default)
		)
		(layer "F.Cu")
	)
	(gr_line
		(start 6.907784 -383.22758)
		(end 7.058406 -383.076958)
		(stroke
			(width 0.087376)
			(type default)
		)
		(layer "F.Cu")
	)
	(gr_line
		(start 6.912356 -382.401572)
		(end 7.058406 -382.547622)
		(stroke
			(width 0.087376)
			(type default)
		)
		(layer "F.Cu")
	)
	(gr_line
		(start 6.912356 -381.918972)
		(end 6.912356 -382.401572)
		(stroke
			(width 0.087376)
			(type default)
		)
		(layer "F.Cu")
	)
	(gr_line
		(start 6.912356 -381.918972)
		(end 7.058406 -381.772922)
		(stroke
			(width 0.087376)
			(type default)
		)
		(layer "F.Cu")
	)
	(gr_line
		(start 6.933184 -381.118364)
		(end 7.058406 -381.243586)
		(stroke
			(width 0.087376)
			(type default)
		)
		(layer "F.Cu")
	)
	(gr_line
		(start 6.933184 -380.594108)
		(end 6.933184 -381.118364)
		(stroke
			(width 0.087376)
			(type default)
		)
		(layer "F.Cu")
	)
	(gr_line
		(start 6.933184 -380.594108)
		(end 7.058406 -380.468886)
		(stroke
			(width 0.087376)
			(type default)
		)
		(layer "F.Cu")
	)
	(gr_line
		(start 7.100824 -449.278756)
		(end 7.2898 -449.467732)
		(stroke
			(width 0.087376)
			(type default)
		)
		(layer "F.Cu")
	)
	(gr_line
		(start 7.253224 -451.600824)
		(end 7.4803 -451.8279)
		(stroke
			(width 0.087376)
			(type default)
		)
		(layer "F.Cu")
	)
	(gr_line
		(start 7.253224 -451.165976)
		(end 7.4803 -450.9389)
		(stroke
			(width 0.087376)
			(type default)
		)
		(layer "F.Cu")
	)
	(gr_line
		(start 7.366 -383.382012)
		(end 7.366 -383.546604)
		(stroke
			(width 0.087376)
			(type default)
		)
		(layer "F.Cu")
	)
	(gr_line
		(start 7.366 -382.077976)
		(end 7.366 -382.242568)
		(stroke
			(width 0.087376)
			(type default)
		)
		(layer "F.Cu")
	)
	(gr_line
		(start 7.366 -380.77394)
		(end 7.366 -380.938532)
		(stroke
			(width 0.087376)
			(type default)
		)
		(layer "F.Cu")
	)
	(gr_line
		(start 7.431024 -379.169676)
		(end 7.6708 -378.9299)
		(stroke
			(width 0.087376)
			(type default)
		)
		(layer "F.Cu")
	)
	(gr_line
		(start 7.431024 -377.801124)
		(end 7.6708 -378.0409)
		(stroke
			(width 0.087376)
			(type default)
		)
		(layer "F.Cu")
	)
	(gr_line
		(start 8.3439 -384.5433)
		(end 8.570976 -384.770376)
		(stroke
			(width 0.087376)
			(type default)
		)
		(layer "F.Cu")
	)
	(gr_line
		(start 8.3439 -383.6543)
		(end 8.570976 -383.427224)
		(stroke
			(width 0.087376)
			(type default)
		)
		(layer "F.Cu")
	)
	(gr_line
		(start 8.3693 -451.8279)
		(end 8.596376 -451.600824)
		(stroke
			(width 0.087376)
			(type default)
		)
		(layer "F.Cu")
	)
	(gr_line
		(start 8.3693 -450.9389)
		(end 8.596376 -451.165976)
		(stroke
			(width 0.087376)
			(type default)
		)
		(layer "F.Cu")
	)
	(gr_line
		(start 8.376666 -446.954656)
		(end 8.376666 -447.118232)
		(stroke
			(width 0.087376)
			(type default)
		)
		(layer "F.Cu")
	)
	(gr_line
		(start 8.376666 -446.954656)
		(end 8.764524 -446.566798)
		(stroke
			(width 0.087376)
			(type default)
		)
		(layer "F.Cu")
	)
	(gr_line
		(start 8.382254 -385.603242)
		(end 8.57123 -385.414266)
		(stroke
			(width 0.087376)
			(type default)
		)
		(layer "F.Cu")
	)
	(gr_line
		(start 8.764524 -446.566798)
		(end 8.9281 -446.566798)
		(stroke
			(width 0.087376)
			(type default)
		)
		(layer "F.Cu")
	)
	(gr_line
		(start 8.80999 -447.12001)
		(end 8.929878 -447.000122)
		(stroke
			(width 0.087376)
			(type default)
		)
		(layer "F.Cu")
	)
	(gr_line
		(start 8.940546 -380.40056)
		(end 8.940546 -380.565152)
		(stroke
			(width 0.087376)
			(type default)
		)
		(layer "F.Cu")
	)
	(gr_line
		(start 8.940546 -379.096524)
		(end 8.940546 -379.261116)
		(stroke
			(width 0.087376)
			(type default)
		)
		(layer "F.Cu")
	)
	(gr_line
		(start 9.005824 -384.770376)
		(end 9.2329 -384.5433)
		(stroke
			(width 0.087376)
			(type default)
		)
		(layer "F.Cu")
	)
	(gr_line
		(start 9.005824 -383.427224)
		(end 9.2329 -383.6543)
		(stroke
			(width 0.087376)
			(type default)
		)
		(layer "F.Cu")
	)
	(gr_line
		(start 9.006078 -385.414266)
		(end 9.195054 -385.603242)
		(stroke
			(width 0.087376)
			(type default)
		)
		(layer "F.Cu")
	)
	(gr_line
		(start 9.24814 -380.870206)
		(end 9.394444 -380.723902)
		(stroke
			(width 0.087376)
			(type default)
		)
		(layer "F.Cu")
	)
	(gr_line
		(start 9.24814 -380.095506)
		(end 9.394444 -380.24181)
		(stroke
			(width 0.087376)
			(type default)
		)
		(layer "F.Cu")
	)
	(gr_line
		(start 9.24814 -379.56617)
		(end 9.407906 -379.406404)
		(stroke
			(width 0.087376)
			(type default)
		)
		(layer "F.Cu")
	)
	(gr_line
		(start 9.24814 -378.79147)
		(end 9.407906 -378.951236)
		(stroke
			(width 0.087376)
			(type default)
		)
		(layer "F.Cu")
	)
	(gr_line
		(start 9.302496 -446.011808)
		(end 9.302496 -446.192402)
		(stroke
			(width 0.087376)
			(type default)
		)
		(layer "F.Cu")
	)
	(gr_line
		(start 9.302496 -446.011808)
		(end 9.673082 -445.640968)
		(stroke
			(width 0.087376)
			(type default)
		)
		(layer "F.Cu")
	)
	(gr_line
		(start 9.394444 -380.24181)
		(end 9.394444 -380.723902)
		(stroke
			(width 0.087376)
			(type default)
		)
		(layer "F.Cu")
	)
	(gr_line
		(start 9.407906 -378.951236)
		(end 9.407906 -379.406404)
		(stroke
			(width 0.087376)
			(type default)
		)
		(layer "F.Cu")
	)
	(gr_line
		(start 9.673082 -445.640968)
		(end 9.85393 -445.640968)
		(stroke
			(width 0.087376)
			(type default)
		)
		(layer "F.Cu")
	)
	(gr_line
		(start 9.73582 -446.19418)
		(end 9.855708 -446.074292)
		(stroke
			(width 0.087376)
			(type default)
		)
		(layer "F.Cu")
	)
	(gr_line
		(start 10.228072 -445.085978)
		(end 10.228072 -445.266826)
		(stroke
			(width 0.087376)
			(type default)
		)
		(layer "F.Cu")
	)
	(gr_line
		(start 10.228072 -445.085978)
		(end 10.598912 -444.715392)
		(stroke
			(width 0.087376)
			(type default)
		)
		(layer "F.Cu")
	)
	(gr_line
		(start 10.598912 -444.715392)
		(end 10.779506 -444.715392)
		(stroke
			(width 0.087376)
			(type default)
		)
		(layer "F.Cu")
	)
	(gr_line
		(start 10.661396 -445.268604)
		(end 10.781284 -445.148716)
		(stroke
			(width 0.087376)
			(type default)
		)
		(layer "F.Cu")
	)
	(gr_line
		(start 11.632184 -437.647588)
		(end 11.757406 -437.77281)
		(stroke
			(width 0.087376)
			(type default)
		)
		(layer "F.Cu")
	)
	(gr_line
		(start 11.632184 -437.123332)
		(end 11.632184 -437.647588)
		(stroke
			(width 0.087376)
			(type default)
		)
		(layer "F.Cu")
	)
	(gr_line
		(start 11.632184 -437.123332)
		(end 11.757406 -436.99811)
		(stroke
			(width 0.087376)
			(type default)
		)
		(layer "F.Cu")
	)
	(gr_line
		(start 11.632184 -436.343552)
		(end 11.757406 -436.468774)
		(stroke
			(width 0.087376)
			(type default)
		)
		(layer "F.Cu")
	)
	(gr_line
		(start 11.632184 -435.819296)
		(end 11.632184 -436.343552)
		(stroke
			(width 0.087376)
			(type default)
		)
		(layer "F.Cu")
	)
	(gr_line
		(start 11.632184 -435.819296)
		(end 11.757406 -435.694074)
		(stroke
			(width 0.087376)
			(type default)
		)
		(layer "F.Cu")
	)
	(gr_line
		(start 12.065 -437.303164)
		(end 12.065 -437.467756)
		(stroke
			(width 0.087376)
			(type default)
		)
		(layer "F.Cu")
	)
	(gr_line
		(start 12.065 -435.999128)
		(end 12.065 -436.16372)
		(stroke
			(width 0.087376)
			(type default)
		)
		(layer "F.Cu")
	)
	(gr_line
		(start 13.937488 -426.287692)
		(end 14.164564 -426.514768)
		(stroke
			(width 0.087376)
			(type default)
		)
		(layer "F.Cu")
	)
	(gr_line
		(start 13.937488 -425.398692)
		(end 14.164564 -425.171616)
		(stroke
			(width 0.087376)
			(type default)
		)
		(layer "F.Cu")
	)
	(gr_line
		(start 14.224 -407.872946)
		(end 14.224 -408.037538)
		(stroke
			(width 0.087376)
			(type default)
		)
		(layer "F.Cu")
	)
	(gr_line
		(start 14.224 -406.56891)
		(end 14.224 -406.733502)
		(stroke
			(width 0.087376)
			(type default)
		)
		(layer "F.Cu")
	)
	(gr_line
		(start 14.224 -405.264874)
		(end 14.224 -405.429466)
		(stroke
			(width 0.087376)
			(type default)
		)
		(layer "F.Cu")
	)
	(gr_line
		(start 14.224 -382.46939)
		(end 14.224 -382.633982)
		(stroke
			(width 0.087376)
			(type default)
		)
		(layer "F.Cu")
	)
	(gr_line
		(start 14.224 -381.165354)
		(end 14.224 -381.329946)
		(stroke
			(width 0.087376)
			(type default)
		)
		(layer "F.Cu")
	)
	(gr_line
		(start 14.531594 -408.342592)
		(end 14.644878 -408.229308)
		(stroke
			(width 0.087376)
			(type default)
		)
		(layer "F.Cu")
	)
	(gr_line
		(start 14.531594 -407.567892)
		(end 14.644878 -407.681176)
		(stroke
			(width 0.087376)
			(type default)
		)
		(layer "F.Cu")
	)
	(gr_line
		(start 14.531594 -407.038556)
		(end 14.640306 -406.929844)
		(stroke
			(width 0.087376)
			(type default)
		)
		(layer "F.Cu")
	)
	(gr_line
		(start 14.531594 -406.263856)
		(end 14.640306 -406.372568)
		(stroke
			(width 0.087376)
			(type default)
		)
		(layer "F.Cu")
	)
	(gr_line
		(start 14.531594 -405.73452)
		(end 14.656816 -405.609298)
		(stroke
			(width 0.087376)
			(type default)
		)
		(layer "F.Cu")
	)
	(gr_line
		(start 14.531594 -404.95982)
		(end 14.656816 -405.085042)
		(stroke
			(width 0.087376)
			(type default)
		)
		(layer "F.Cu")
	)
	(gr_line
		(start 14.531594 -382.939036)
		(end 14.656816 -382.813814)
		(stroke
			(width 0.087376)
			(type default)
		)
		(layer "F.Cu")
	)
	(gr_line
		(start 14.531594 -382.164336)
		(end 14.656816 -382.289558)
		(stroke
			(width 0.087376)
			(type default)
		)
		(layer "F.Cu")
	)
	(gr_line
		(start 14.531594 -381.635)
		(end 14.656816 -381.509778)
		(stroke
			(width 0.087376)
			(type default)
		)
		(layer "F.Cu")
	)
	(gr_line
		(start 14.531594 -380.8603)
		(end 14.656816 -380.985522)
		(stroke
			(width 0.087376)
			(type default)
		)
		(layer "F.Cu")
	)
	(gr_line
		(start 14.599412 -426.514768)
		(end 14.826488 -426.287692)
		(stroke
			(width 0.087376)
			(type default)
		)
		(layer "F.Cu")
	)
	(gr_line
		(start 14.599412 -425.171616)
		(end 14.826488 -425.398692)
		(stroke
			(width 0.087376)
			(type default)
		)
		(layer "F.Cu")
	)
	(gr_line
		(start 14.640306 -406.372568)
		(end 14.640306 -406.929844)
		(stroke
			(width 0.087376)
			(type default)
		)
		(layer "F.Cu")
	)
	(gr_line
		(start 14.644878 -407.681176)
		(end 14.644878 -408.229308)
		(stroke
			(width 0.087376)
			(type default)
		)
		(layer "F.Cu")
	)
	(gr_line
		(start 14.656816 -405.085042)
		(end 14.656816 -405.609298)
		(stroke
			(width 0.087376)
			(type default)
		)
		(layer "F.Cu")
	)
	(gr_line
		(start 14.656816 -382.289558)
		(end 14.656816 -382.813814)
		(stroke
			(width 0.087376)
			(type default)
		)
		(layer "F.Cu")
	)
	(gr_line
		(start 14.656816 -380.985522)
		(end 14.656816 -381.509778)
		(stroke
			(width 0.087376)
			(type default)
		)
		(layer "F.Cu")
	)
	(gr_line
		(start 17.272 -445.416178)
		(end 17.460976 -445.227202)
		(stroke
			(width 0.087376)
			(type default)
		)
		(layer "F.Cu")
	)
	(gr_line
		(start 17.272 -444.603378)
		(end 17.460976 -444.792354)
		(stroke
			(width 0.087376)
			(type default)
		)
		(layer "F.Cu")
	)
	(gr_line
		(start 17.272 -342.41613)
		(end 17.460976 -342.227154)
		(stroke
			(width 0.087376)
			(type default)
		)
		(layer "F.Cu")
	)
	(gr_line
		(start 17.272 -341.60333)
		(end 17.460976 -341.792306)
		(stroke
			(width 0.087376)
			(type default)
		)
		(layer "F.Cu")
	)
	(gr_line
		(start 17.272 -239.416082)
		(end 17.460976 -239.227106)
		(stroke
			(width 0.087376)
			(type default)
		)
		(layer "F.Cu")
	)
	(gr_line
		(start 17.272 -238.603282)
		(end 17.460976 -238.792258)
		(stroke
			(width 0.087376)
			(type default)
		)
		(layer "F.Cu")
	)
	(gr_line
		(start 17.272 -136.416034)
		(end 17.460976 -136.227058)
		(stroke
			(width 0.087376)
			(type default)
		)
		(layer "F.Cu")
	)
	(gr_line
		(start 17.272 -135.603234)
		(end 17.460976 -135.79221)
		(stroke
			(width 0.087376)
			(type default)
		)
		(layer "F.Cu")
	)
	(gr_line
		(start 17.272 -33.415986)
		(end 17.460976 -33.22701)
		(stroke
			(width 0.087376)
			(type default)
		)
		(layer "F.Cu")
	)
	(gr_line
		(start 17.272 -32.603186)
		(end 17.460976 -32.792162)
		(stroke
			(width 0.087376)
			(type default)
		)
		(layer "F.Cu")
	)
	(gr_line
		(start 18.239486 -445.213486)
		(end 18.436082 -445.410082)
		(stroke
			(width 0.087376)
			(type default)
		)
		(layer "F.Cu")
	)
	(gr_line
		(start 18.239486 -444.778638)
		(end 18.408142 -444.609982)
		(stroke
			(width 0.087376)
			(type default)
		)
		(layer "F.Cu")
	)
	(gr_line
		(start 18.353024 -136.227058)
		(end 18.535904 -136.409938)
		(stroke
			(width 0.087376)
			(type default)
		)
		(layer "F.Cu")
	)
	(gr_line
		(start 18.353024 -135.791956)
		(end 18.535142 -135.609838)
		(stroke
			(width 0.087376)
			(type default)
		)
		(layer "F.Cu")
	)
	(gr_line
		(start 18.353024 -33.22701)
		(end 18.535904 -33.40989)
		(stroke
			(width 0.087376)
			(type default)
		)
		(layer "F.Cu")
	)
	(gr_line
		(start 18.353024 -32.791908)
		(end 18.535142 -32.60979)
		(stroke
			(width 0.087376)
			(type default)
		)
		(layer "F.Cu")
	)
	(gr_line
		(start 18.356326 -342.230456)
		(end 18.535904 -342.410034)
		(stroke
			(width 0.087376)
			(type default)
		)
		(layer "F.Cu")
	)
	(gr_line
		(start 18.356326 -341.795608)
		(end 18.542 -341.609934)
		(stroke
			(width 0.087376)
			(type default)
		)
		(layer "F.Cu")
	)
	(gr_line
		(start 18.356326 -239.230408)
		(end 18.535904 -239.409986)
		(stroke
			(width 0.087376)
			(type default)
		)
		(layer "F.Cu")
	)
	(gr_line
		(start 18.356326 -238.79556)
		(end 18.542 -238.609886)
		(stroke
			(width 0.087376)
			(type default)
		)
		(layer "F.Cu")
	)
	(gr_line
		(start 18.408142 -444.609982)
		(end 19.61007 -444.609982)
		(stroke
			(width 0.087376)
			(type default)
		)
		(layer "F.Cu")
	)
	(gr_line
		(start 18.436082 -445.410082)
		(end 19.61007 -445.410082)
		(stroke
			(width 0.087376)
			(type default)
		)
		(layer "F.Cu")
	)
	(gr_line
		(start 18.535142 -135.609838)
		(end 19.61007 -135.609838)
		(stroke
			(width 0.087376)
			(type default)
		)
		(layer "F.Cu")
	)
	(gr_line
		(start 18.535142 -32.60979)
		(end 19.61007 -32.60979)
		(stroke
			(width 0.087376)
			(type default)
		)
		(layer "F.Cu")
	)
	(gr_line
		(start 18.535904 -342.410034)
		(end 19.61007 -342.410034)
		(stroke
			(width 0.087376)
			(type default)
		)
		(layer "F.Cu")
	)
	(gr_line
		(start 18.535904 -239.409986)
		(end 19.61007 -239.409986)
		(stroke
			(width 0.087376)
			(type default)
		)
		(layer "F.Cu")
	)
	(gr_line
		(start 18.535904 -136.409938)
		(end 19.61007 -136.409938)
		(stroke
			(width 0.087376)
			(type default)
		)
		(layer "F.Cu")
	)
	(gr_line
		(start 18.535904 -33.40989)
		(end 19.61007 -33.40989)
		(stroke
			(width 0.087376)
			(type default)
		)
		(layer "F.Cu")
	)
	(gr_line
		(start 18.542 -341.609934)
		(end 19.61007 -341.609934)
		(stroke
			(width 0.087376)
			(type default)
		)
		(layer "F.Cu")
	)
	(gr_line
		(start 18.542 -238.609886)
		(end 19.61007 -238.609886)
		(stroke
			(width 0.087376)
			(type default)
		)
		(layer "F.Cu")
	)
	(gr_line
		(start 22.800056 -453.810116)
		(end 23.882604 -453.810116)
		(stroke
			(width 0.087376)
			(type default)
		)
		(layer "F.Cu")
	)
	(gr_line
		(start 22.800056 -453.010016)
		(end 23.876 -453.010016)
		(stroke
			(width 0.087376)
			(type default)
		)
		(layer "F.Cu")
	)
	(gr_line
		(start 22.800056 -451.41007)
		(end 23.95093 -451.41007)
		(stroke
			(width 0.087376)
			(type default)
		)
		(layer "F.Cu")
	)
	(gr_line
		(start 22.800056 -450.60997)
		(end 23.88997 -450.60997)
		(stroke
			(width 0.087376)
			(type default)
		)
		(layer "F.Cu")
	)
	(gr_line
		(start 22.800056 -449.010024)
		(end 23.882604 -449.010024)
		(stroke
			(width 0.087376)
			(type default)
		)
		(layer "F.Cu")
	)
	(gr_line
		(start 22.800056 -448.210178)
		(end 23.903178 -448.210178)
		(stroke
			(width 0.087376)
			(type default)
		)
		(layer "F.Cu")
	)
	(gr_line
		(start 22.800056 -438.609994)
		(end 24.003 -438.609994)
		(stroke
			(width 0.087376)
			(type default)
		)
		(layer "F.Cu")
	)
	(gr_line
		(start 22.800056 -437.810148)
		(end 24.003 -437.810148)
		(stroke
			(width 0.087376)
			(type default)
		)
		(layer "F.Cu")
	)
	(gr_line
		(start 22.800056 -436.210202)
		(end 23.876 -436.210202)
		(stroke
			(width 0.087376)
			(type default)
		)
		(layer "F.Cu")
	)
	(gr_line
		(start 22.800056 -435.410102)
		(end 23.876 -435.410102)
		(stroke
			(width 0.087376)
			(type default)
		)
		(layer "F.Cu")
	)
	(gr_line
		(start 22.800056 -433.810156)
		(end 23.876 -433.810156)
		(stroke
			(width 0.087376)
			(type default)
		)
		(layer "F.Cu")
	)
	(gr_line
		(start 22.800056 -433.010056)
		(end 23.876 -433.010056)
		(stroke
			(width 0.087376)
			(type default)
		)
		(layer "F.Cu")
	)
	(gr_line
		(start 22.800056 -431.41011)
		(end 23.88235 -431.41011)
		(stroke
			(width 0.087376)
			(type default)
		)
		(layer "F.Cu")
	)
	(gr_line
		(start 22.800056 -430.61001)
		(end 23.876 -430.61001)
		(stroke
			(width 0.087376)
			(type default)
		)
		(layer "F.Cu")
	)
	(gr_line
		(start 22.800056 -429.010064)
		(end 23.88235 -429.010064)
		(stroke
			(width 0.087376)
			(type default)
		)
		(layer "F.Cu")
	)
	(gr_line
		(start 22.800056 -428.209964)
		(end 23.876 -428.209964)
		(stroke
			(width 0.087376)
			(type default)
		)
		(layer "F.Cu")
	)
	(gr_line
		(start 22.800056 -426.610018)
		(end 23.858982 -426.610018)
		(stroke
			(width 0.087376)
			(type default)
		)
		(layer "F.Cu")
	)
	(gr_line
		(start 22.800056 -425.810172)
		(end 23.882604 -425.810172)
		(stroke
			(width 0.087376)
			(type default)
		)
		(layer "F.Cu")
	)
	(gr_line
		(start 22.800056 -424.209972)
		(end 24.007826 -424.209972)
		(stroke
			(width 0.085598)
			(type default)
		)
		(layer "F.Cu")
	)
	(gr_line
		(start 22.800056 -423.410126)
		(end 24.00808 -423.410126)
		(stroke
			(width 0.085598)
			(type default)
		)
		(layer "F.Cu")
	)
	(gr_line
		(start 22.800056 -350.810068)
		(end 23.966932 -350.810068)
		(stroke
			(width 0.087376)
			(type default)
		)
		(layer "F.Cu")
	)
	(gr_line
		(start 22.800056 -350.009968)
		(end 23.966678 -350.009968)
		(stroke
			(width 0.087376)
			(type default)
		)
		(layer "F.Cu")
	)
	(gr_line
		(start 22.800056 -348.410022)
		(end 23.88235 -348.410022)
		(stroke
			(width 0.087376)
			(type default)
		)
		(layer "F.Cu")
	)
	(gr_line
		(start 22.800056 -347.609922)
		(end 23.876 -347.609922)
		(stroke
			(width 0.087376)
			(type default)
		)
		(layer "F.Cu")
	)
	(gr_line
		(start 22.800056 -346.009976)
		(end 23.876 -346.009976)
		(stroke
			(width 0.087376)
			(type default)
		)
		(layer "F.Cu")
	)
	(gr_line
		(start 22.800056 -345.21013)
		(end 23.876 -345.21013)
		(stroke
			(width 0.087376)
			(type default)
		)
		(layer "F.Cu")
	)
	(gr_line
		(start 22.800056 -335.609946)
		(end 23.882604 -335.609946)
		(stroke
			(width 0.087376)
			(type default)
		)
		(layer "F.Cu")
	)
	(gr_line
		(start 22.800056 -334.8101)
		(end 23.876 -334.8101)
		(stroke
			(width 0.087376)
			(type default)
		)
		(layer "F.Cu")
	)
	(gr_line
		(start 22.800056 -333.210154)
		(end 23.997666 -333.210154)
		(stroke
			(width 0.087376)
			(type default)
		)
		(layer "F.Cu")
	)
	(gr_line
		(start 22.800056 -332.410054)
		(end 23.876 -332.410054)
		(stroke
			(width 0.087376)
			(type default)
		)
		(layer "F.Cu")
	)
	(gr_line
		(start 22.800056 -330.810108)
		(end 23.88235 -330.810108)
		(stroke
			(width 0.087376)
			(type default)
		)
		(layer "F.Cu")
	)
	(gr_line
		(start 22.800056 -330.010008)
		(end 23.876 -330.010008)
		(stroke
			(width 0.087376)
			(type default)
		)
		(layer "F.Cu")
	)
	(gr_line
		(start 22.800056 -328.410062)
		(end 23.887938 -328.410062)
		(stroke
			(width 0.087376)
			(type default)
		)
		(layer "F.Cu")
	)
	(gr_line
		(start 22.800056 -327.609962)
		(end 23.876 -327.609962)
		(stroke
			(width 0.087376)
			(type default)
		)
		(layer "F.Cu")
	)
	(gr_line
		(start 22.800056 -326.010016)
		(end 23.88235 -326.010016)
		(stroke
			(width 0.087376)
			(type default)
		)
		(layer "F.Cu")
	)
	(gr_line
		(start 22.800056 -325.209916)
		(end 23.876 -325.209916)
		(stroke
			(width 0.087376)
			(type default)
		)
		(layer "F.Cu")
	)
	(gr_line
		(start 22.800056 -323.60997)
		(end 23.882604 -323.60997)
		(stroke
			(width 0.087376)
			(type default)
		)
		(layer "F.Cu")
	)
	(gr_line
		(start 22.800056 -322.810124)
		(end 23.876 -322.810124)
		(stroke
			(width 0.087376)
			(type default)
		)
		(layer "F.Cu")
	)
	(gr_line
		(start 22.800056 -321.209924)
		(end 23.880826 -321.209924)
		(stroke
			(width 0.085598)
			(type default)
		)
		(layer "F.Cu")
	)
	(gr_line
		(start 22.800056 -320.410078)
		(end 23.88108 -320.410078)
		(stroke
			(width 0.085598)
			(type default)
		)
		(layer "F.Cu")
	)
	(gr_line
		(start 22.800056 -247.81002)
		(end 23.882604 -247.81002)
		(stroke
			(width 0.087376)
			(type default)
		)
		(layer "F.Cu")
	)
	(gr_line
		(start 22.800056 -247.00992)
		(end 23.88235 -247.00992)
		(stroke
			(width 0.087376)
			(type default)
		)
		(layer "F.Cu")
	)
	(gr_line
		(start 22.800056 -245.409974)
		(end 23.88235 -245.409974)
		(stroke
			(width 0.087376)
			(type default)
		)
		(layer "F.Cu")
	)
	(gr_line
		(start 22.800056 -244.609874)
		(end 23.876 -244.609874)
		(stroke
			(width 0.087376)
			(type default)
		)
		(layer "F.Cu")
	)
	(gr_line
		(start 22.800056 -243.009928)
		(end 23.944072 -243.009928)
		(stroke
			(width 0.087376)
			(type default)
		)
		(layer "F.Cu")
	)
	(gr_line
		(start 22.800056 -242.210082)
		(end 23.876 -242.210082)
		(stroke
			(width 0.087376)
			(type default)
		)
		(layer "F.Cu")
	)
	(gr_line
		(start 22.800056 -232.609898)
		(end 23.882604 -232.609898)
		(stroke
			(width 0.087376)
			(type default)
		)
		(layer "F.Cu")
	)
	(gr_line
		(start 22.800056 -231.810052)
		(end 23.876 -231.810052)
		(stroke
			(width 0.087376)
			(type default)
		)
		(layer "F.Cu")
	)
	(gr_line
		(start 22.800056 -230.210106)
		(end 23.88235 -230.210106)
		(stroke
			(width 0.087376)
			(type default)
		)
		(layer "F.Cu")
	)
	(gr_line
		(start 22.800056 -229.410006)
		(end 23.876 -229.410006)
		(stroke
			(width 0.087376)
			(type default)
		)
		(layer "F.Cu")
	)
	(gr_line
		(start 22.800056 -227.81006)
		(end 23.876 -227.81006)
		(stroke
			(width 0.087376)
			(type default)
		)
		(layer "F.Cu")
	)
	(gr_line
		(start 22.800056 -227.00996)
		(end 23.876 -227.00996)
		(stroke
			(width 0.087376)
			(type default)
		)
		(layer "F.Cu")
	)
	(gr_line
		(start 22.800056 -225.410014)
		(end 23.890986 -225.410014)
		(stroke
			(width 0.087376)
			(type default)
		)
		(layer "F.Cu")
	)
	(gr_line
		(start 22.800056 -224.609914)
		(end 23.876 -224.609914)
		(stroke
			(width 0.087376)
			(type default)
		)
		(layer "F.Cu")
	)
	(gr_line
		(start 22.800056 -223.009968)
		(end 23.876 -223.009968)
		(stroke
			(width 0.087376)
			(type default)
		)
		(layer "F.Cu")
	)
	(gr_line
		(start 22.800056 -222.209868)
		(end 23.835868 -222.209868)
		(stroke
			(width 0.087376)
			(type default)
		)
		(layer "F.Cu")
	)
	(gr_line
		(start 22.800056 -220.609922)
		(end 23.882604 -220.609922)
		(stroke
			(width 0.087376)
			(type default)
		)
		(layer "F.Cu")
	)
	(gr_line
		(start 22.800056 -219.810076)
		(end 23.876 -219.810076)
		(stroke
			(width 0.087376)
			(type default)
		)
		(layer "F.Cu")
	)
	(gr_line
		(start 22.800056 -218.209876)
		(end 23.880826 -218.209876)
		(stroke
			(width 0.085598)
			(type default)
		)
		(layer "F.Cu")
	)
	(gr_line
		(start 22.800056 -217.41003)
		(end 23.876 -217.41003)
		(stroke
			(width 0.085598)
			(type default)
		)
		(layer "F.Cu")
	)
	(gr_line
		(start 22.800056 -144.809972)
		(end 23.876 -144.809972)
		(stroke
			(width 0.087376)
			(type default)
		)
		(layer "F.Cu")
	)
	(gr_line
		(start 22.800056 -144.009872)
		(end 23.876 -144.009872)
		(stroke
			(width 0.087376)
			(type default)
		)
		(layer "F.Cu")
	)
	(gr_line
		(start 22.800056 -142.409926)
		(end 24.046434 -142.409926)
		(stroke
			(width 0.087376)
			(type default)
		)
		(layer "F.Cu")
	)
	(gr_line
		(start 22.800056 -141.609826)
		(end 24.032718 -141.609826)
		(stroke
			(width 0.087376)
			(type default)
		)
		(layer "F.Cu")
	)
	(gr_line
		(start 22.800056 -140.00988)
		(end 23.882604 -140.00988)
		(stroke
			(width 0.087376)
			(type default)
		)
		(layer "F.Cu")
	)
	(gr_line
		(start 22.800056 -139.210034)
		(end 23.894034 -139.210034)
		(stroke
			(width 0.087376)
			(type default)
		)
		(layer "F.Cu")
	)
	(gr_line
		(start 22.800056 -129.60985)
		(end 23.882604 -129.60985)
		(stroke
			(width 0.087376)
			(type default)
		)
		(layer "F.Cu")
	)
	(gr_line
		(start 22.800056 -128.810004)
		(end 23.876 -128.810004)
		(stroke
			(width 0.087376)
			(type default)
		)
		(layer "F.Cu")
	)
	(gr_line
		(start 22.800056 -127.210058)
		(end 23.970742 -127.210058)
		(stroke
			(width 0.087376)
			(type default)
		)
		(layer "F.Cu")
	)
	(gr_line
		(start 22.800056 -126.409958)
		(end 23.876 -126.409958)
		(stroke
			(width 0.087376)
			(type default)
		)
		(layer "F.Cu")
	)
	(gr_line
		(start 22.800056 -124.810012)
		(end 23.906988 -124.810012)
		(stroke
			(width 0.087376)
			(type default)
		)
		(layer "F.Cu")
	)
	(gr_line
		(start 22.800056 -124.009912)
		(end 23.882604 -124.009912)
		(stroke
			(width 0.087376)
			(type default)
		)
		(layer "F.Cu")
	)
	(gr_line
		(start 22.800056 -122.409966)
		(end 24.031194 -122.409966)
		(stroke
			(width 0.087376)
			(type default)
		)
		(layer "F.Cu")
	)
	(gr_line
		(start 22.800056 -121.609866)
		(end 23.941532 -121.609866)
		(stroke
			(width 0.087376)
			(type default)
		)
		(layer "F.Cu")
	)
	(gr_line
		(start 22.800056 -120.00992)
		(end 23.88235 -120.00992)
		(stroke
			(width 0.087376)
			(type default)
		)
		(layer "F.Cu")
	)
	(gr_line
		(start 22.800056 -119.20982)
		(end 23.876 -119.20982)
		(stroke
			(width 0.087376)
			(type default)
		)
		(layer "F.Cu")
	)
	(gr_line
		(start 22.800056 -117.609874)
		(end 24.007826 -117.609874)
		(stroke
			(width 0.087376)
			(type default)
		)
		(layer "F.Cu")
	)
	(gr_line
		(start 22.800056 -116.810028)
		(end 23.882604 -116.810028)
		(stroke
			(width 0.087376)
			(type default)
		)
		(layer "F.Cu")
	)
	(gr_line
		(start 22.800056 -115.209828)
		(end 23.880826 -115.209828)
		(stroke
			(width 0.085598)
			(type default)
		)
		(layer "F.Cu")
	)
	(gr_line
		(start 22.800056 -114.409982)
		(end 23.88108 -114.409982)
		(stroke
			(width 0.085598)
			(type default)
		)
		(layer "F.Cu")
	)
	(gr_line
		(start 22.800056 -41.809924)
		(end 23.882604 -41.809924)
		(stroke
			(width 0.087376)
			(type default)
		)
		(layer "F.Cu")
	)
	(gr_line
		(start 22.800056 -41.009824)
		(end 23.88235 -41.009824)
		(stroke
			(width 0.087376)
			(type default)
		)
		(layer "F.Cu")
	)
	(gr_line
		(start 22.800056 -39.409878)
		(end 23.88235 -39.409878)
		(stroke
			(width 0.087376)
			(type default)
		)
		(layer "F.Cu")
	)
	(gr_line
		(start 22.800056 -38.609778)
		(end 23.876 -38.609778)
		(stroke
			(width 0.087376)
			(type default)
		)
		(layer "F.Cu")
	)
	(gr_line
		(start 22.800056 -37.009832)
		(end 23.978108 -37.009832)
		(stroke
			(width 0.087376)
			(type default)
		)
		(layer "F.Cu")
	)
	(gr_line
		(start 22.800056 -36.209986)
		(end 23.876 -36.209986)
		(stroke
			(width 0.087376)
			(type default)
		)
		(layer "F.Cu")
	)
	(gr_line
		(start 22.800056 -26.609802)
		(end 23.882604 -26.609802)
		(stroke
			(width 0.087376)
			(type default)
		)
		(layer "F.Cu")
	)
	(gr_line
		(start 22.800056 -25.809956)
		(end 23.876 -25.809956)
		(stroke
			(width 0.087376)
			(type default)
		)
		(layer "F.Cu")
	)
	(gr_line
		(start 22.800056 -24.21001)
		(end 24.03221 -24.21001)
		(stroke
			(width 0.087376)
			(type default)
		)
		(layer "F.Cu")
	)
	(gr_line
		(start 22.800056 -23.40991)
		(end 23.876 -23.40991)
		(stroke
			(width 0.087376)
			(type default)
		)
		(layer "F.Cu")
	)
	(gr_line
		(start 22.800056 -21.809964)
		(end 23.88235 -21.809964)
		(stroke
			(width 0.087376)
			(type default)
		)
		(layer "F.Cu")
	)
	(gr_line
		(start 22.800056 -21.009864)
		(end 23.876 -21.009864)
		(stroke
			(width 0.087376)
			(type default)
		)
		(layer "F.Cu")
	)
	(gr_line
		(start 22.800056 -19.409918)
		(end 23.876 -19.409918)
		(stroke
			(width 0.087376)
			(type default)
		)
		(layer "F.Cu")
	)
	(gr_line
		(start 22.800056 -18.609818)
		(end 23.876 -18.609818)
		(stroke
			(width 0.087376)
			(type default)
		)
		(layer "F.Cu")
	)
	(gr_line
		(start 22.800056 -17.009872)
		(end 23.88235 -17.009872)
		(stroke
			(width 0.087376)
			(type default)
		)
		(layer "F.Cu")
	)
	(gr_line
		(start 22.800056 -16.209772)
		(end 23.876 -16.209772)
		(stroke
			(width 0.087376)
			(type default)
		)
		(layer "F.Cu")
	)
	(gr_line
		(start 22.800056 -14.609826)
		(end 23.985982 -14.609826)
		(stroke
			(width 0.087376)
			(type default)
		)
		(layer "F.Cu")
	)
	(gr_line
		(start 22.800056 -13.80998)
		(end 23.99538 -13.80998)
		(stroke
			(width 0.087376)
			(type default)
		)
		(layer "F.Cu")
	)
	(gr_line
		(start 22.800056 -12.20978)
		(end 23.880826 -12.20978)
		(stroke
			(width 0.085598)
			(type default)
		)
		(layer "F.Cu")
	)
	(gr_line
		(start 22.800056 -11.409934)
		(end 23.855934 -11.409934)
		(stroke
			(width 0.085598)
			(type default)
		)
		(layer "F.Cu")
	)
	(gr_line
		(start 23.835868 -222.209868)
		(end 24.03856 -222.41256)
		(stroke
			(width 0.087376)
			(type default)
		)
		(layer "F.Cu")
	)
	(gr_line
		(start 23.855934 -11.409934)
		(end 23.875746 -11.429746)
		(stroke
			(width 0.085598)
			(type default)
		)
		(layer "F.Cu")
	)
	(gr_line
		(start 23.858982 -426.610018)
		(end 24.053292 -426.415708)
		(stroke
			(width 0.087376)
			(type default)
		)
		(layer "F.Cu")
	)
	(gr_line
		(start 23.876 -453.010016)
		(end 24.061928 -453.195944)
		(stroke
			(width 0.087376)
			(type default)
		)
		(layer "F.Cu")
	)
	(gr_line
		(start 23.876 -436.210202)
		(end 24.058626 -436.027576)
		(stroke
			(width 0.087376)
			(type default)
		)
		(layer "F.Cu")
	)
	(gr_line
		(start 23.876 -435.410102)
		(end 24.058626 -435.592728)
		(stroke
			(width 0.087376)
			(type default)
		)
		(layer "F.Cu")
	)
	(gr_line
		(start 23.876 -433.810156)
		(end 24.058626 -433.62753)
		(stroke
			(width 0.087376)
			(type default)
		)
		(layer "F.Cu")
	)
	(gr_line
		(start 23.876 -433.010056)
		(end 24.058626 -433.192682)
		(stroke
			(width 0.087376)
			(type default)
		)
		(layer "F.Cu")
	)
	(gr_line
		(start 23.876 -430.61001)
		(end 24.061674 -430.795684)
		(stroke
			(width 0.087376)
			(type default)
		)
		(layer "F.Cu")
	)
	(gr_line
		(start 23.876 -428.209964)
		(end 24.061674 -428.395638)
		(stroke
			(width 0.087376)
			(type default)
		)
		(layer "F.Cu")
	)
	(gr_line
		(start 23.876 -347.609922)
		(end 24.061674 -347.795596)
		(stroke
			(width 0.087376)
			(type default)
		)
		(layer "F.Cu")
	)
	(gr_line
		(start 23.876 -346.009976)
		(end 24.058372 -345.827604)
		(stroke
			(width 0.087376)
			(type default)
		)
		(layer "F.Cu")
	)
	(gr_line
		(start 23.876 -345.21013)
		(end 24.058372 -345.392502)
		(stroke
			(width 0.087376)
			(type default)
		)
		(layer "F.Cu")
	)
	(gr_line
		(start 23.876 -334.8101)
		(end 24.061674 -334.995774)
		(stroke
			(width 0.087376)
			(type default)
		)
		(layer "F.Cu")
	)
	(gr_line
		(start 23.876 -332.410054)
		(end 24.24049 -332.65491)
		(stroke
			(width 0.087376)
			(type default)
		)
		(layer "F.Cu")
	)
	(gr_line
		(start 23.876 -330.010008)
		(end 24.061674 -330.195682)
		(stroke
			(width 0.087376)
			(type default)
		)
		(layer "F.Cu")
	)
	(gr_line
		(start 23.876 -327.609962)
		(end 24.064468 -327.79843)
		(stroke
			(width 0.087376)
			(type default)
		)
		(layer "F.Cu")
	)
	(gr_line
		(start 23.876 -325.209916)
		(end 24.061674 -325.39559)
		(stroke
			(width 0.087376)
			(type default)
		)
		(layer "F.Cu")
	)
	(gr_line
		(start 23.876 -322.810124)
		(end 24.061674 -322.995798)
		(stroke
			(width 0.087376)
			(type default)
		)
		(layer "F.Cu")
	)
	(gr_line
		(start 23.876 -244.609874)
		(end 24.061674 -244.795548)
		(stroke
			(width 0.087376)
			(type default)
		)
		(layer "F.Cu")
	)
	(gr_line
		(start 23.876 -242.210082)
		(end 24.092408 -242.42649)
		(stroke
			(width 0.087376)
			(type default)
		)
		(layer "F.Cu")
	)
	(gr_line
		(start 23.876 -231.810052)
		(end 24.061674 -231.995726)
		(stroke
			(width 0.087376)
			(type default)
		)
		(layer "F.Cu")
	)
	(gr_line
		(start 23.876 -229.410006)
		(end 24.061674 -229.59568)
		(stroke
			(width 0.087376)
			(type default)
		)
		(layer "F.Cu")
	)
	(gr_line
		(start 23.876 -227.81006)
		(end 24.058626 -227.627434)
		(stroke
			(width 0.087376)
			(type default)
		)
		(layer "F.Cu")
	)
	(gr_line
		(start 23.876 -227.00996)
		(end 24.058626 -227.192586)
		(stroke
			(width 0.087376)
			(type default)
		)
		(layer "F.Cu")
	)
	(gr_line
		(start 23.876 -224.609914)
		(end 24.065992 -224.799906)
		(stroke
			(width 0.087376)
			(type default)
		)
		(layer "F.Cu")
	)
	(gr_line
		(start 23.876 -223.009968)
		(end 24.03856 -222.847408)
		(stroke
			(width 0.087376)
			(type default)
		)
		(layer "F.Cu")
	)
	(gr_line
		(start 23.876 -219.810076)
		(end 24.061674 -219.99575)
		(stroke
			(width 0.087376)
			(type default)
		)
		(layer "F.Cu")
	)
	(gr_line
		(start 23.876 -217.41003)
		(end 23.885906 -217.419936)
		(stroke
			(width 0.085598)
			(type default)
		)
		(layer "F.Cu")
	)
	(gr_line
		(start 23.876 -144.809972)
		(end 24.058626 -144.627346)
		(stroke
			(width 0.087376)
			(type default)
		)
		(layer "F.Cu")
	)
	(gr_line
		(start 23.876 -144.009872)
		(end 24.058626 -144.192498)
		(stroke
			(width 0.087376)
			(type default)
		)
		(layer "F.Cu")
	)
	(gr_line
		(start 23.876 -128.810004)
		(end 24.061674 -128.995678)
		(stroke
			(width 0.087376)
			(type default)
		)
		(layer "F.Cu")
	)
	(gr_line
		(start 23.876 -126.409958)
		(end 24.225504 -126.654814)
		(stroke
			(width 0.087376)
			(type default)
		)
		(layer "F.Cu")
	)
	(gr_line
		(start 23.876 -119.20982)
		(end 24.061674 -119.395494)
		(stroke
			(width 0.087376)
			(type default)
		)
		(layer "F.Cu")
	)
	(gr_line
		(start 23.876 -38.609778)
		(end 24.061674 -38.795452)
		(stroke
			(width 0.087376)
			(type default)
		)
		(layer "F.Cu")
	)
	(gr_line
		(start 23.876 -36.209986)
		(end 24.238204 -36.454842)
		(stroke
			(width 0.087376)
			(type default)
		)
		(layer "F.Cu")
	)
	(gr_line
		(start 23.876 -25.809956)
		(end 24.061674 -25.99563)
		(stroke
			(width 0.087376)
			(type default)
		)
		(layer "F.Cu")
	)
	(gr_line
		(start 23.876 -23.40991)
		(end 24.275796 -23.654766)
		(stroke
			(width 0.087376)
			(type default)
		)
		(layer "F.Cu")
	)
	(gr_line
		(start 23.876 -21.009864)
		(end 24.061674 -21.195538)
		(stroke
			(width 0.087376)
			(type default)
		)
		(layer "F.Cu")
	)
	(gr_line
		(start 23.876 -19.409918)
		(end 24.058626 -19.227292)
		(stroke
			(width 0.087376)
			(type default)
		)
		(layer "F.Cu")
	)
	(gr_line
		(start 23.876 -18.609818)
		(end 24.058626 -18.792444)
		(stroke
			(width 0.087376)
			(type default)
		)
		(layer "F.Cu")
	)
	(gr_line
		(start 23.876 -16.209772)
		(end 24.061674 -16.395446)
		(stroke
			(width 0.087376)
			(type default)
		)
		(layer "F.Cu")
	)
	(gr_line
		(start 23.880826 -321.209924)
		(end 23.888446 -321.202304)
		(stroke
			(width 0.085598)
			(type default)
		)
		(layer "F.Cu")
	)
	(gr_line
		(start 23.880826 -218.209876)
		(end 23.885906 -218.204796)
		(stroke
			(width 0.085598)
			(type default)
		)
		(layer "F.Cu")
	)
	(gr_line
		(start 23.880826 -115.209828)
		(end 23.888446 -115.202208)
		(stroke
			(width 0.085598)
			(type default)
		)
		(layer "F.Cu")
	)
	(gr_line
		(start 23.88108 -320.410078)
		(end 23.888446 -320.417444)
		(stroke
			(width 0.085598)
			(type default)
		)
		(layer "F.Cu")
	)
	(gr_line
		(start 23.88108 -114.409982)
		(end 23.888446 -114.417348)
		(stroke
			(width 0.085598)
			(type default)
		)
		(layer "F.Cu")
	)
	(gr_line
		(start 23.88235 -431.41011)
		(end 24.061674 -431.230786)
		(stroke
			(width 0.087376)
			(type default)
		)
		(layer "F.Cu")
	)
	(gr_line
		(start 23.88235 -429.010064)
		(end 24.061674 -428.83074)
		(stroke
			(width 0.087376)
			(type default)
		)
		(layer "F.Cu")
	)
	(gr_line
		(start 23.88235 -348.410022)
		(end 24.061674 -348.230698)
		(stroke
			(width 0.087376)
			(type default)
		)
		(layer "F.Cu")
	)
	(gr_line
		(start 23.88235 -330.810108)
		(end 24.061674 -330.630784)
		(stroke
			(width 0.087376)
			(type default)
		)
		(layer "F.Cu")
	)
	(gr_line
		(start 23.88235 -326.010016)
		(end 24.061674 -325.830692)
		(stroke
			(width 0.087376)
			(type default)
		)
		(layer "F.Cu")
	)
	(gr_line
		(start 23.88235 -247.00992)
		(end 24.064976 -247.192546)
		(stroke
			(width 0.087376)
			(type default)
		)
		(layer "F.Cu")
	)
	(gr_line
		(start 23.88235 -245.409974)
		(end 24.061674 -245.23065)
		(stroke
			(width 0.087376)
			(type default)
		)
		(layer "F.Cu")
	)
	(gr_line
		(start 23.88235 -230.210106)
		(end 24.061674 -230.030782)
		(stroke
			(width 0.087376)
			(type default)
		)
		(layer "F.Cu")
	)
	(gr_line
		(start 23.88235 -120.00992)
		(end 24.061674 -119.830596)
		(stroke
			(width 0.087376)
			(type default)
		)
		(layer "F.Cu")
	)
	(gr_line
		(start 23.88235 -41.009824)
		(end 24.064976 -41.19245)
		(stroke
			(width 0.087376)
			(type default)
		)
		(layer "F.Cu")
	)
	(gr_line
		(start 23.88235 -39.409878)
		(end 24.061674 -39.230554)
		(stroke
			(width 0.087376)
			(type default)
		)
		(layer "F.Cu")
	)
	(gr_line
		(start 23.88235 -21.809964)
		(end 24.061674 -21.63064)
		(stroke
			(width 0.087376)
			(type default)
		)
		(layer "F.Cu")
	)
	(gr_line
		(start 23.88235 -17.009872)
		(end 24.061674 -16.830548)
		(stroke
			(width 0.087376)
			(type default)
		)
		(layer "F.Cu")
	)
	(gr_line
		(start 23.882604 -453.810116)
		(end 24.061928 -453.630792)
		(stroke
			(width 0.087376)
			(type default)
		)
		(layer "F.Cu")
	)
	(gr_line
		(start 23.882604 -449.010024)
		(end 24.07539 -448.817238)
		(stroke
			(width 0.087376)
			(type default)
		)
		(layer "F.Cu")
	)
	(gr_line
		(start 23.882604 -425.810172)
		(end 24.053292 -425.98086)
		(stroke
			(width 0.087376)
			(type default)
		)
		(layer "F.Cu")
	)
	(gr_line
		(start 23.882604 -335.609946)
		(end 24.061674 -335.430876)
		(stroke
			(width 0.087376)
			(type default)
		)
		(layer "F.Cu")
	)
	(gr_line
		(start 23.882604 -323.60997)
		(end 24.061674 -323.4309)
		(stroke
			(width 0.087376)
			(type default)
		)
		(layer "F.Cu")
	)
	(gr_line
		(start 23.882604 -247.81002)
		(end 24.064976 -247.627648)
		(stroke
			(width 0.087376)
			(type default)
		)
		(layer "F.Cu")
	)
	(gr_line
		(start 23.882604 -232.609898)
		(end 24.061674 -232.430828)
		(stroke
			(width 0.087376)
			(type default)
		)
		(layer "F.Cu")
	)
	(gr_line
		(start 23.882604 -220.609922)
		(end 24.061674 -220.430852)
		(stroke
			(width 0.087376)
			(type default)
		)
		(layer "F.Cu")
	)
	(gr_line
		(start 23.882604 -140.00988)
		(end 24.070818 -139.821666)
		(stroke
			(width 0.087376)
			(type default)
		)
		(layer "F.Cu")
	)
	(gr_line
		(start 23.882604 -129.60985)
		(end 24.061674 -129.43078)
		(stroke
			(width 0.087376)
			(type default)
		)
		(layer "F.Cu")
	)
	(gr_line
		(start 23.882604 -124.009912)
		(end 24.077422 -124.20473)
		(stroke
			(width 0.087376)
			(type default)
		)
		(layer "F.Cu")
	)
	(gr_line
		(start 23.882604 -116.810028)
		(end 24.26335 -117.054884)
		(stroke
			(width 0.087376)
			(type default)
		)
		(layer "F.Cu")
	)
	(gr_line
		(start 23.882604 -41.809924)
		(end 24.064976 -41.627552)
		(stroke
			(width 0.087376)
			(type default)
		)
		(layer "F.Cu")
	)
	(gr_line
		(start 23.882604 -26.609802)
		(end 24.061674 -26.430732)
		(stroke
			(width 0.087376)
			(type default)
		)
		(layer "F.Cu")
	)
	(gr_line
		(start 23.887938 -328.410062)
		(end 24.064468 -328.233532)
		(stroke
			(width 0.087376)
			(type default)
		)
		(layer "F.Cu")
	)
	(gr_line
		(start 23.88997 -450.60997)
		(end 24.103076 -450.823076)
		(stroke
			(width 0.087376)
			(type default)
		)
		(layer "F.Cu")
	)
	(gr_line
		(start 23.890986 -225.410014)
		(end 24.065992 -225.235008)
		(stroke
			(width 0.087376)
			(type default)
		)
		(layer "F.Cu")
	)
	(gr_line
		(start 23.894034 -139.210034)
		(end 24.070818 -139.386818)
		(stroke
			(width 0.087376)
			(type default)
		)
		(layer "F.Cu")
	)
	(gr_line
		(start 23.903178 -448.210178)
		(end 24.07539 -448.38239)
		(stroke
			(width 0.087376)
			(type default)
		)
		(layer "F.Cu")
	)
	(gr_line
		(start 23.906988 -124.810012)
		(end 24.077422 -124.639578)
		(stroke
			(width 0.087376)
			(type default)
		)
		(layer "F.Cu")
	)
	(gr_line
		(start 23.941532 -121.609866)
		(end 24.313642 -121.854722)
		(stroke
			(width 0.087376)
			(type default)
		)
		(layer "F.Cu")
	)
	(gr_line
		(start 23.944072 -243.009928)
		(end 24.092408 -242.861592)
		(stroke
			(width 0.087376)
			(type default)
		)
		(layer "F.Cu")
	)
	(gr_line
		(start 23.95093 -451.41007)
		(end 24.103076 -451.257924)
		(stroke
			(width 0.087376)
			(type default)
		)
		(layer "F.Cu")
	)
	(gr_line
		(start 23.966678 -350.009968)
		(end 24.149304 -350.192594)
		(stroke
			(width 0.087376)
			(type default)
		)
		(layer "F.Cu")
	)
	(gr_line
		(start 23.966932 -350.810068)
		(end 24.149304 -350.627696)
		(stroke
			(width 0.087376)
			(type default)
		)
		(layer "F.Cu")
	)
	(gr_line
		(start 23.970742 -127.210058)
		(end 24.216106 -126.964694)
		(stroke
			(width 0.087376)
			(type default)
		)
		(layer "F.Cu")
	)
	(gr_line
		(start 23.978108 -37.009832)
		(end 24.223472 -36.764468)
		(stroke
			(width 0.087376)
			(type default)
		)
		(layer "F.Cu")
	)
	(gr_line
		(start 23.985982 -14.609826)
		(end 24.17318 -14.422628)
		(stroke
			(width 0.087376)
			(type default)
		)
		(layer "F.Cu")
	)
	(gr_line
		(start 23.99538 -13.80998)
		(end 24.17318 -13.98778)
		(stroke
			(width 0.087376)
			(type default)
		)
		(layer "F.Cu")
	)
	(gr_line
		(start 23.997666 -333.210154)
		(end 24.242776 -332.965044)
		(stroke
			(width 0.087376)
			(type default)
		)
		(layer "F.Cu")
	)
	(gr_line
		(start 24.003 -438.609994)
		(end 24.185372 -438.427622)
		(stroke
			(width 0.087376)
			(type default)
		)
		(layer "F.Cu")
	)
	(gr_line
		(start 24.003 -437.810148)
		(end 24.185372 -437.99252)
		(stroke
			(width 0.087376)
			(type default)
		)
		(layer "F.Cu")
	)
	(gr_line
		(start 24.007826 -424.209972)
		(end 24.015446 -424.202352)
		(stroke
			(width 0.085598)
			(type default)
		)
		(layer "F.Cu")
	)
	(gr_line
		(start 24.007826 -117.609874)
		(end 24.252936 -117.364764)
		(stroke
			(width 0.087376)
			(type default)
		)
		(layer "F.Cu")
	)
	(gr_line
		(start 24.00808 -423.410126)
		(end 24.015446 -423.417492)
		(stroke
			(width 0.085598)
			(type default)
		)
		(layer "F.Cu")
	)
	(gr_line
		(start 24.031194 -122.409966)
		(end 24.278844 -122.162316)
		(stroke
			(width 0.087376)
			(type default)
		)
		(layer "F.Cu")
	)
	(gr_line
		(start 24.03221 -24.21001)
		(end 24.27732 -23.9649)
		(stroke
			(width 0.087376)
			(type default)
		)
		(layer "F.Cu")
	)
	(gr_line
		(start 24.032718 -141.609826)
		(end 24.222202 -141.79931)
		(stroke
			(width 0.087376)
			(type default)
		)
		(layer "F.Cu")
	)
	(gr_line
		(start 24.046434 -142.409926)
		(end 24.222202 -142.234158)
		(stroke
			(width 0.087376)
			(type default)
		)
		(layer "F.Cu")
	)
	(gr_line
		(start 24.4475 -380.238)
		(end 24.69007 -379.99543)
		(stroke
			(width 0.085598)
			(type default)
		)
		(layer "F.Cu")
	)
	(gr_line
		(start 24.4475 -378.968)
		(end 24.69007 -379.21057)
		(stroke
			(width 0.085598)
			(type default)
		)
		(layer "F.Cu")
	)
	(gr_line
		(start 24.931624 -448.827398)
		(end 25.273 -449.168774)
		(stroke
			(width 0.087376)
			(type default)
		)
		(layer "F.Cu")
	)
	(gr_line
		(start 24.931624 -448.39255)
		(end 25.273 -448.051174)
		(stroke
			(width 0.087376)
			(type default)
		)
		(layer "F.Cu")
	)
	(gr_line
		(start 24.931624 -436.027576)
		(end 25.273 -436.368952)
		(stroke
			(width 0.087376)
			(type default)
		)
		(layer "F.Cu")
	)
	(gr_line
		(start 24.931624 -435.592728)
		(end 25.273 -435.251352)
		(stroke
			(width 0.087376)
			(type default)
		)
		(layer "F.Cu")
	)
	(gr_line
		(start 24.931624 -431.227484)
		(end 25.273 -431.56886)
		(stroke
			(width 0.087376)
			(type default)
		)
		(layer "F.Cu")
	)
	(gr_line
		(start 24.931624 -430.792636)
		(end 25.273 -430.45126)
		(stroke
			(width 0.087376)
			(type default)
		)
		(layer "F.Cu")
	)
	(gr_line
		(start 24.931624 -426.427392)
		(end 25.273 -426.768768)
		(stroke
			(width 0.087376)
			(type default)
		)
		(layer "F.Cu")
	)
	(gr_line
		(start 24.931624 -425.992544)
		(end 25.273 -425.651168)
		(stroke
			(width 0.087376)
			(type default)
		)
		(layer "F.Cu")
	)
	(gr_line
		(start 24.931624 -345.82735)
		(end 25.273 -346.168726)
		(stroke
			(width 0.087376)
			(type default)
		)
		(layer "F.Cu")
	)
	(gr_line
		(start 24.931624 -345.392502)
		(end 25.273 -345.051126)
		(stroke
			(width 0.087376)
			(type default)
		)
		(layer "F.Cu")
	)
	(gr_line
		(start 24.931624 -333.027528)
		(end 25.273 -333.368904)
		(stroke
			(width 0.087376)
			(type default)
		)
		(layer "F.Cu")
	)
	(gr_line
		(start 24.931624 -332.59268)
		(end 25.273 -332.251304)
		(stroke
			(width 0.087376)
			(type default)
		)
		(layer "F.Cu")
	)
	(gr_line
		(start 24.931624 -328.227436)
		(end 25.273 -328.568812)
		(stroke
			(width 0.087376)
			(type default)
		)
		(layer "F.Cu")
	)
	(gr_line
		(start 24.931624 -327.792588)
		(end 25.273 -327.451212)
		(stroke
			(width 0.087376)
			(type default)
		)
		(layer "F.Cu")
	)
	(gr_line
		(start 24.931624 -323.427344)
		(end 25.273 -323.76872)
		(stroke
			(width 0.087376)
			(type default)
		)
		(layer "F.Cu")
	)
	(gr_line
		(start 24.931624 -322.992496)
		(end 25.273 -322.65112)
		(stroke
			(width 0.087376)
			(type default)
		)
		(layer "F.Cu")
	)
	(gr_line
		(start 24.931624 -242.827302)
		(end 25.273 -243.168678)
		(stroke
			(width 0.087376)
			(type default)
		)
		(layer "F.Cu")
	)
	(gr_line
		(start 24.931624 -242.392454)
		(end 25.273 -242.051078)
		(stroke
			(width 0.087376)
			(type default)
		)
		(layer "F.Cu")
	)
	(gr_line
		(start 24.931624 -230.02748)
		(end 25.273 -230.368856)
		(stroke
			(width 0.087376)
			(type default)
		)
		(layer "F.Cu")
	)
	(gr_line
		(start 24.931624 -229.592632)
		(end 25.273 -229.251256)
		(stroke
			(width 0.087376)
			(type default)
		)
		(layer "F.Cu")
	)
	(gr_line
		(start 24.931624 -225.227388)
		(end 25.273 -225.568764)
		(stroke
			(width 0.087376)
			(type default)
		)
		(layer "F.Cu")
	)
	(gr_line
		(start 24.931624 -224.79254)
		(end 25.273 -224.451164)
		(stroke
			(width 0.087376)
			(type default)
		)
		(layer "F.Cu")
	)
	(gr_line
		(start 24.931624 -220.427296)
		(end 25.273 -220.768672)
		(stroke
			(width 0.087376)
			(type default)
		)
		(layer "F.Cu")
	)
	(gr_line
		(start 24.931624 -219.992448)
		(end 25.273 -219.651072)
		(stroke
			(width 0.087376)
			(type default)
		)
		(layer "F.Cu")
	)
	(gr_line
		(start 24.931624 -139.827254)
		(end 25.273 -140.16863)
		(stroke
			(width 0.087376)
			(type default)
		)
		(layer "F.Cu")
	)
	(gr_line
		(start 24.931624 -139.392406)
		(end 25.273 -139.05103)
		(stroke
			(width 0.087376)
			(type default)
		)
		(layer "F.Cu")
	)
	(gr_line
		(start 24.931624 -127.027432)
		(end 25.273 -127.368808)
		(stroke
			(width 0.087376)
			(type default)
		)
		(layer "F.Cu")
	)
	(gr_line
		(start 24.931624 -126.592584)
		(end 25.273 -126.251208)
		(stroke
			(width 0.087376)
			(type default)
		)
		(layer "F.Cu")
	)
	(gr_line
		(start 24.931624 -122.22734)
		(end 25.273 -122.568716)
		(stroke
			(width 0.087376)
			(type default)
		)
		(layer "F.Cu")
	)
	(gr_line
		(start 24.931624 -121.792492)
		(end 25.273 -121.451116)
		(stroke
			(width 0.087376)
			(type default)
		)
		(layer "F.Cu")
	)
	(gr_line
		(start 24.931624 -117.427248)
		(end 25.273 -117.768624)
		(stroke
			(width 0.087376)
			(type default)
		)
		(layer "F.Cu")
	)
	(gr_line
		(start 24.931624 -116.9924)
		(end 25.273 -116.651024)
		(stroke
			(width 0.087376)
			(type default)
		)
		(layer "F.Cu")
	)
	(gr_line
		(start 24.931624 -36.827206)
		(end 25.273 -37.168582)
		(stroke
			(width 0.087376)
			(type default)
		)
		(layer "F.Cu")
	)
	(gr_line
		(start 24.931624 -36.392358)
		(end 25.273 -36.050982)
		(stroke
			(width 0.087376)
			(type default)
		)
		(layer "F.Cu")
	)
	(gr_line
		(start 24.931624 -24.027384)
		(end 25.273 -24.36876)
		(stroke
			(width 0.087376)
			(type default)
		)
		(layer "F.Cu")
	)
	(gr_line
		(start 24.931624 -23.592536)
		(end 25.273 -23.25116)
		(stroke
			(width 0.087376)
			(type default)
		)
		(layer "F.Cu")
	)
	(gr_line
		(start 24.931624 -19.227292)
		(end 25.273 -19.568668)
		(stroke
			(width 0.087376)
			(type default)
		)
		(layer "F.Cu")
	)
	(gr_line
		(start 24.931624 -18.792444)
		(end 25.273 -18.451068)
		(stroke
			(width 0.087376)
			(type default)
		)
		(layer "F.Cu")
	)
	(gr_line
		(start 24.931624 -14.4526)
		(end 25.273 -14.793976)
		(stroke
			(width 0.087376)
			(type default)
		)
		(layer "F.Cu")
	)
	(gr_line
		(start 24.931624 -14.017752)
		(end 25.273 -13.676376)
		(stroke
			(width 0.087376)
			(type default)
		)
		(layer "F.Cu")
	)
	(gr_line
		(start 25.79243 -379.99543)
		(end 26.416 -380.619)
		(stroke
			(width 0.085598)
			(type default)
		)
		(layer "F.Cu")
	)
	(gr_line
		(start 25.79243 -379.21057)
		(end 26.416 -378.587)
		(stroke
			(width 0.085598)
			(type default)
		)
		(layer "F.Cu")
	)
	(gr_line
		(start 26.416 -380.619)
		(end 27.059636 -379.975364)
		(stroke
			(width 0.085598)
			(type default)
		)
		(layer "F.Cu")
	)
	(gr_line
		(start 26.416 -378.587)
		(end 27.154124 -379.325124)
		(stroke
			(width 0.085598)
			(type default)
		)
		(layer "F.Cu")
	)
	(gr_line
		(start 26.481024 -451.227444)
		(end 26.67 -451.41642)
		(stroke
			(width 0.087376)
			(type default)
		)
		(layer "F.Cu")
	)
	(gr_line
		(start 26.481024 -450.792596)
		(end 26.67 -450.60362)
		(stroke
			(width 0.087376)
			(type default)
		)
		(layer "F.Cu")
	)
	(gr_line
		(start 26.481024 -438.427368)
		(end 26.67 -438.616344)
		(stroke
			(width 0.087376)
			(type default)
		)
		(layer "F.Cu")
	)
	(gr_line
		(start 26.481024 -437.99252)
		(end 26.67 -437.803544)
		(stroke
			(width 0.087376)
			(type default)
		)
		(layer "F.Cu")
	)
	(gr_line
		(start 26.481024 -433.62753)
		(end 26.67 -433.816506)
		(stroke
			(width 0.087376)
			(type default)
		)
		(layer "F.Cu")
	)
	(gr_line
		(start 26.481024 -433.192682)
		(end 26.67 -433.003706)
		(stroke
			(width 0.087376)
			(type default)
		)
		(layer "F.Cu")
	)
	(gr_line
		(start 26.481024 -428.827438)
		(end 26.67 -429.016414)
		(stroke
			(width 0.087376)
			(type default)
		)
		(layer "F.Cu")
	)
	(gr_line
		(start 26.481024 -428.39259)
		(end 26.67 -428.203614)
		(stroke
			(width 0.087376)
			(type default)
		)
		(layer "F.Cu")
	)
	(gr_line
		(start 26.481024 -348.227396)
		(end 26.67 -348.416372)
		(stroke
			(width 0.087376)
			(type default)
		)
		(layer "F.Cu")
	)
	(gr_line
		(start 26.481024 -347.792548)
		(end 26.67 -347.603572)
		(stroke
			(width 0.087376)
			(type default)
		)
		(layer "F.Cu")
	)
	(gr_line
		(start 26.481024 -335.42732)
		(end 26.67 -335.616296)
		(stroke
			(width 0.087376)
			(type default)
		)
		(layer "F.Cu")
	)
	(gr_line
		(start 26.481024 -334.992472)
		(end 26.67 -334.803496)
		(stroke
			(width 0.087376)
			(type default)
		)
		(layer "F.Cu")
	)
	(gr_line
		(start 26.481024 -330.627482)
		(end 26.67 -330.816458)
		(stroke
			(width 0.087376)
			(type default)
		)
		(layer "F.Cu")
	)
	(gr_line
		(start 26.481024 -330.192634)
		(end 26.67 -330.003658)
		(stroke
			(width 0.087376)
			(type default)
		)
		(layer "F.Cu")
	)
	(gr_line
		(start 26.481024 -325.82739)
		(end 26.67 -326.016366)
		(stroke
			(width 0.087376)
			(type default)
		)
		(layer "F.Cu")
	)
	(gr_line
		(start 26.481024 -325.392542)
		(end 26.67 -325.203566)
		(stroke
			(width 0.087376)
			(type default)
		)
		(layer "F.Cu")
	)
	(gr_line
		(start 26.481024 -245.227348)
		(end 26.67 -245.416324)
		(stroke
			(width 0.087376)
			(type default)
		)
		(layer "F.Cu")
	)
	(gr_line
		(start 26.481024 -244.7925)
		(end 26.67 -244.603524)
		(stroke
			(width 0.087376)
			(type default)
		)
		(layer "F.Cu")
	)
	(gr_line
		(start 26.481024 -232.427272)
		(end 26.67 -232.616248)
		(stroke
			(width 0.087376)
			(type default)
		)
		(layer "F.Cu")
	)
	(gr_line
		(start 26.481024 -231.992424)
		(end 26.67 -231.803448)
		(stroke
			(width 0.087376)
			(type default)
		)
		(layer "F.Cu")
	)
	(gr_line
		(start 26.481024 -227.627434)
		(end 26.67 -227.81641)
		(stroke
			(width 0.087376)
			(type default)
		)
		(layer "F.Cu")
	)
	(gr_line
		(start 26.481024 -227.192586)
		(end 26.67 -227.00361)
		(stroke
			(width 0.087376)
			(type default)
		)
		(layer "F.Cu")
	)
	(gr_line
		(start 26.481024 -222.827342)
		(end 26.67 -223.016318)
		(stroke
			(width 0.087376)
			(type default)
		)
		(layer "F.Cu")
	)
	(gr_line
		(start 26.481024 -222.392494)
		(end 26.67 -222.203518)
		(stroke
			(width 0.087376)
			(type default)
		)
		(layer "F.Cu")
	)
	(gr_line
		(start 26.481024 -142.2273)
		(end 26.67 -142.416276)
		(stroke
			(width 0.087376)
			(type default)
		)
		(layer "F.Cu")
	)
	(gr_line
		(start 26.481024 -141.792452)
		(end 26.67 -141.603476)
		(stroke
			(width 0.087376)
			(type default)
		)
		(layer "F.Cu")
	)
	(gr_line
		(start 26.481024 -129.427224)
		(end 26.67 -129.6162)
		(stroke
			(width 0.087376)
			(type default)
		)
		(layer "F.Cu")
	)
	(gr_line
		(start 26.481024 -128.992376)
		(end 26.67 -128.8034)
		(stroke
			(width 0.087376)
			(type default)
		)
		(layer "F.Cu")
	)
	(gr_line
		(start 26.481024 -124.627386)
		(end 26.67 -124.816362)
		(stroke
			(width 0.087376)
			(type default)
		)
		(layer "F.Cu")
	)
	(gr_line
		(start 26.481024 -124.192538)
		(end 26.67 -124.003562)
		(stroke
			(width 0.087376)
			(type default)
		)
		(layer "F.Cu")
	)
	(gr_line
		(start 26.481024 -119.827294)
		(end 26.67 -120.01627)
		(stroke
			(width 0.087376)
			(type default)
		)
		(layer "F.Cu")
	)
	(gr_line
		(start 26.481024 -119.392446)
		(end 26.67 -119.20347)
		(stroke
			(width 0.087376)
			(type default)
		)
		(layer "F.Cu")
	)
	(gr_line
		(start 26.481024 -39.227252)
		(end 26.67 -39.416228)
		(stroke
			(width 0.087376)
			(type default)
		)
		(layer "F.Cu")
	)
	(gr_line
		(start 26.481024 -38.792404)
		(end 26.67 -38.603428)
		(stroke
			(width 0.087376)
			(type default)
		)
		(layer "F.Cu")
	)
	(gr_line
		(start 26.481024 -26.427176)
		(end 26.67 -26.616152)
		(stroke
			(width 0.087376)
			(type default)
		)
		(layer "F.Cu")
	)
	(gr_line
		(start 26.481024 -25.992328)
		(end 26.67 -25.803352)
		(stroke
			(width 0.087376)
			(type default)
		)
		(layer "F.Cu")
	)
	(gr_line
		(start 26.481024 -21.627338)
		(end 26.67 -21.816314)
		(stroke
			(width 0.087376)
			(type default)
		)
		(layer "F.Cu")
	)
	(gr_line
		(start 26.481024 -21.19249)
		(end 26.67 -21.003514)
		(stroke
			(width 0.087376)
			(type default)
		)
		(layer "F.Cu")
	)
	(gr_line
		(start 26.481024 -16.827246)
		(end 26.67 -17.016222)
		(stroke
			(width 0.087376)
			(type default)
		)
		(layer "F.Cu")
	)
	(gr_line
		(start 26.481024 -16.392398)
		(end 26.67 -16.203422)
		(stroke
			(width 0.087376)
			(type default)
		)
		(layer "F.Cu")
	)
	(gr_line
		(start 26.87193 -424.267122)
		(end 27.432 -424.827192)
		(stroke
			(width 0.085598)
			(type default)
		)
		(layer "F.Cu")
	)
	(gr_line
		(start 26.87193 -423.482262)
		(end 27.432 -422.922192)
		(stroke
			(width 0.085598)
			(type default)
		)
		(layer "F.Cu")
	)
	(gr_line
		(start 26.87193 -321.267074)
		(end 27.432 -321.827144)
		(stroke
			(width 0.085598)
			(type default)
		)
		(layer "F.Cu")
	)
	(gr_line
		(start 26.87193 -320.482214)
		(end 27.432 -319.922144)
		(stroke
			(width 0.085598)
			(type default)
		)
		(layer "F.Cu")
	)
	(gr_line
		(start 26.87193 -218.267026)
		(end 27.432 -218.827096)
		(stroke
			(width 0.085598)
			(type default)
		)
		(layer "F.Cu")
	)
	(gr_line
		(start 26.87193 -217.482166)
		(end 27.432 -216.922096)
		(stroke
			(width 0.085598)
			(type default)
		)
		(layer "F.Cu")
	)
	(gr_line
		(start 26.87193 -115.266978)
		(end 27.432 -115.827048)
		(stroke
			(width 0.085598)
			(type default)
		)
		(layer "F.Cu")
	)
	(gr_line
		(start 26.87193 -114.482118)
		(end 27.432 -113.922048)
		(stroke
			(width 0.085598)
			(type default)
		)
		(layer "F.Cu")
	)
	(gr_line
		(start 27.059636 -379.975364)
		(end 28.945078 -379.975364)
		(stroke
			(width 0.085598)
			(type default)
		)
		(layer "F.Cu")
	)
	(gr_line
		(start 27.154124 -379.325124)
		(end 28.945078 -379.325124)
		(stroke
			(width 0.085598)
			(type default)
		)
		(layer "F.Cu")
	)
	(gr_line
		(start 27.432 -424.827192)
		(end 27.99207 -424.267122)
		(stroke
			(width 0.085598)
			(type default)
		)
		(layer "F.Cu")
	)
	(gr_line
		(start 27.432 -422.922192)
		(end 27.99207 -423.482262)
		(stroke
			(width 0.085598)
			(type default)
		)
		(layer "F.Cu")
	)
	(gr_line
		(start 27.432 -321.827144)
		(end 27.99207 -321.267074)
		(stroke
			(width 0.085598)
			(type default)
		)
		(layer "F.Cu")
	)
	(gr_line
		(start 27.432 -319.922144)
		(end 27.99207 -320.482214)
		(stroke
			(width 0.085598)
			(type default)
		)
		(layer "F.Cu")
	)
	(gr_line
		(start 27.432 -218.827096)
		(end 27.99207 -218.267026)
		(stroke
			(width 0.085598)
			(type default)
		)
		(layer "F.Cu")
	)
	(gr_line
		(start 27.432 -216.922096)
		(end 27.99207 -217.482166)
		(stroke
			(width 0.085598)
			(type default)
		)
		(layer "F.Cu")
	)
	(gr_line
		(start 27.432 -115.827048)
		(end 27.99207 -115.266978)
		(stroke
			(width 0.085598)
			(type default)
		)
		(layer "F.Cu")
	)
	(gr_line
		(start 27.432 -113.922048)
		(end 27.99207 -114.482118)
		(stroke
			(width 0.085598)
			(type default)
		)
		(layer "F.Cu")
	)
	(gr_line
		(start 28.142184 -140.540486)
		(end 28.267406 -140.665708)
		(stroke
			(width 0.087376)
			(type default)
		)
		(layer "F.Cu")
	)
	(gr_line
		(start 28.142184 -140.01623)
		(end 28.142184 -140.540486)
		(stroke
			(width 0.087376)
			(type default)
		)
		(layer "F.Cu")
	)
	(gr_line
		(start 28.142184 -140.01623)
		(end 28.267406 -139.891008)
		(stroke
			(width 0.087376)
			(type default)
		)
		(layer "F.Cu")
	)
	(gr_line
		(start 28.142184 -139.23645)
		(end 28.267406 -139.361672)
		(stroke
			(width 0.087376)
			(type default)
		)
		(layer "F.Cu")
	)
	(gr_line
		(start 28.142184 -138.712194)
		(end 28.142184 -139.23645)
		(stroke
			(width 0.087376)
			(type default)
		)
		(layer "F.Cu")
	)
	(gr_line
		(start 28.142184 -138.712194)
		(end 28.267406 -138.586972)
		(stroke
			(width 0.087376)
			(type default)
		)
		(layer "F.Cu")
	)
	(gr_line
		(start 28.142184 -137.932414)
		(end 28.267406 -138.057636)
		(stroke
			(width 0.087376)
			(type default)
		)
		(layer "F.Cu")
	)
	(gr_line
		(start 28.142184 -137.408158)
		(end 28.142184 -137.932414)
		(stroke
			(width 0.087376)
			(type default)
		)
		(layer "F.Cu")
	)
	(gr_line
		(start 28.142184 -137.408158)
		(end 28.267406 -137.282936)
		(stroke
			(width 0.087376)
			(type default)
		)
		(layer "F.Cu")
	)
	(gr_line
		(start 28.447238 -346.525088)
		(end 28.57246 -346.65031)
		(stroke
			(width 0.087376)
			(type default)
		)
		(layer "F.Cu")
	)
	(gr_line
		(start 28.447238 -346.000832)
		(end 28.447238 -346.525088)
		(stroke
			(width 0.087376)
			(type default)
		)
		(layer "F.Cu")
	)
	(gr_line
		(start 28.447238 -346.000832)
		(end 28.57246 -345.87561)
		(stroke
			(width 0.087376)
			(type default)
		)
		(layer "F.Cu")
	)
	(gr_line
		(start 28.447238 -345.221052)
		(end 28.57246 -345.346274)
		(stroke
			(width 0.087376)
			(type default)
		)
		(layer "F.Cu")
	)
	(gr_line
		(start 28.447238 -344.696796)
		(end 28.447238 -345.221052)
		(stroke
			(width 0.087376)
			(type default)
		)
		(layer "F.Cu")
	)
	(gr_line
		(start 28.447238 -344.696796)
		(end 28.57246 -344.571574)
		(stroke
			(width 0.087376)
			(type default)
		)
		(layer "F.Cu")
	)
	(gr_line
		(start 28.447238 -343.917016)
		(end 28.57246 -344.042238)
		(stroke
			(width 0.087376)
			(type default)
		)
		(layer "F.Cu")
	)
	(gr_line
		(start 28.447238 -343.39276)
		(end 28.447238 -343.917016)
		(stroke
			(width 0.087376)
			(type default)
		)
		(layer "F.Cu")
	)
	(gr_line
		(start 28.447238 -343.39276)
		(end 28.57246 -343.267538)
		(stroke
			(width 0.087376)
			(type default)
		)
		(layer "F.Cu")
	)
	(gr_line
		(start 28.448 -451.75805)
		(end 28.448 -451.922642)
		(stroke
			(width 0.087376)
			(type default)
		)
		(layer "F.Cu")
	)
	(gr_line
		(start 28.448 -450.454014)
		(end 28.448 -450.618606)
		(stroke
			(width 0.087376)
			(type default)
		)
		(layer "F.Cu")
	)
	(gr_line
		(start 28.448 -449.149978)
		(end 28.448 -449.31457)
		(stroke
			(width 0.087376)
			(type default)
		)
		(layer "F.Cu")
	)
	(gr_line
		(start 28.448 -445.830198)
		(end 28.448 -445.99479)
		(stroke
			(width 0.087376)
			(type default)
		)
		(layer "F.Cu")
	)
	(gr_line
		(start 28.448 -444.526162)
		(end 28.448 -444.690754)
		(stroke
			(width 0.087376)
			(type default)
		)
		(layer "F.Cu")
	)
	(gr_line
		(start 28.575 -339.344)
		(end 28.636976 -339.282024)
		(stroke
			(width 0.087376)
			(type default)
		)
		(layer "F.Cu")
	)
	(gr_line
		(start 28.575 -140.196062)
		(end 28.575 -140.360654)
		(stroke
			(width 0.087376)
			(type default)
		)
		(layer "F.Cu")
	)
	(gr_line
		(start 28.575 -138.892026)
		(end 28.575 -139.056618)
		(stroke
			(width 0.087376)
			(type default)
		)
		(layer "F.Cu")
	)
	(gr_line
		(start 28.575 -137.58799)
		(end 28.575 -137.752582)
		(stroke
			(width 0.087376)
			(type default)
		)
		(layer "F.Cu")
	)
	(gr_line
		(start 28.640532 -133.561074)
		(end 28.640532 -133.738366)
		(stroke
			(width 0.087376)
			(type default)
		)
		(layer "F.Cu")
	)
	(gr_line
		(start 28.640532 -133.561074)
		(end 29.011372 -133.190488)
		(stroke
			(width 0.087376)
			(type default)
		)
		(layer "F.Cu")
	)
	(gr_line
		(start 28.7528 -15.2273)
		(end 29.31287 -15.78737)
		(stroke
			(width 0.085598)
			(type default)
		)
		(layer "F.Cu")
	)
	(gr_line
		(start 28.7528 -15.2273)
		(end 29.31287 -14.66723)
		(stroke
			(width 0.085598)
			(type default)
		)
		(layer "F.Cu")
	)
	(gr_line
		(start 28.755594 -452.227696)
		(end 28.880816 -452.102474)
		(stroke
			(width 0.087376)
			(type default)
		)
		(layer "F.Cu")
	)
	(gr_line
		(start 28.755594 -451.452996)
		(end 28.880816 -451.578218)
		(stroke
			(width 0.087376)
			(type default)
		)
		(layer "F.Cu")
	)
	(gr_line
		(start 28.755594 -450.92366)
		(end 28.880816 -450.798438)
		(stroke
			(width 0.087376)
			(type default)
		)
		(layer "F.Cu")
	)
	(gr_line
		(start 28.755594 -450.14896)
		(end 28.880816 -450.274182)
		(stroke
			(width 0.087376)
			(type default)
		)
		(layer "F.Cu")
	)
	(gr_line
		(start 28.755594 -449.619624)
		(end 28.880816 -449.494402)
		(stroke
			(width 0.087376)
			(type default)
		)
		(layer "F.Cu")
	)
	(gr_line
		(start 28.755594 -448.844924)
		(end 28.880816 -448.970146)
		(stroke
			(width 0.087376)
			(type default)
		)
		(layer "F.Cu")
	)
	(gr_line
		(start 28.755594 -446.299844)
		(end 28.880816 -446.174622)
		(stroke
			(width 0.087376)
			(type default)
		)
		(layer "F.Cu")
	)
	(gr_line
		(start 28.755594 -445.525144)
		(end 28.880816 -445.650366)
		(stroke
			(width 0.087376)
			(type default)
		)
		(layer "F.Cu")
	)
	(gr_line
		(start 28.755594 -444.995808)
		(end 28.880816 -444.870586)
		(stroke
			(width 0.087376)
			(type default)
		)
		(layer "F.Cu")
	)
	(gr_line
		(start 28.755594 -444.221108)
		(end 28.880816 -444.34633)
		(stroke
			(width 0.087376)
			(type default)
		)
		(layer "F.Cu")
	)
	(gr_line
		(start 28.880054 -346.180664)
		(end 28.880054 -346.345256)
		(stroke
			(width 0.087376)
			(type default)
		)
		(layer "F.Cu")
	)
	(gr_line
		(start 28.880054 -344.876628)
		(end 28.880054 -345.04122)
		(stroke
			(width 0.087376)
			(type default)
		)
		(layer "F.Cu")
	)
	(gr_line
		(start 28.880054 -343.572592)
		(end 28.880054 -343.737184)
		(stroke
			(width 0.087376)
			(type default)
		)
		(layer "F.Cu")
	)
	(gr_line
		(start 28.880816 -451.578218)
		(end 28.880816 -452.102474)
		(stroke
			(width 0.087376)
			(type default)
		)
		(layer "F.Cu")
	)
	(gr_line
		(start 28.880816 -450.274182)
		(end 28.880816 -450.798438)
		(stroke
			(width 0.087376)
			(type default)
		)
		(layer "F.Cu")
	)
	(gr_line
		(start 28.880816 -448.970146)
		(end 28.880816 -449.494402)
		(stroke
			(width 0.087376)
			(type default)
		)
		(layer "F.Cu")
	)
	(gr_line
		(start 28.880816 -445.650366)
		(end 28.880816 -446.174622)
		(stroke
			(width 0.087376)
			(type default)
		)
		(layer "F.Cu")
	)
	(gr_line
		(start 28.880816 -444.34633)
		(end 28.880816 -444.870586)
		(stroke
			(width 0.087376)
			(type default)
		)
		(layer "F.Cu")
	)
	(gr_line
		(start 28.945586 -338.792566)
		(end 28.945586 -338.970112)
		(stroke
			(width 0.087376)
			(type default)
		)
		(layer "F.Cu")
	)
	(gr_line
		(start 28.945586 -338.792566)
		(end 29.316426 -338.42198)
		(stroke
			(width 0.087376)
			(type default)
		)
		(layer "F.Cu")
	)
	(gr_line
		(start 29.011372 -133.190488)
		(end 29.18841 -133.190488)
		(stroke
			(width 0.087376)
			(type default)
		)
		(layer "F.Cu")
	)
	(gr_line
		(start 29.0322 -18.01876)
		(end 29.27477 -18.26133)
		(stroke
			(width 0.085598)
			(type default)
		)
		(layer "F.Cu")
	)
	(gr_line
		(start 29.0322 -17.5895)
		(end 29.0322 -18.01876)
		(stroke
			(width 0.085598)
			(type default)
		)
		(layer "F.Cu")
	)
	(gr_line
		(start 29.0322 -16.7005)
		(end 29.27477 -16.45793)
		(stroke
			(width 0.085598)
			(type default)
		)
		(layer "F.Cu")
	)
	(gr_line
		(start 29.073856 -133.740144)
		(end 29.190188 -133.623812)
		(stroke
			(width 0.087376)
			(type default)
		)
		(layer "F.Cu")
	)
	(gr_line
		(start 29.15793 -424.19143)
		(end 29.4005 -424.434)
		(stroke
			(width 0.085598)
			(type default)
		)
		(layer "F.Cu")
	)
	(gr_line
		(start 29.15793 -423.40657)
		(end 29.4005 -423.164)
		(stroke
			(width 0.085598)
			(type default)
		)
		(layer "F.Cu")
	)
	(gr_line
		(start 29.15793 -321.19443)
		(end 29.4005 -321.437)
		(stroke
			(width 0.085598)
			(type default)
		)
		(layer "F.Cu")
	)
	(gr_line
		(start 29.15793 -320.40957)
		(end 29.4005 -320.167)
		(stroke
			(width 0.085598)
			(type default)
		)
		(layer "F.Cu")
	)
	(gr_line
		(start 29.15793 -115.20043)
		(end 29.4005 -115.443)
		(stroke
			(width 0.085598)
			(type default)
		)
		(layer "F.Cu")
	)
	(gr_line
		(start 29.15793 -114.41557)
		(end 29.4005 -114.173)
		(stroke
			(width 0.085598)
			(type default)
		)
		(layer "F.Cu")
	)
	(gr_line
		(start 29.160978 -218.200478)
		(end 29.4005 -218.44)
		(stroke
			(width 0.085598)
			(type default)
		)
		(layer "F.Cu")
	)
	(gr_line
		(start 29.160978 -217.415618)
		(end 29.4005 -217.176096)
		(stroke
			(width 0.085598)
			(type default)
		)
		(layer "F.Cu")
	)
	(gr_line
		(start 29.188664 -339.161882)
		(end 29.495242 -338.855304)
		(stroke
			(width 0.087376)
			(type default)
		)
		(layer "F.Cu")
	)
	(gr_line
		(start 29.19095 -245.40591)
		(end 29.19095 -245.582948)
		(stroke
			(width 0.087376)
			(type default)
		)
		(layer "F.Cu")
	)
	(gr_line
		(start 29.19095 -245.40591)
		(end 29.561536 -245.03507)
		(stroke
			(width 0.087376)
			(type default)
		)
		(layer "F.Cu")
	)
	(gr_line
		(start 29.316426 -338.42198)
		(end 29.493718 -338.42198)
		(stroke
			(width 0.087376)
			(type default)
		)
		(layer "F.Cu")
	)
	(gr_line
		(start 29.4005 -217.17)
		(end 29.4005 -217.176096)
		(stroke
			(width 0.085598)
			(type default)
		)
		(layer "F.Cu")
	)
	(gr_line
		(start 29.561536 -245.03507)
		(end 29.738828 -245.03507)
		(stroke
			(width 0.087376)
			(type default)
		)
		(layer "F.Cu")
	)
	(gr_line
		(start 29.562806 -132.639054)
		(end 29.562806 -132.816092)
		(stroke
			(width 0.087376)
			(type default)
		)
		(layer "F.Cu")
	)
	(gr_line
		(start 29.562806 -132.639054)
		(end 29.933392 -132.268214)
		(stroke
			(width 0.087376)
			(type default)
		)
		(layer "F.Cu")
	)
	(gr_line
		(start 29.624274 -245.584726)
		(end 29.740606 -245.468394)
		(stroke
			(width 0.087376)
			(type default)
		)
		(layer "F.Cu")
	)
	(gr_line
		(start 29.816298 -391.544302)
		(end 29.816298 -392.1125)
		(stroke
			(width 0.085598)
			(type default)
		)
		(layer "F.Cu")
	)
	(gr_line
		(start 29.816298 -391.544302)
		(end 29.89707 -391.46353)
		(stroke
			(width 0.085598)
			(type default)
		)
		(layer "F.Cu")
	)
	(gr_line
		(start 29.816298 -390.597898)
		(end 29.89707 -390.67867)
		(stroke
			(width 0.085598)
			(type default)
		)
		(layer "F.Cu")
	)
	(gr_line
		(start 29.816298 -390.2075)
		(end 29.816298 -390.597898)
		(stroke
			(width 0.085598)
			(type default)
		)
		(layer "F.Cu")
	)
	(gr_line
		(start 29.86786 -337.870546)
		(end 29.86786 -338.047838)
		(stroke
			(width 0.087376)
			(type default)
		)
		(layer "F.Cu")
	)
	(gr_line
		(start 29.86786 -337.870546)
		(end 30.238446 -337.499706)
		(stroke
			(width 0.087376)
			(type default)
		)
		(layer "F.Cu")
	)
	(gr_line
		(start 29.933392 -132.268214)
		(end 30.110684 -132.268214)
		(stroke
			(width 0.087376)
			(type default)
		)
		(layer "F.Cu")
	)
	(gr_line
		(start 29.99613 -132.81787)
		(end 30.112462 -132.701538)
		(stroke
			(width 0.087376)
			(type default)
		)
		(layer "F.Cu")
	)
	(gr_line
		(start 30.05963 -16.45793)
		(end 30.3022 -16.7005)
		(stroke
			(width 0.085598)
			(type default)
		)
		(layer "F.Cu")
	)
	(gr_line
		(start 30.059884 -18.26133)
		(end 30.3022 -18.019014)
		(stroke
			(width 0.085598)
			(type default)
		)
		(layer "F.Cu")
	)
	(gr_line
		(start 30.09773 -15.78737)
		(end 30.6578 -15.2273)
		(stroke
			(width 0.085598)
			(type default)
		)
		(layer "F.Cu")
	)
	(gr_line
		(start 30.09773 -14.66723)
		(end 30.6578 -15.2273)
		(stroke
			(width 0.085598)
			(type default)
		)
		(layer "F.Cu")
	)
	(gr_line
		(start 30.110938 -338.239608)
		(end 30.608524 -337.742276)
		(stroke
			(width 0.087376)
			(type default)
		)
		(layer "F.Cu")
	)
	(gr_line
		(start 30.11297 -244.48389)
		(end 30.11297 -244.660928)
		(stroke
			(width 0.087376)
			(type default)
		)
		(layer "F.Cu")
	)
	(gr_line
		(start 30.11297 -244.48389)
		(end 30.48381 -244.11305)
		(stroke
			(width 0.087376)
			(type default)
		)
		(layer "F.Cu")
	)
	(gr_line
		(start 30.238446 -337.499706)
		(end 30.415992 -337.499706)
		(stroke
			(width 0.087376)
			(type default)
		)
		(layer "F.Cu")
	)
	(gr_line
		(start 30.2895 -424.434)
		(end 30.53207 -424.19143)
		(stroke
			(width 0.085598)
			(type default)
		)
		(layer "F.Cu")
	)
	(gr_line
		(start 30.2895 -423.164)
		(end 30.53207 -423.40657)
		(stroke
			(width 0.085598)
			(type default)
		)
		(layer "F.Cu")
	)
	(gr_line
		(start 30.2895 -321.437)
		(end 30.53207 -321.19443)
		(stroke
			(width 0.085598)
			(type default)
		)
		(layer "F.Cu")
	)
	(gr_line
		(start 30.2895 -320.167)
		(end 30.53207 -320.40957)
		(stroke
			(width 0.085598)
			(type default)
		)
		(layer "F.Cu")
	)
	(gr_line
		(start 30.2895 -218.44)
		(end 30.53207 -218.19743)
		(stroke
			(width 0.085598)
			(type default)
		)
		(layer "F.Cu")
	)
	(gr_line
		(start 30.2895 -217.17)
		(end 30.53207 -217.41257)
		(stroke
			(width 0.085598)
			(type default)
		)
		(layer "F.Cu")
	)
	(gr_line
		(start 30.2895 -115.443)
		(end 30.53207 -115.20043)
		(stroke
			(width 0.085598)
			(type default)
		)
		(layer "F.Cu")
	)
	(gr_line
		(start 30.2895 -114.173)
		(end 30.53207 -114.41557)
		(stroke
			(width 0.085598)
			(type default)
		)
		(layer "F.Cu")
	)
	(gr_line
		(start 30.3022 -17.5895)
		(end 30.3022 -18.019014)
		(stroke
			(width 0.085598)
			(type default)
		)
		(layer "F.Cu")
	)
	(gr_line
		(start 30.48381 -244.11305)
		(end 30.660848 -244.11305)
		(stroke
			(width 0.087376)
			(type default)
		)
		(layer "F.Cu")
	)
	(gr_line
		(start 30.546294 -244.662706)
		(end 30.662626 -244.546374)
		(stroke
			(width 0.087376)
			(type default)
		)
		(layer "F.Cu")
	)
	(gr_line
		(start 31.01213 -492.28883)
		(end 31.2547 -492.5314)
		(stroke
			(width 0.085598)
			(type default)
		)
		(layer "F.Cu")
	)
	(gr_line
		(start 31.01213 -491.50397)
		(end 31.2547 -491.2614)
		(stroke
			(width 0.085598)
			(type default)
		)
		(layer "F.Cu")
	)
	(gr_line
		(start 31.03499 -243.561616)
		(end 31.03499 -243.738908)
		(stroke
			(width 0.087376)
			(type default)
		)
		(layer "F.Cu")
	)
	(gr_line
		(start 31.03499 -243.561616)
		(end 31.40583 -243.19103)
		(stroke
			(width 0.087376)
			(type default)
		)
		(layer "F.Cu")
	)
	(gr_line
		(start 31.202376 -424.7896)
		(end 31.581852 -424.7896)
		(stroke
			(width 0.085598)
			(type default)
		)
		(layer "F.Cu")
	)
	(gr_line
		(start 31.356046 -28.171394)
		(end 31.481268 -28.296616)
		(stroke
			(width 0.087376)
			(type default)
		)
		(layer "F.Cu")
	)
	(gr_line
		(start 31.40583 -243.19103)
		(end 31.582868 -243.19103)
		(stroke
			(width 0.087376)
			(type default)
		)
		(layer "F.Cu")
	)
	(gr_line
		(start 31.44393 -391.55243)
		(end 31.6865 -391.795)
		(stroke
			(width 0.085598)
			(type default)
		)
		(layer "F.Cu")
	)
	(gr_line
		(start 31.44393 -390.76757)
		(end 31.6865 -390.525)
		(stroke
			(width 0.085598)
			(type default)
		)
		(layer "F.Cu")
	)
	(gr_line
		(start 31.44393 -288.55543)
		(end 31.6865 -288.798)
		(stroke
			(width 0.085598)
			(type default)
		)
		(layer "F.Cu")
	)
	(gr_line
		(start 31.44393 -287.77057)
		(end 31.6865 -287.528)
		(stroke
			(width 0.085598)
			(type default)
		)
		(layer "F.Cu")
	)
	(gr_line
		(start 31.44393 -185.55843)
		(end 31.6865 -185.801)
		(stroke
			(width 0.085598)
			(type default)
		)
		(layer "F.Cu")
	)
	(gr_line
		(start 31.44393 -184.77357)
		(end 31.6865 -184.531)
		(stroke
			(width 0.085598)
			(type default)
		)
		(layer "F.Cu")
	)
	(gr_line
		(start 31.44393 -82.56143)
		(end 31.6865 -82.804)
		(stroke
			(width 0.085598)
			(type default)
		)
		(layer "F.Cu")
	)
	(gr_line
		(start 31.44393 -81.77657)
		(end 31.6865 -81.534)
		(stroke
			(width 0.085598)
			(type default)
		)
		(layer "F.Cu")
	)
	(gr_line
		(start 31.468314 -243.740686)
		(end 31.584646 -243.624354)
		(stroke
			(width 0.087376)
			(type default)
		)
		(layer "F.Cu")
	)
	(gr_line
		(start 31.481268 -28.296616)
		(end 32.005524 -28.296616)
		(stroke
			(width 0.087376)
			(type default)
		)
		(layer "F.Cu")
	)
	(gr_line
		(start 31.496 -136.416542)
		(end 31.684976 -136.227566)
		(stroke
			(width 0.087376)
			(type default)
		)
		(layer "F.Cu")
	)
	(gr_line
		(start 31.496 -135.603742)
		(end 31.684976 -135.792718)
		(stroke
			(width 0.087376)
			(type default)
		)
		(layer "F.Cu")
	)
	(gr_line
		(start 31.496 -33.415986)
		(end 31.684976 -33.22701)
		(stroke
			(width 0.087376)
			(type default)
		)
		(layer "F.Cu")
	)
	(gr_line
		(start 31.496 -32.603186)
		(end 31.684976 -32.792162)
		(stroke
			(width 0.087376)
			(type default)
		)
		(layer "F.Cu")
	)
	(gr_line
		(start 31.581852 -424.7896)
		(end 31.63697 -424.734482)
		(stroke
			(width 0.085598)
			(type default)
		)
		(layer "F.Cu")
	)
	(gr_line
		(start 31.6611 -27.8638)
		(end 31.825692 -27.8638)
		(stroke
			(width 0.087376)
			(type default)
		)
		(layer "F.Cu")
	)
	(gr_line
		(start 31.75 -445.397636)
		(end 31.938976 -445.20866)
		(stroke
			(width 0.087376)
			(type default)
		)
		(layer "F.Cu")
	)
	(gr_line
		(start 31.75 -444.584836)
		(end 31.938976 -444.773812)
		(stroke
			(width 0.087376)
			(type default)
		)
		(layer "F.Cu")
	)
	(gr_line
		(start 32.005524 -28.296616)
		(end 32.130746 -28.171394)
		(stroke
			(width 0.087376)
			(type default)
		)
		(layer "F.Cu")
	)
	(gr_line
		(start 32.055054 -218.255088)
		(end 32.060134 -218.260168)
		(stroke
			(width 0.085598)
			(type default)
		)
		(layer "F.Cu")
	)
	(gr_line
		(start 32.055054 -217.469974)
		(end 32.060134 -217.464894)
		(stroke
			(width 0.085598)
			(type default)
		)
		(layer "F.Cu")
	)
	(gr_line
		(start 32.060134 -218.260168)
		(end 32.060134 -218.7575)
		(stroke
			(width 0.085598)
			(type default)
		)
		(layer "F.Cu")
	)
	(gr_line
		(start 32.060134 -216.8525)
		(end 32.060134 -217.464894)
		(stroke
			(width 0.085598)
			(type default)
		)
		(layer "F.Cu")
	)
	(gr_line
		(start 32.1437 -492.5314)
		(end 32.38627 -492.28883)
		(stroke
			(width 0.085598)
			(type default)
		)
		(layer "F.Cu")
	)
	(gr_line
		(start 32.1437 -491.2614)
		(end 32.38627 -491.50397)
		(stroke
			(width 0.085598)
			(type default)
		)
		(layer "F.Cu")
	)
	(gr_line
		(start 32.422084 -424.734482)
		(end 32.477202 -424.7896)
		(stroke
			(width 0.085598)
			(type default)
		)
		(layer "F.Cu")
	)
	(gr_line
		(start 32.477202 -424.7896)
		(end 33.107376 -424.7896)
		(stroke
			(width 0.085598)
			(type default)
		)
		(layer "F.Cu")
	)
	(gr_line
		(start 32.5755 -391.795)
		(end 32.81807 -391.55243)
		(stroke
			(width 0.085598)
			(type default)
		)
		(layer "F.Cu")
	)
	(gr_line
		(start 32.5755 -390.525)
		(end 32.81807 -390.76757)
		(stroke
			(width 0.085598)
			(type default)
		)
		(layer "F.Cu")
	)
	(gr_line
		(start 32.5755 -288.798)
		(end 32.81807 -288.55543)
		(stroke
			(width 0.085598)
			(type default)
		)
		(layer "F.Cu")
	)
	(gr_line
		(start 32.5755 -287.528)
		(end 32.81807 -287.77057)
		(stroke
			(width 0.085598)
			(type default)
		)
		(layer "F.Cu")
	)
	(gr_line
		(start 32.5755 -185.801)
		(end 32.81807 -185.55843)
		(stroke
			(width 0.085598)
			(type default)
		)
		(layer "F.Cu")
	)
	(gr_line
		(start 32.5755 -184.531)
		(end 32.81807 -184.77357)
		(stroke
			(width 0.085598)
			(type default)
		)
		(layer "F.Cu")
	)
	(gr_line
		(start 32.5755 -82.804)
		(end 32.81807 -82.56143)
		(stroke
			(width 0.085598)
			(type default)
		)
		(layer "F.Cu")
	)
	(gr_line
		(start 32.5755 -81.534)
		(end 32.81807 -81.77657)
		(stroke
			(width 0.085598)
			(type default)
		)
		(layer "F.Cu")
	)
	(gr_line
		(start 32.660082 -28.171394)
		(end 32.785304 -28.296616)
		(stroke
			(width 0.087376)
			(type default)
		)
		(layer "F.Cu")
	)
	(gr_line
		(start 32.785304 -28.296616)
		(end 33.30956 -28.296616)
		(stroke
			(width 0.087376)
			(type default)
		)
		(layer "F.Cu")
	)
	(gr_line
		(start 32.893 -342.397334)
		(end 33.081976 -342.208358)
		(stroke
			(width 0.087376)
			(type default)
		)
		(layer "F.Cu")
	)
	(gr_line
		(start 32.893 -341.584534)
		(end 33.081976 -341.77351)
		(stroke
			(width 0.087376)
			(type default)
		)
		(layer "F.Cu")
	)
	(gr_line
		(start 32.91586 -492.282734)
		(end 33.47593 -492.842804)
		(stroke
			(width 0.085598)
			(type default)
		)
		(layer "F.Cu")
	)
	(gr_line
		(start 32.91586 -491.497874)
		(end 33.47593 -490.937804)
		(stroke
			(width 0.085598)
			(type default)
		)
		(layer "F.Cu")
	)
	(gr_line
		(start 32.965136 -27.8638)
		(end 33.129728 -27.8638)
		(stroke
			(width 0.087376)
			(type default)
		)
		(layer "F.Cu")
	)
	(gr_line
		(start 33.009332 -334.909922)
		(end 33.071308 -334.847946)
		(stroke
			(width 0.087376)
			(type default)
		)
		(layer "F.Cu")
	)
	(gr_line
		(start 33.15462 -33.165034)
		(end 33.279842 -33.290256)
		(stroke
			(width 0.087376)
			(type default)
		)
		(layer "F.Cu")
	)
	(gr_line
		(start 33.222946 -443.249558)
		(end 33.222946 -443.41415)
		(stroke
			(width 0.087376)
			(type default)
		)
		(layer "F.Cu")
	)
	(gr_line
		(start 33.222946 -441.945522)
		(end 33.222946 -442.110114)
		(stroke
			(width 0.087376)
			(type default)
		)
		(layer "F.Cu")
	)
	(gr_line
		(start 33.222946 -440.641486)
		(end 33.222946 -440.806078)
		(stroke
			(width 0.087376)
			(type default)
		)
		(layer "F.Cu")
	)
	(gr_line
		(start 33.222946 -436.310278)
		(end 33.284922 -436.248302)
		(stroke
			(width 0.087376)
			(type default)
		)
		(layer "F.Cu")
	)
	(gr_line
		(start 33.279842 -33.290256)
		(end 33.804098 -33.290256)
		(stroke
			(width 0.087376)
			(type default)
		)
		(layer "F.Cu")
	)
	(gr_line
		(start 33.30956 -28.296616)
		(end 33.434782 -28.171394)
		(stroke
			(width 0.087376)
			(type default)
		)
		(layer "F.Cu")
	)
	(gr_line
		(start 33.382458 -241.214148)
		(end 33.382458 -241.39144)
		(stroke
			(width 0.087376)
			(type default)
		)
		(layer "F.Cu")
	)
	(gr_line
		(start 33.382458 -241.214148)
		(end 33.753298 -240.843562)
		(stroke
			(width 0.087376)
			(type default)
		)
		(layer "F.Cu")
	)
	(gr_line
		(start 33.459674 -32.85744)
		(end 33.624266 -32.85744)
		(stroke
			(width 0.087376)
			(type default)
		)
		(layer "F.Cu")
	)
	(gr_line
		(start 33.47593 -492.842804)
		(end 34.036 -492.282734)
		(stroke
			(width 0.085598)
			(type default)
		)
		(layer "F.Cu")
	)
	(gr_line
		(start 33.47593 -490.937804)
		(end 34.036 -491.497874)
		(stroke
			(width 0.085598)
			(type default)
		)
		(layer "F.Cu")
	)
	(gr_line
		(start 33.53054 -443.719204)
		(end 33.655762 -443.593982)
		(stroke
			(width 0.087376)
			(type default)
		)
		(layer "F.Cu")
	)
	(gr_line
		(start 33.53054 -442.944504)
		(end 33.655762 -443.069726)
		(stroke
			(width 0.087376)
			(type default)
		)
		(layer "F.Cu")
	)
	(gr_line
		(start 33.53054 -442.415168)
		(end 33.655762 -442.289946)
		(stroke
			(width 0.087376)
			(type default)
		)
		(layer "F.Cu")
	)
	(gr_line
		(start 33.53054 -441.640468)
		(end 33.655762 -441.76569)
		(stroke
			(width 0.087376)
			(type default)
		)
		(layer "F.Cu")
	)
	(gr_line
		(start 33.53054 -441.111132)
		(end 33.655762 -440.98591)
		(stroke
			(width 0.087376)
			(type default)
		)
		(layer "F.Cu")
	)
	(gr_line
		(start 33.53054 -440.336432)
		(end 33.655762 -440.461654)
		(stroke
			(width 0.087376)
			(type default)
		)
		(layer "F.Cu")
	)
	(gr_line
		(start 33.655762 -443.069726)
		(end 33.655762 -443.593982)
		(stroke
			(width 0.087376)
			(type default)
		)
		(layer "F.Cu")
	)
	(gr_line
		(start 33.655762 -441.76569)
		(end 33.655762 -442.289946)
		(stroke
			(width 0.087376)
			(type default)
		)
		(layer "F.Cu")
	)
	(gr_line
		(start 33.655762 -440.461654)
		(end 33.655762 -440.98591)
		(stroke
			(width 0.087376)
			(type default)
		)
		(layer "F.Cu")
	)
	(gr_line
		(start 33.698688 -134.903718)
		(end 33.698688 -135.080756)
		(stroke
			(width 0.087376)
			(type default)
		)
		(layer "F.Cu")
	)
	(gr_line
		(start 33.698688 -134.903718)
		(end 34.069274 -134.532878)
		(stroke
			(width 0.087376)
			(type default)
		)
		(layer "F.Cu")
	)
	(gr_line
		(start 33.753298 -240.843562)
		(end 33.930336 -240.843562)
		(stroke
			(width 0.087376)
			(type default)
		)
		(layer "F.Cu")
	)
	(gr_line
		(start 33.804098 -33.290256)
		(end 33.92932 -33.165034)
		(stroke
			(width 0.087376)
			(type default)
		)
		(layer "F.Cu")
	)
	(gr_line
		(start 33.815782 -241.393218)
		(end 33.932114 -241.276886)
		(stroke
			(width 0.087376)
			(type default)
		)
		(layer "F.Cu")
	)
	(gr_line
		(start 33.90646 -391.517886)
		(end 34.46653 -392.077956)
		(stroke
			(width 0.085598)
			(type default)
		)
		(layer "F.Cu")
	)
	(gr_line
		(start 33.90646 -390.733026)
		(end 34.46653 -390.172956)
		(stroke
			(width 0.085598)
			(type default)
		)
		(layer "F.Cu")
	)
	(gr_line
		(start 33.95726 -288.517838)
		(end 34.51733 -289.077908)
		(stroke
			(width 0.085598)
			(type default)
		)
		(layer "F.Cu")
	)
	(gr_line
		(start 33.95726 -287.732978)
		(end 34.51733 -287.172908)
		(stroke
			(width 0.085598)
			(type default)
		)
		(layer "F.Cu")
	)
	(gr_line
		(start 33.964118 -28.171394)
		(end 34.08934 -28.296616)
		(stroke
			(width 0.087376)
			(type default)
		)
		(layer "F.Cu")
	)
	(gr_line
		(start 34.069274 -134.532878)
		(end 34.246566 -134.532878)
		(stroke
			(width 0.087376)
			(type default)
		)
		(layer "F.Cu")
	)
	(gr_line
		(start 34.08426 -185.51779)
		(end 34.64433 -186.07786)
		(stroke
			(width 0.085598)
			(type default)
		)
		(layer "F.Cu")
	)
	(gr_line
		(start 34.08426 -184.73293)
		(end 34.64433 -184.17286)
		(stroke
			(width 0.085598)
			(type default)
		)
		(layer "F.Cu")
	)
	(gr_line
		(start 34.08934 -28.296616)
		(end 34.613596 -28.296616)
		(stroke
			(width 0.087376)
			(type default)
		)
		(layer "F.Cu")
	)
	(gr_line
		(start 34.132012 -135.082534)
		(end 34.248344 -134.966202)
		(stroke
			(width 0.087376)
			(type default)
		)
		(layer "F.Cu")
	)
	(gr_line
		(start 34.18586 -82.517742)
		(end 34.74593 -83.077812)
		(stroke
			(width 0.085598)
			(type default)
		)
		(layer "F.Cu")
	)
	(gr_line
		(start 34.18586 -81.732882)
		(end 34.74593 -81.172812)
		(stroke
			(width 0.085598)
			(type default)
		)
		(layer "F.Cu")
	)
	(gr_line
		(start 34.269172 -27.8638)
		(end 34.433764 -27.8638)
		(stroke
			(width 0.087376)
			(type default)
		)
		(layer "F.Cu")
	)
	(gr_line
		(start 34.304732 -240.292128)
		(end 34.304732 -240.469166)
		(stroke
			(width 0.087376)
			(type default)
		)
		(layer "F.Cu")
	)
	(gr_line
		(start 34.304732 -240.292128)
		(end 34.675318 -239.921542)
		(stroke
			(width 0.087376)
			(type default)
		)
		(layer "F.Cu")
	)
	(gr_line
		(start 34.448242 -435.084982)
		(end 34.564828 -434.968396)
		(stroke
			(width 0.087376)
			(type default)
		)
		(layer "F.Cu")
	)
	(gr_line
		(start 34.45002 -435.518306)
		(end 34.627566 -435.518306)
		(stroke
			(width 0.087376)
			(type default)
		)
		(layer "F.Cu")
	)
	(gr_line
		(start 34.458656 -33.165034)
		(end 34.583878 -33.290256)
		(stroke
			(width 0.087376)
			(type default)
		)
		(layer "F.Cu")
	)
	(gr_line
		(start 34.46653 -392.077956)
		(end 35.0266 -391.517886)
		(stroke
			(width 0.085598)
			(type default)
		)
		(layer "F.Cu")
	)
	(gr_line
		(start 34.46653 -390.172956)
		(end 35.0266 -390.733026)
		(stroke
			(width 0.085598)
			(type default)
		)
		(layer "F.Cu")
	)
	(gr_line
		(start 34.51733 -289.077908)
		(end 35.0774 -288.517838)
		(stroke
			(width 0.085598)
			(type default)
		)
		(layer "F.Cu")
	)
	(gr_line
		(start 34.51733 -287.172908)
		(end 35.0774 -287.732978)
		(stroke
			(width 0.085598)
			(type default)
		)
		(layer "F.Cu")
	)
	(gr_line
		(start 34.583878 -33.290256)
		(end 35.108134 -33.290256)
		(stroke
			(width 0.087376)
			(type default)
		)
		(layer "F.Cu")
	)
	(gr_line
		(start 34.613596 -28.296616)
		(end 34.738818 -28.171394)
		(stroke
			(width 0.087376)
			(type default)
		)
		(layer "F.Cu")
	)
	(gr_line
		(start 34.620708 -133.981444)
		(end 34.620708 -134.158736)
		(stroke
			(width 0.087376)
			(type default)
		)
		(layer "F.Cu")
	)
	(gr_line
		(start 34.620708 -133.981444)
		(end 34.991548 -133.610858)
		(stroke
			(width 0.087376)
			(type default)
		)
		(layer "F.Cu")
	)
	(gr_line
		(start 34.627566 -435.518306)
		(end 34.998152 -435.147466)
		(stroke
			(width 0.087376)
			(type default)
		)
		(layer "F.Cu")
	)
	(gr_line
		(start 34.64433 -186.07786)
		(end 35.2044 -185.51779)
		(stroke
			(width 0.085598)
			(type default)
		)
		(layer "F.Cu")
	)
	(gr_line
		(start 34.64433 -184.17286)
		(end 35.2044 -184.73293)
		(stroke
			(width 0.085598)
			(type default)
		)
		(layer "F.Cu")
	)
	(gr_line
		(start 34.675318 -239.921542)
		(end 34.852356 -239.921542)
		(stroke
			(width 0.087376)
			(type default)
		)
		(layer "F.Cu")
	)
	(gr_line
		(start 34.738056 -240.470944)
		(end 34.854134 -240.354866)
		(stroke
			(width 0.087376)
			(type default)
		)
		(layer "F.Cu")
	)
	(gr_line
		(start 34.74593 -83.077812)
		(end 35.306 -82.517742)
		(stroke
			(width 0.085598)
			(type default)
		)
		(layer "F.Cu")
	)
	(gr_line
		(start 34.74593 -81.172812)
		(end 35.306 -81.732882)
		(stroke
			(width 0.085598)
			(type default)
		)
		(layer "F.Cu")
	)
	(gr_line
		(start 34.76371 -32.85744)
		(end 34.928302 -32.85744)
		(stroke
			(width 0.087376)
			(type default)
		)
		(layer "F.Cu")
	)
	(gr_line
		(start 34.991548 -133.610858)
		(end 35.168586 -133.610858)
		(stroke
			(width 0.087376)
			(type default)
		)
		(layer "F.Cu")
	)
	(gr_line
		(start 34.998152 -434.970174)
		(end 34.998152 -435.147466)
		(stroke
			(width 0.087376)
			(type default)
		)
		(layer "F.Cu")
	)
	(gr_line
		(start 35.054032 -134.160514)
		(end 35.170364 -134.044182)
		(stroke
			(width 0.087376)
			(type default)
		)
		(layer "F.Cu")
	)
	(gr_line
		(start 35.108134 -33.290256)
		(end 35.233356 -33.165034)
		(stroke
			(width 0.087376)
			(type default)
		)
		(layer "F.Cu")
	)
	(gr_line
		(start 35.33013 -489.796582)
		(end 35.519106 -489.607606)
		(stroke
			(width 0.087376)
			(type default)
		)
		(layer "F.Cu")
	)
	(gr_line
		(start 35.33013 -488.983782)
		(end 35.519106 -489.172758)
		(stroke
			(width 0.087376)
			(type default)
		)
		(layer "F.Cu")
	)
	(gr_line
		(start 35.33013 -484.99649)
		(end 35.519106 -484.807514)
		(stroke
			(width 0.087376)
			(type default)
		)
		(layer "F.Cu")
	)
	(gr_line
		(start 35.33013 -484.18369)
		(end 35.519106 -484.372666)
		(stroke
			(width 0.087376)
			(type default)
		)
		(layer "F.Cu")
	)
	(gr_line
		(start 35.33013 -480.196652)
		(end 35.519106 -480.007676)
		(stroke
			(width 0.087376)
			(type default)
		)
		(layer "F.Cu")
	)
	(gr_line
		(start 35.33013 -479.383852)
		(end 35.519106 -479.572828)
		(stroke
			(width 0.087376)
			(type default)
		)
		(layer "F.Cu")
	)
	(gr_line
		(start 35.33013 -467.396576)
		(end 35.519106 -467.2076)
		(stroke
			(width 0.087376)
			(type default)
		)
		(layer "F.Cu")
	)
	(gr_line
		(start 35.33013 -466.583776)
		(end 35.519106 -466.772752)
		(stroke
			(width 0.087376)
			(type default)
		)
		(layer "F.Cu")
	)
	(gr_line
		(start 35.33013 -386.796534)
		(end 35.519106 -386.607558)
		(stroke
			(width 0.087376)
			(type default)
		)
		(layer "F.Cu")
	)
	(gr_line
		(start 35.33013 -385.983734)
		(end 35.519106 -386.17271)
		(stroke
			(width 0.087376)
			(type default)
		)
		(layer "F.Cu")
	)
	(gr_line
		(start 35.33013 -381.996442)
		(end 35.519106 -381.807466)
		(stroke
			(width 0.087376)
			(type default)
		)
		(layer "F.Cu")
	)
	(gr_line
		(start 35.33013 -381.183642)
		(end 35.519106 -381.372618)
		(stroke
			(width 0.087376)
			(type default)
		)
		(layer "F.Cu")
	)
	(gr_line
		(start 35.33013 -377.196604)
		(end 35.519106 -377.007628)
		(stroke
			(width 0.087376)
			(type default)
		)
		(layer "F.Cu")
	)
	(gr_line
		(start 35.33013 -376.383804)
		(end 35.519106 -376.57278)
		(stroke
			(width 0.087376)
			(type default)
		)
		(layer "F.Cu")
	)
	(gr_line
		(start 35.33013 -364.396528)
		(end 35.519106 -364.207552)
		(stroke
			(width 0.087376)
			(type default)
		)
		(layer "F.Cu")
	)
	(gr_line
		(start 35.33013 -363.583728)
		(end 35.519106 -363.772704)
		(stroke
			(width 0.087376)
			(type default)
		)
		(layer "F.Cu")
	)
	(gr_line
		(start 35.33013 -283.796486)
		(end 35.519106 -283.60751)
		(stroke
			(width 0.087376)
			(type default)
		)
		(layer "F.Cu")
	)
	(gr_line
		(start 35.33013 -282.983686)
		(end 35.519106 -283.172662)
		(stroke
			(width 0.087376)
			(type default)
		)
		(layer "F.Cu")
	)
	(gr_line
		(start 35.33013 -278.996394)
		(end 35.519106 -278.807418)
		(stroke
			(width 0.087376)
			(type default)
		)
		(layer "F.Cu")
	)
	(gr_line
		(start 35.33013 -278.183594)
		(end 35.519106 -278.37257)
		(stroke
			(width 0.087376)
			(type default)
		)
		(layer "F.Cu")
	)
	(gr_line
		(start 35.33013 -274.196556)
		(end 35.519106 -274.00758)
		(stroke
			(width 0.087376)
			(type default)
		)
		(layer "F.Cu")
	)
	(gr_line
		(start 35.33013 -273.383756)
		(end 35.519106 -273.572732)
		(stroke
			(width 0.087376)
			(type default)
		)
		(layer "F.Cu")
	)
	(gr_line
		(start 35.33013 -261.39648)
		(end 35.519106 -261.207504)
		(stroke
			(width 0.087376)
			(type default)
		)
		(layer "F.Cu")
	)
	(gr_line
		(start 35.33013 -260.58368)
		(end 35.519106 -260.772656)
		(stroke
			(width 0.087376)
			(type default)
		)
		(layer "F.Cu")
	)
	(gr_line
		(start 35.33013 -180.796438)
		(end 35.519106 -180.607462)
		(stroke
			(width 0.087376)
			(type default)
		)
		(layer "F.Cu")
	)
	(gr_line
		(start 35.33013 -179.983638)
		(end 35.519106 -180.172614)
		(stroke
			(width 0.087376)
			(type default)
		)
		(layer "F.Cu")
	)
	(gr_line
		(start 35.33013 -175.996346)
		(end 35.519106 -175.80737)
		(stroke
			(width 0.087376)
			(type default)
		)
		(layer "F.Cu")
	)
	(gr_line
		(start 35.33013 -175.183546)
		(end 35.519106 -175.372522)
		(stroke
			(width 0.087376)
			(type default)
		)
		(layer "F.Cu")
	)
	(gr_line
		(start 35.33013 -171.196508)
		(end 35.519106 -171.007532)
		(stroke
			(width 0.087376)
			(type default)
		)
		(layer "F.Cu")
	)
	(gr_line
		(start 35.33013 -170.383708)
		(end 35.519106 -170.572684)
		(stroke
			(width 0.087376)
			(type default)
		)
		(layer "F.Cu")
	)
	(gr_line
		(start 35.33013 -158.396432)
		(end 35.519106 -158.207456)
		(stroke
			(width 0.087376)
			(type default)
		)
		(layer "F.Cu")
	)
	(gr_line
		(start 35.33013 -157.583632)
		(end 35.519106 -157.772608)
		(stroke
			(width 0.087376)
			(type default)
		)
		(layer "F.Cu")
	)
	(gr_line
		(start 35.33013 -77.79639)
		(end 35.519106 -77.607414)
		(stroke
			(width 0.087376)
			(type default)
		)
		(layer "F.Cu")
	)
	(gr_line
		(start 35.33013 -76.98359)
		(end 35.519106 -77.172566)
		(stroke
			(width 0.087376)
			(type default)
		)
		(layer "F.Cu")
	)
	(gr_line
		(start 35.33013 -72.996298)
		(end 35.519106 -72.807322)
		(stroke
			(width 0.087376)
			(type default)
		)
		(layer "F.Cu")
	)
	(gr_line
		(start 35.33013 -72.183498)
		(end 35.519106 -72.372474)
		(stroke
			(width 0.087376)
			(type default)
		)
		(layer "F.Cu")
	)
	(gr_line
		(start 35.33013 -68.19646)
		(end 35.519106 -68.007484)
		(stroke
			(width 0.087376)
			(type default)
		)
		(layer "F.Cu")
	)
	(gr_line
		(start 35.33013 -67.38366)
		(end 35.519106 -67.572636)
		(stroke
			(width 0.087376)
			(type default)
		)
		(layer "F.Cu")
	)
	(gr_line
		(start 35.33013 -55.396384)
		(end 35.519106 -55.207408)
		(stroke
			(width 0.087376)
			(type default)
		)
		(layer "F.Cu")
	)
	(gr_line
		(start 35.33013 -54.583584)
		(end 35.519106 -54.77256)
		(stroke
			(width 0.087376)
			(type default)
		)
		(layer "F.Cu")
	)
	(gr_line
		(start 35.370516 -434.162708)
		(end 35.487102 -434.046122)
		(stroke
			(width 0.087376)
			(type default)
		)
		(layer "F.Cu")
	)
	(gr_line
		(start 35.372294 -434.596032)
		(end 35.549586 -434.596032)
		(stroke
			(width 0.087376)
			(type default)
		)
		(layer "F.Cu")
	)
	(gr_line
		(start 35.542982 -133.059424)
		(end 35.542982 -133.236462)
		(stroke
			(width 0.087376)
			(type default)
		)
		(layer "F.Cu")
	)
	(gr_line
		(start 35.542982 -133.059424)
		(end 35.913568 -132.688838)
		(stroke
			(width 0.087376)
			(type default)
		)
		(layer "F.Cu")
	)
	(gr_line
		(start 35.549586 -434.596032)
		(end 35.920426 -434.225446)
		(stroke
			(width 0.087376)
			(type default)
		)
		(layer "F.Cu")
	)
	(gr_line
		(start 35.762692 -33.165034)
		(end 35.887914 -33.290256)
		(stroke
			(width 0.087376)
			(type default)
		)
		(layer "F.Cu")
	)
	(gr_line
		(start 35.887914 -33.290256)
		(end 36.41217 -33.290256)
		(stroke
			(width 0.087376)
			(type default)
		)
		(layer "F.Cu")
	)
	(gr_line
		(start 35.913568 -132.688838)
		(end 36.090606 -132.688838)
		(stroke
			(width 0.087376)
			(type default)
		)
		(layer "F.Cu")
	)
	(gr_line
		(start 35.920426 -434.0479)
		(end 35.920426 -434.225446)
		(stroke
			(width 0.087376)
			(type default)
		)
		(layer "F.Cu")
	)
	(gr_line
		(start 35.976306 -133.23824)
		(end 36.092384 -133.122162)
		(stroke
			(width 0.087376)
			(type default)
		)
		(layer "F.Cu")
	)
	(gr_line
		(start 36.067746 -32.85744)
		(end 36.232338 -32.85744)
		(stroke
			(width 0.087376)
			(type default)
		)
		(layer "F.Cu")
	)
	(gr_line
		(start 36.41217 -33.290256)
		(end 36.537392 -33.165034)
		(stroke
			(width 0.087376)
			(type default)
		)
		(layer "F.Cu")
	)
	(gr_line
		(start 36.72713 -492.349028)
		(end 37.068506 -492.007652)
		(stroke
			(width 0.087376)
			(type default)
		)
		(layer "F.Cu")
	)
	(gr_line
		(start 36.72713 -491.231428)
		(end 37.068506 -491.572804)
		(stroke
			(width 0.087376)
			(type default)
		)
		(layer "F.Cu")
	)
	(gr_line
		(start 36.72713 -487.548936)
		(end 37.068506 -487.20756)
		(stroke
			(width 0.087376)
			(type default)
		)
		(layer "F.Cu")
	)
	(gr_line
		(start 36.72713 -486.431336)
		(end 37.068506 -486.772712)
		(stroke
			(width 0.087376)
			(type default)
		)
		(layer "F.Cu")
	)
	(gr_line
		(start 36.72713 -482.748844)
		(end 37.068506 -482.407468)
		(stroke
			(width 0.087376)
			(type default)
		)
		(layer "F.Cu")
	)
	(gr_line
		(start 36.72713 -481.631244)
		(end 37.068506 -481.97262)
		(stroke
			(width 0.087376)
			(type default)
		)
		(layer "F.Cu")
	)
	(gr_line
		(start 36.72713 -469.949022)
		(end 37.068506 -469.607646)
		(stroke
			(width 0.087376)
			(type default)
		)
		(layer "F.Cu")
	)
	(gr_line
		(start 36.72713 -468.831422)
		(end 37.068506 -469.172798)
		(stroke
			(width 0.087376)
			(type default)
		)
		(layer "F.Cu")
	)
	(gr_line
		(start 36.72713 -389.34898)
		(end 37.068506 -389.007604)
		(stroke
			(width 0.087376)
			(type default)
		)
		(layer "F.Cu")
	)
	(gr_line
		(start 36.72713 -388.23138)
		(end 37.068506 -388.572756)
		(stroke
			(width 0.087376)
			(type default)
		)
		(layer "F.Cu")
	)
	(gr_line
		(start 36.72713 -384.548888)
		(end 37.068506 -384.207512)
		(stroke
			(width 0.087376)
			(type default)
		)
		(layer "F.Cu")
	)
	(gr_line
		(start 36.72713 -383.431288)
		(end 37.068506 -383.772664)
		(stroke
			(width 0.087376)
			(type default)
		)
		(layer "F.Cu")
	)
	(gr_line
		(start 36.72713 -379.748796)
		(end 37.068506 -379.40742)
		(stroke
			(width 0.087376)
			(type default)
		)
		(layer "F.Cu")
	)
	(gr_line
		(start 36.72713 -378.631196)
		(end 37.068506 -378.972572)
		(stroke
			(width 0.087376)
			(type default)
		)
		(layer "F.Cu")
	)
	(gr_line
		(start 36.72713 -366.948974)
		(end 37.068506 -366.607598)
		(stroke
			(width 0.087376)
			(type default)
		)
		(layer "F.Cu")
	)
	(gr_line
		(start 36.72713 -365.831374)
		(end 37.068506 -366.17275)
		(stroke
			(width 0.087376)
			(type default)
		)
		(layer "F.Cu")
	)
	(gr_line
		(start 36.72713 -286.348932)
		(end 37.068506 -286.007556)
		(stroke
			(width 0.087376)
			(type default)
		)
		(layer "F.Cu")
	)
	(gr_line
		(start 36.72713 -285.231332)
		(end 37.068506 -285.572708)
		(stroke
			(width 0.087376)
			(type default)
		)
		(layer "F.Cu")
	)
	(gr_line
		(start 36.72713 -281.54884)
		(end 37.068506 -281.207464)
		(stroke
			(width 0.087376)
			(type default)
		)
		(layer "F.Cu")
	)
	(gr_line
		(start 36.72713 -280.43124)
		(end 37.068506 -280.772616)
		(stroke
			(width 0.087376)
			(type default)
		)
		(layer "F.Cu")
	)
	(gr_line
		(start 36.72713 -276.748748)
		(end 37.068506 -276.407372)
		(stroke
			(width 0.087376)
			(type default)
		)
		(layer "F.Cu")
	)
	(gr_line
		(start 36.72713 -275.631148)
		(end 37.068506 -275.972524)
		(stroke
			(width 0.087376)
			(type default)
		)
		(layer "F.Cu")
	)
	(gr_line
		(start 36.72713 -263.948926)
		(end 37.068506 -263.60755)
		(stroke
			(width 0.087376)
			(type default)
		)
		(layer "F.Cu")
	)
	(gr_line
		(start 36.72713 -262.831326)
		(end 37.068506 -263.172702)
		(stroke
			(width 0.087376)
			(type default)
		)
		(layer "F.Cu")
	)
	(gr_line
		(start 36.72713 -183.348884)
		(end 37.068506 -183.007508)
		(stroke
			(width 0.087376)
			(type default)
		)
		(layer "F.Cu")
	)
	(gr_line
		(start 36.72713 -182.231284)
		(end 37.068506 -182.57266)
		(stroke
			(width 0.087376)
			(type default)
		)
		(layer "F.Cu")
	)
	(gr_line
		(start 36.72713 -178.548792)
		(end 37.068506 -178.207416)
		(stroke
			(width 0.087376)
			(type default)
		)
		(layer "F.Cu")
	)
	(gr_line
		(start 36.72713 -177.431192)
		(end 37.068506 -177.772568)
		(stroke
			(width 0.087376)
			(type default)
		)
		(layer "F.Cu")
	)
	(gr_line
		(start 36.72713 -173.7487)
		(end 37.068506 -173.407324)
		(stroke
			(width 0.087376)
			(type default)
		)
		(layer "F.Cu")
	)
	(gr_line
		(start 36.72713 -172.6311)
		(end 37.068506 -172.972476)
		(stroke
			(width 0.087376)
			(type default)
		)
		(layer "F.Cu")
	)
	(gr_line
		(start 36.72713 -160.948878)
		(end 37.068506 -160.607502)
		(stroke
			(width 0.087376)
			(type default)
		)
		(layer "F.Cu")
	)
	(gr_line
		(start 36.72713 -159.831278)
		(end 37.068506 -160.172654)
		(stroke
			(width 0.087376)
			(type default)
		)
		(layer "F.Cu")
	)
	(gr_line
		(start 36.72713 -80.348836)
		(end 37.068506 -80.00746)
		(stroke
			(width 0.087376)
			(type default)
		)
		(layer "F.Cu")
	)
	(gr_line
		(start 36.72713 -79.231236)
		(end 37.068506 -79.572612)
		(stroke
			(width 0.087376)
			(type default)
		)
		(layer "F.Cu")
	)
	(gr_line
		(start 36.72713 -75.548744)
		(end 37.068506 -75.207368)
		(stroke
			(width 0.087376)
			(type default)
		)
		(layer "F.Cu")
	)
	(gr_line
		(start 36.72713 -74.431144)
		(end 37.068506 -74.77252)
		(stroke
			(width 0.087376)
			(type default)
		)
		(layer "F.Cu")
	)
	(gr_line
		(start 36.72713 -70.748652)
		(end 37.068506 -70.407276)
		(stroke
			(width 0.087376)
			(type default)
		)
		(layer "F.Cu")
	)
	(gr_line
		(start 36.72713 -69.631052)
		(end 37.068506 -69.972428)
		(stroke
			(width 0.087376)
			(type default)
		)
		(layer "F.Cu")
	)
	(gr_line
		(start 36.72713 -57.94883)
		(end 37.068506 -57.607454)
		(stroke
			(width 0.087376)
			(type default)
		)
		(layer "F.Cu")
	)
	(gr_line
		(start 36.72713 -56.83123)
		(end 37.068506 -57.172606)
		(stroke
			(width 0.087376)
			(type default)
		)
		(layer "F.Cu")
	)
	(gr_line
		(start 37.660326 -484.804466)
		(end 37.846 -484.99014)
		(stroke
			(width 0.087376)
			(type default)
		)
		(layer "F.Cu")
	)
	(gr_line
		(start 37.660326 -484.369364)
		(end 37.83965 -484.19004)
		(stroke
			(width 0.087376)
			(type default)
		)
		(layer "F.Cu")
	)
	(gr_line
		(start 37.784024 -480.007676)
		(end 37.966396 -480.190048)
		(stroke
			(width 0.087376)
			(type default)
		)
		(layer "F.Cu")
	)
	(gr_line
		(start 37.784024 -479.572574)
		(end 37.966396 -479.390202)
		(stroke
			(width 0.087376)
			(type default)
		)
		(layer "F.Cu")
	)
	(gr_line
		(start 37.784024 -467.207854)
		(end 37.966396 -467.390226)
		(stroke
			(width 0.087376)
			(type default)
		)
		(layer "F.Cu")
	)
	(gr_line
		(start 37.784024 -466.772752)
		(end 37.96665 -466.590126)
		(stroke
			(width 0.087376)
			(type default)
		)
		(layer "F.Cu")
	)
	(gr_line
		(start 37.787072 -489.610908)
		(end 37.966396 -489.790232)
		(stroke
			(width 0.087376)
			(type default)
		)
		(layer "F.Cu")
	)
	(gr_line
		(start 37.787072 -489.17606)
		(end 37.973 -488.990132)
		(stroke
			(width 0.087376)
			(type default)
		)
		(layer "F.Cu")
	)
	(gr_line
		(start 37.787326 -469.604344)
		(end 37.973 -469.790018)
		(stroke
			(width 0.087376)
			(type default)
		)
		(layer "F.Cu")
	)
	(gr_line
		(start 37.787326 -469.169242)
		(end 37.966396 -468.990172)
		(stroke
			(width 0.087376)
			(type default)
		)
		(layer "F.Cu")
	)
	(gr_line
		(start 37.787834 -464.805014)
		(end 37.973 -464.99018)
		(stroke
			(width 0.087376)
			(type default)
		)
		(layer "F.Cu")
	)
	(gr_line
		(start 37.787834 -464.370166)
		(end 37.96792 -464.19008)
		(stroke
			(width 0.087376)
			(type default)
		)
		(layer "F.Cu")
	)
	(gr_line
		(start 37.790374 -487.20756)
		(end 37.973 -487.390186)
		(stroke
			(width 0.087376)
			(type default)
		)
		(layer "F.Cu")
	)
	(gr_line
		(start 37.790374 -486.772712)
		(end 37.973 -486.590086)
		(stroke
			(width 0.087376)
			(type default)
		)
		(layer "F.Cu")
	)
	(gr_line
		(start 37.790374 -482.407468)
		(end 37.973 -482.590094)
		(stroke
			(width 0.087376)
			(type default)
		)
		(layer "F.Cu")
	)
	(gr_line
		(start 37.790374 -481.97262)
		(end 37.973 -481.789994)
		(stroke
			(width 0.087376)
			(type default)
		)
		(layer "F.Cu")
	)
	(gr_line
		(start 37.790628 -492.007652)
		(end 37.973 -492.190024)
		(stroke
			(width 0.087376)
			(type default)
		)
		(layer "F.Cu")
	)
	(gr_line
		(start 37.790628 -491.57255)
		(end 37.973 -491.390178)
		(stroke
			(width 0.087376)
			(type default)
		)
		(layer "F.Cu")
	)
	(gr_line
		(start 37.83965 -484.19004)
		(end 39.200074 -484.19004)
		(stroke
			(width 0.087376)
			(type default)
		)
		(layer "F.Cu")
	)
	(gr_line
		(start 37.846 -484.99014)
		(end 39.200074 -484.99014)
		(stroke
			(width 0.087376)
			(type default)
		)
		(layer "F.Cu")
	)
	(gr_line
		(start 37.890196 -130.711956)
		(end 37.890196 -130.889248)
		(stroke
			(width 0.087376)
			(type default)
		)
		(layer "F.Cu")
	)
	(gr_line
		(start 37.890196 -130.711956)
		(end 38.261036 -130.34137)
		(stroke
			(width 0.087376)
			(type default)
		)
		(layer "F.Cu")
	)
	(gr_line
		(start 37.909754 -68.008754)
		(end 38.090856 -68.189856)
		(stroke
			(width 0.087376)
			(type default)
		)
		(layer "F.Cu")
	)
	(gr_line
		(start 37.909754 -67.573652)
		(end 38.093396 -67.39001)
		(stroke
			(width 0.087376)
			(type default)
		)
		(layer "F.Cu")
	)
	(gr_line
		(start 37.911024 -364.207806)
		(end 38.093396 -364.390178)
		(stroke
			(width 0.087376)
			(type default)
		)
		(layer "F.Cu")
	)
	(gr_line
		(start 37.911024 -363.772704)
		(end 38.09365 -363.590078)
		(stroke
			(width 0.087376)
			(type default)
		)
		(layer "F.Cu")
	)
	(gr_line
		(start 37.911024 -261.207758)
		(end 38.093396 -261.39013)
		(stroke
			(width 0.087376)
			(type default)
		)
		(layer "F.Cu")
	)
	(gr_line
		(start 37.911024 -260.772656)
		(end 38.09365 -260.59003)
		(stroke
			(width 0.087376)
			(type default)
		)
		(layer "F.Cu")
	)
	(gr_line
		(start 37.911024 -258.807458)
		(end 38.09365 -258.990084)
		(stroke
			(width 0.087376)
			(type default)
		)
		(layer "F.Cu")
	)
	(gr_line
		(start 37.911024 -258.372356)
		(end 38.093396 -258.189984)
		(stroke
			(width 0.087376)
			(type default)
		)
		(layer "F.Cu")
	)
	(gr_line
		(start 37.911024 -160.607502)
		(end 38.093396 -160.789874)
		(stroke
			(width 0.087376)
			(type default)
		)
		(layer "F.Cu")
	)
	(gr_line
		(start 37.911024 -160.1724)
		(end 38.093396 -159.990028)
		(stroke
			(width 0.087376)
			(type default)
		)
		(layer "F.Cu")
	)
	(gr_line
		(start 37.911024 -158.20771)
		(end 38.093396 -158.390082)
		(stroke
			(width 0.087376)
			(type default)
		)
		(layer "F.Cu")
	)
	(gr_line
		(start 37.911024 -157.772608)
		(end 38.09365 -157.589982)
		(stroke
			(width 0.087376)
			(type default)
		)
		(layer "F.Cu")
	)
	(gr_line
		(start 37.911024 -77.607668)
		(end 38.093396 -77.79004)
		(stroke
			(width 0.087376)
			(type default)
		)
		(layer "F.Cu")
	)
	(gr_line
		(start 37.911024 -77.172566)
		(end 38.09365 -76.98994)
		(stroke
			(width 0.087376)
			(type default)
		)
		(layer "F.Cu")
	)
	(gr_line
		(start 37.911024 -57.607454)
		(end 38.093396 -57.789826)
		(stroke
			(width 0.087376)
			(type default)
		)
		(layer "F.Cu")
	)
	(gr_line
		(start 37.911024 -57.172352)
		(end 38.093396 -56.98998)
		(stroke
			(width 0.087376)
			(type default)
		)
		(layer "F.Cu")
	)
	(gr_line
		(start 37.911024 -55.207662)
		(end 38.093396 -55.390034)
		(stroke
			(width 0.087376)
			(type default)
		)
		(layer "F.Cu")
	)
	(gr_line
		(start 37.911024 -54.77256)
		(end 38.09365 -54.589934)
		(stroke
			(width 0.087376)
			(type default)
		)
		(layer "F.Cu")
	)
	(gr_line
		(start 37.911024 -52.807362)
		(end 38.09365 -52.989988)
		(stroke
			(width 0.087376)
			(type default)
		)
		(layer "F.Cu")
	)
	(gr_line
		(start 37.911024 -52.37226)
		(end 38.093396 -52.189888)
		(stroke
			(width 0.087376)
			(type default)
		)
		(layer "F.Cu")
	)
	(gr_line
		(start 37.914326 -377.01093)
		(end 38.093396 -377.19)
		(stroke
			(width 0.087376)
			(type default)
		)
		(layer "F.Cu")
	)
	(gr_line
		(start 37.914326 -376.575828)
		(end 38.1 -376.390154)
		(stroke
			(width 0.087376)
			(type default)
		)
		(layer "F.Cu")
	)
	(gr_line
		(start 37.914326 -361.810808)
		(end 38.09365 -361.990132)
		(stroke
			(width 0.087376)
			(type default)
		)
		(layer "F.Cu")
	)
	(gr_line
		(start 37.914326 -361.375706)
		(end 38.1 -361.190032)
		(stroke
			(width 0.087376)
			(type default)
		)
		(layer "F.Cu")
	)
	(gr_line
		(start 37.914326 -278.80437)
		(end 38.1 -278.990044)
		(stroke
			(width 0.087376)
			(type default)
		)
		(layer "F.Cu")
	)
	(gr_line
		(start 37.914326 -278.369268)
		(end 38.09365 -278.189944)
		(stroke
			(width 0.087376)
			(type default)
		)
		(layer "F.Cu")
	)
	(gr_line
		(start 37.914326 -276.404324)
		(end 38.1 -276.589998)
		(stroke
			(width 0.087376)
			(type default)
		)
		(layer "F.Cu")
	)
	(gr_line
		(start 37.914326 -275.969222)
		(end 38.09365 -275.789898)
		(stroke
			(width 0.087376)
			(type default)
		)
		(layer "F.Cu")
	)
	(gr_line
		(start 37.914326 -274.004278)
		(end 38.1 -274.189952)
		(stroke
			(width 0.087376)
			(type default)
		)
		(layer "F.Cu")
	)
	(gr_line
		(start 37.914326 -273.569176)
		(end 38.093396 -273.390106)
		(stroke
			(width 0.087376)
			(type default)
		)
		(layer "F.Cu")
	)
	(gr_line
		(start 37.914326 -183.01081)
		(end 38.093396 -183.18988)
		(stroke
			(width 0.087376)
			(type default)
		)
		(layer "F.Cu")
	)
	(gr_line
		(start 37.914326 -182.575708)
		(end 38.1 -182.390034)
		(stroke
			(width 0.087376)
			(type default)
		)
		(layer "F.Cu")
	)
	(gr_line
		(start 37.914326 -175.804322)
		(end 38.1 -175.989996)
		(stroke
			(width 0.087376)
			(type default)
		)
		(layer "F.Cu")
	)
	(gr_line
		(start 37.914326 -175.36922)
		(end 38.09365 -175.189896)
		(stroke
			(width 0.087376)
			(type default)
		)
		(layer "F.Cu")
	)
	(gr_line
		(start 37.914326 -173.404276)
		(end 38.1 -173.58995)
		(stroke
			(width 0.087376)
			(type default)
		)
		(layer "F.Cu")
	)
	(gr_line
		(start 37.914326 -172.969174)
		(end 38.09365 -172.78985)
		(stroke
			(width 0.087376)
			(type default)
		)
		(layer "F.Cu")
	)
	(gr_line
		(start 37.914326 -171.00423)
		(end 38.1 -171.189904)
		(stroke
			(width 0.087376)
			(type default)
		)
		(layer "F.Cu")
	)
	(gr_line
		(start 37.914326 -170.569128)
		(end 38.093396 -170.390058)
		(stroke
			(width 0.087376)
			(type default)
		)
		(layer "F.Cu")
	)
	(gr_line
		(start 37.914326 -75.20432)
		(end 38.1 -75.389994)
		(stroke
			(width 0.087376)
			(type default)
		)
		(layer "F.Cu")
	)
	(gr_line
		(start 37.914326 -74.769218)
		(end 38.09365 -74.589894)
		(stroke
			(width 0.087376)
			(type default)
		)
		(layer "F.Cu")
	)
	(gr_line
		(start 37.914326 -70.404228)
		(end 38.1 -70.589902)
		(stroke
			(width 0.087376)
			(type default)
		)
		(layer "F.Cu")
	)
	(gr_line
		(start 37.914326 -69.969126)
		(end 38.09365 -69.789802)
		(stroke
			(width 0.087376)
			(type default)
		)
		(layer "F.Cu")
	)
	(gr_line
		(start 37.916358 -155.812744)
		(end 38.09365 -155.990036)
		(stroke
			(width 0.087376)
			(type default)
		)
		(layer "F.Cu")
	)
	(gr_line
		(start 37.916358 -155.377642)
		(end 38.104064 -155.189936)
		(stroke
			(width 0.087376)
			(type default)
		)
		(layer "F.Cu")
	)
	(gr_line
		(start 37.917374 -386.607558)
		(end 38.1 -386.790184)
		(stroke
			(width 0.087376)
			(type default)
		)
		(layer "F.Cu")
	)
	(gr_line
		(start 37.917374 -386.17271)
		(end 38.1 -385.990084)
		(stroke
			(width 0.087376)
			(type default)
		)
		(layer "F.Cu")
	)
	(gr_line
		(start 37.917374 -384.207512)
		(end 38.1 -384.390138)
		(stroke
			(width 0.087376)
			(type default)
		)
		(layer "F.Cu")
	)
	(gr_line
		(start 37.917374 -383.772664)
		(end 38.1 -383.590038)
		(stroke
			(width 0.087376)
			(type default)
		)
		(layer "F.Cu")
	)
	(gr_line
		(start 37.917374 -381.807466)
		(end 38.1 -381.990092)
		(stroke
			(width 0.087376)
			(type default)
		)
		(layer "F.Cu")
	)
	(gr_line
		(start 37.917374 -381.372618)
		(end 38.1 -381.189992)
		(stroke
			(width 0.087376)
			(type default)
		)
		(layer "F.Cu")
	)
	(gr_line
		(start 37.917374 -379.40742)
		(end 38.1 -379.590046)
		(stroke
			(width 0.087376)
			(type default)
		)
		(layer "F.Cu")
	)
	(gr_line
		(start 37.917374 -378.972572)
		(end 38.1 -378.789946)
		(stroke
			(width 0.087376)
			(type default)
		)
		(layer "F.Cu")
	)
	(gr_line
		(start 37.917374 -283.60751)
		(end 38.1 -283.790136)
		(stroke
			(width 0.087376)
			(type default)
		)
		(layer "F.Cu")
	)
	(gr_line
		(start 37.917374 -283.172662)
		(end 38.1 -282.990036)
		(stroke
			(width 0.087376)
			(type default)
		)
		(layer "F.Cu")
	)
	(gr_line
		(start 37.917374 -281.207464)
		(end 38.1 -281.39009)
		(stroke
			(width 0.087376)
			(type default)
		)
		(layer "F.Cu")
	)
	(gr_line
		(start 37.917374 -280.772616)
		(end 38.1 -280.58999)
		(stroke
			(width 0.087376)
			(type default)
		)
		(layer "F.Cu")
	)
	(gr_line
		(start 37.917374 -180.607462)
		(end 38.1 -180.790088)
		(stroke
			(width 0.087376)
			(type default)
		)
		(layer "F.Cu")
	)
	(gr_line
		(start 37.917374 -180.172614)
		(end 38.1 -179.989988)
		(stroke
			(width 0.087376)
			(type default)
		)
		(layer "F.Cu")
	)
	(gr_line
		(start 37.917374 -178.207416)
		(end 38.1 -178.390042)
		(stroke
			(width 0.087376)
			(type default)
		)
		(layer "F.Cu")
	)
	(gr_line
		(start 37.917374 -177.772568)
		(end 38.1 -177.589942)
		(stroke
			(width 0.087376)
			(type default)
		)
		(layer "F.Cu")
	)
	(gr_line
		(start 37.917374 -72.807322)
		(end 38.1 -72.989948)
		(stroke
			(width 0.087376)
			(type default)
		)
		(layer "F.Cu")
	)
	(gr_line
		(start 37.917374 -72.372474)
		(end 38.1 -72.189848)
		(stroke
			(width 0.087376)
			(type default)
		)
		(layer "F.Cu")
	)
	(gr_line
		(start 37.917628 -389.007604)
		(end 38.1 -389.189976)
		(stroke
			(width 0.087376)
			(type default)
		)
		(layer "F.Cu")
	)
	(gr_line
		(start 37.917628 -388.572502)
		(end 38.1 -388.39013)
		(stroke
			(width 0.087376)
			(type default)
		)
		(layer "F.Cu")
	)
	(gr_line
		(start 37.917628 -286.007556)
		(end 38.1 -286.189928)
		(stroke
			(width 0.087376)
			(type default)
		)
		(layer "F.Cu")
	)
	(gr_line
		(start 37.917628 -285.572454)
		(end 38.1 -285.390082)
		(stroke
			(width 0.087376)
			(type default)
		)
		(layer "F.Cu")
	)
	(gr_line
		(start 37.917628 -80.00746)
		(end 38.1 -80.189832)
		(stroke
			(width 0.087376)
			(type default)
		)
		(layer "F.Cu")
	)
	(gr_line
		(start 37.917628 -79.572358)
		(end 38.1 -79.389986)
		(stroke
			(width 0.087376)
			(type default)
		)
		(layer "F.Cu")
	)
	(gr_line
		(start 37.921184 -366.597184)
		(end 38.11397 -366.78997)
		(stroke
			(width 0.087376)
			(type default)
		)
		(layer "F.Cu")
	)
	(gr_line
		(start 37.921184 -366.162336)
		(end 38.093396 -365.990124)
		(stroke
			(width 0.087376)
			(type default)
		)
		(layer "F.Cu")
	)
	(gr_line
		(start 37.927788 -263.624314)
		(end 38.093396 -263.789922)
		(stroke
			(width 0.087376)
			(type default)
		)
		(layer "F.Cu")
	)
	(gr_line
		(start 37.927788 -263.189212)
		(end 38.126924 -262.990076)
		(stroke
			(width 0.087376)
			(type default)
		)
		(layer "F.Cu")
	)
	(gr_line
		(start 37.963094 -494.585244)
		(end 37.96792 -494.59007)
		(stroke
			(width 0.085598)
			(type default)
		)
		(layer "F.Cu")
	)
	(gr_line
		(start 37.963094 -493.80013)
		(end 37.973 -493.790224)
		(stroke
			(width 0.085598)
			(type default)
		)
		(layer "F.Cu")
	)
	(gr_line
		(start 37.966396 -489.790232)
		(end 39.200074 -489.790232)
		(stroke
			(width 0.087376)
			(type default)
		)
		(layer "F.Cu")
	)
	(gr_line
		(start 37.966396 -480.190048)
		(end 39.200074 -480.190048)
		(stroke
			(width 0.087376)
			(type default)
		)
		(layer "F.Cu")
	)
	(gr_line
		(start 37.966396 -479.390202)
		(end 39.200074 -479.390202)
		(stroke
			(width 0.087376)
			(type default)
		)
		(layer "F.Cu")
	)
	(gr_line
		(start 37.966396 -468.990172)
		(end 39.200074 -468.990172)
		(stroke
			(width 0.087376)
			(type default)
		)
		(layer "F.Cu")
	)
	(gr_line
		(start 37.966396 -467.390226)
		(end 39.200074 -467.390226)
		(stroke
			(width 0.087376)
			(type default)
		)
		(layer "F.Cu")
	)
	(gr_line
		(start 37.96665 -466.590126)
		(end 39.200074 -466.590126)
		(stroke
			(width 0.087376)
			(type default)
		)
		(layer "F.Cu")
	)
	(gr_line
		(start 37.96792 -494.59007)
		(end 39.200074 -494.59007)
		(stroke
			(width 0.085598)
			(type default)
		)
		(layer "F.Cu")
	)
	(gr_line
		(start 37.96792 -464.19008)
		(end 39.200074 -464.19008)
		(stroke
			(width 0.087376)
			(type default)
		)
		(layer "F.Cu")
	)
	(gr_line
		(start 37.973 -493.790224)
		(end 39.200074 -493.790224)
		(stroke
			(width 0.085598)
			(type default)
		)
		(layer "F.Cu")
	)
	(gr_line
		(start 37.973 -492.190024)
		(end 39.200074 -492.190024)
		(stroke
			(width 0.087376)
			(type default)
		)
		(layer "F.Cu")
	)
	(gr_line
		(start 37.973 -491.390178)
		(end 39.200074 -491.390178)
		(stroke
			(width 0.087376)
			(type default)
		)
		(layer "F.Cu")
	)
	(gr_line
		(start 37.973 -488.990132)
		(end 39.200074 -488.990132)
		(stroke
			(width 0.087376)
			(type default)
		)
		(layer "F.Cu")
	)
	(gr_line
		(start 37.973 -487.390186)
		(end 39.200074 -487.390186)
		(stroke
			(width 0.087376)
			(type default)
		)
		(layer "F.Cu")
	)
	(gr_line
		(start 37.973 -486.590086)
		(end 39.200074 -486.590086)
		(stroke
			(width 0.087376)
			(type default)
		)
		(layer "F.Cu")
	)
	(gr_line
		(start 37.973 -482.590094)
		(end 39.200074 -482.590094)
		(stroke
			(width 0.087376)
			(type default)
		)
		(layer "F.Cu")
	)
	(gr_line
		(start 37.973 -481.789994)
		(end 39.200074 -481.789994)
		(stroke
			(width 0.087376)
			(type default)
		)
		(layer "F.Cu")
	)
	(gr_line
		(start 37.973 -469.790018)
		(end 39.200074 -469.790018)
		(stroke
			(width 0.087376)
			(type default)
		)
		(layer "F.Cu")
	)
	(gr_line
		(start 37.973 -464.99018)
		(end 39.200074 -464.99018)
		(stroke
			(width 0.087376)
			(type default)
		)
		(layer "F.Cu")
	)
	(gr_line
		(start 38.088062 -81.801716)
		(end 38.1 -81.790032)
		(stroke
			(width 0.085598)
			(type default)
		)
		(layer "F.Cu")
	)
	(gr_line
		(start 38.08984 -82.584798)
		(end 38.09492 -82.589878)
		(stroke
			(width 0.085598)
			(type default)
		)
		(layer "F.Cu")
	)
	(gr_line
		(start 38.090856 -68.189856)
		(end 39.200074 -68.189856)
		(stroke
			(width 0.087376)
			(type default)
		)
		(layer "F.Cu")
	)
	(gr_line
		(start 38.092634 -391.582656)
		(end 38.1 -391.590022)
		(stroke
			(width 0.085598)
			(type default)
		)
		(layer "F.Cu")
	)
	(gr_line
		(start 38.092634 -390.797542)
		(end 38.1 -390.790176)
		(stroke
			(width 0.085598)
			(type default)
		)
		(layer "F.Cu")
	)
	(gr_line
		(start 38.092634 -288.582608)
		(end 38.1 -288.589974)
		(stroke
			(width 0.085598)
			(type default)
		)
		(layer "F.Cu")
	)
	(gr_line
		(start 38.092634 -287.797494)
		(end 38.1 -287.790128)
		(stroke
			(width 0.085598)
			(type default)
		)
		(layer "F.Cu")
	)
	(gr_line
		(start 38.092634 -185.58256)
		(end 38.1 -185.589926)
		(stroke
			(width 0.085598)
			(type default)
		)
		(layer "F.Cu")
	)
	(gr_line
		(start 38.092634 -184.797446)
		(end 38.1 -184.79008)
		(stroke
			(width 0.085598)
			(type default)
		)
		(layer "F.Cu")
	)
	(gr_line
		(start 38.093396 -377.19)
		(end 39.200074 -377.19)
		(stroke
			(width 0.087376)
			(type default)
		)
		(layer "F.Cu")
	)
	(gr_line
		(start 38.093396 -365.990124)
		(end 39.200074 -365.990124)
		(stroke
			(width 0.087376)
			(type default)
		)
		(layer "F.Cu")
	)
	(gr_line
		(start 38.093396 -364.390178)
		(end 39.200074 -364.390178)
		(stroke
			(width 0.087376)
			(type default)
		)
		(layer "F.Cu")
	)
	(gr_line
		(start 38.093396 -273.390106)
		(end 39.200074 -273.390106)
		(stroke
			(width 0.087376)
			(type default)
		)
		(layer "F.Cu")
	)
	(gr_line
		(start 38.093396 -263.789922)
		(end 39.200074 -263.789922)
		(stroke
			(width 0.087376)
			(type default)
		)
		(layer "F.Cu")
	)
	(gr_line
		(start 38.093396 -261.39013)
		(end 39.200074 -261.39013)
		(stroke
			(width 0.087376)
			(type default)
		)
		(layer "F.Cu")
	)
	(gr_line
		(start 38.093396 -258.189984)
		(end 39.200074 -258.189984)
		(stroke
			(width 0.087376)
			(type default)
		)
		(layer "F.Cu")
	)
	(gr_line
		(start 38.093396 -183.18988)
		(end 39.200074 -183.18988)
		(stroke
			(width 0.087376)
			(type default)
		)
		(layer "F.Cu")
	)
	(gr_line
		(start 38.093396 -170.390058)
		(end 39.200074 -170.390058)
		(stroke
			(width 0.087376)
			(type default)
		)
		(layer "F.Cu")
	)
	(gr_line
		(start 38.093396 -160.789874)
		(end 39.200074 -160.789874)
		(stroke
			(width 0.087376)
			(type default)
		)
		(layer "F.Cu")
	)
	(gr_line
		(start 38.093396 -159.990028)
		(end 39.200074 -159.990028)
		(stroke
			(width 0.087376)
			(type default)
		)
		(layer "F.Cu")
	)
	(gr_line
		(start 38.093396 -158.390082)
		(end 39.200074 -158.390082)
		(stroke
			(width 0.087376)
			(type default)
		)
		(layer "F.Cu")
	)
	(gr_line
		(start 38.093396 -77.79004)
		(end 39.200074 -77.79004)
		(stroke
			(width 0.087376)
			(type default)
		)
		(layer "F.Cu")
	)
	(gr_line
		(start 38.093396 -67.39001)
		(end 39.200074 -67.39001)
		(stroke
			(width 0.087376)
			(type default)
		)
		(layer "F.Cu")
	)
	(gr_line
		(start 38.093396 -57.789826)
		(end 39.200074 -57.789826)
		(stroke
			(width 0.087376)
			(type default)
		)
		(layer "F.Cu")
	)
	(gr_line
		(start 38.093396 -56.98998)
		(end 39.200074 -56.98998)
		(stroke
			(width 0.087376)
			(type default)
		)
		(layer "F.Cu")
	)
	(gr_line
		(start 38.093396 -55.390034)
		(end 39.200074 -55.390034)
		(stroke
			(width 0.087376)
			(type default)
		)
		(layer "F.Cu")
	)
	(gr_line
		(start 38.093396 -52.189888)
		(end 39.200074 -52.189888)
		(stroke
			(width 0.087376)
			(type default)
		)
		(layer "F.Cu")
	)
	(gr_line
		(start 38.09365 -363.590078)
		(end 39.200074 -363.590078)
		(stroke
			(width 0.087376)
			(type default)
		)
		(layer "F.Cu")
	)
	(gr_line
		(start 38.09365 -361.990132)
		(end 39.200074 -361.990132)
		(stroke
			(width 0.087376)
			(type default)
		)
		(layer "F.Cu")
	)
	(gr_line
		(start 38.09365 -278.189944)
		(end 39.200074 -278.189944)
		(stroke
			(width 0.087376)
			(type default)
		)
		(layer "F.Cu")
	)
	(gr_line
		(start 38.09365 -275.789898)
		(end 39.200074 -275.789898)
		(stroke
			(width 0.087376)
			(type default)
		)
		(layer "F.Cu")
	)
	(gr_line
		(start 38.09365 -260.59003)
		(end 39.200074 -260.59003)
		(stroke
			(width 0.087376)
			(type default)
		)
		(layer "F.Cu")
	)
	(gr_line
		(start 38.09365 -258.990084)
		(end 39.200074 -258.990084)
		(stroke
			(width 0.087376)
			(type default)
		)
		(layer "F.Cu")
	)
	(gr_line
		(start 38.09365 -175.189896)
		(end 39.200074 -175.189896)
		(stroke
			(width 0.087376)
			(type default)
		)
		(layer "F.Cu")
	)
	(gr_line
		(start 38.09365 -172.78985)
		(end 39.200074 -172.78985)
		(stroke
			(width 0.087376)
			(type default)
		)
		(layer "F.Cu")
	)
	(gr_line
		(start 38.09365 -157.589982)
		(end 39.200074 -157.589982)
		(stroke
			(width 0.087376)
			(type default)
		)
		(layer "F.Cu")
	)
	(gr_line
		(start 38.09365 -155.990036)
		(end 39.200074 -155.990036)
		(stroke
			(width 0.087376)
			(type default)
		)
		(layer "F.Cu")
	)
	(gr_line
		(start 38.09365 -76.98994)
		(end 39.200074 -76.98994)
		(stroke
			(width 0.087376)
			(type default)
		)
		(layer "F.Cu")
	)
	(gr_line
		(start 38.09365 -74.589894)
		(end 39.200074 -74.589894)
		(stroke
			(width 0.087376)
			(type default)
		)
		(layer "F.Cu")
	)
	(gr_line
		(start 38.09365 -69.789802)
		(end 39.200074 -69.789802)
		(stroke
			(width 0.087376)
			(type default)
		)
		(layer "F.Cu")
	)
	(gr_line
		(start 38.09365 -54.589934)
		(end 39.200074 -54.589934)
		(stroke
			(width 0.087376)
			(type default)
		)
		(layer "F.Cu")
	)
	(gr_line
		(start 38.09365 -52.989988)
		(end 39.200074 -52.989988)
		(stroke
			(width 0.087376)
			(type default)
		)
		(layer "F.Cu")
	)
	(gr_line
		(start 38.09492 -82.589878)
		(end 39.200074 -82.589878)
		(stroke
			(width 0.085598)
			(type default)
		)
		(layer "F.Cu")
	)
	(gr_line
		(start 38.1 -391.590022)
		(end 39.200074 -391.590022)
		(stroke
			(width 0.085598)
			(type default)
		)
		(layer "F.Cu")
	)
	(gr_line
		(start 38.1 -390.790176)
		(end 39.200074 -390.790176)
		(stroke
			(width 0.085598)
			(type default)
		)
		(layer "F.Cu")
	)
	(gr_line
		(start 38.1 -389.189976)
		(end 39.200074 -389.189976)
		(stroke
			(width 0.087376)
			(type default)
		)
		(layer "F.Cu")
	)
	(gr_line
		(start 38.1 -388.39013)
		(end 39.200074 -388.39013)
		(stroke
			(width 0.087376)
			(type default)
		)
		(layer "F.Cu")
	)
	(gr_line
		(start 38.1 -386.790184)
		(end 39.200074 -386.790184)
		(stroke
			(width 0.087376)
			(type default)
		)
		(layer "F.Cu")
	)
	(gr_line
		(start 38.1 -385.990084)
		(end 39.200074 -385.990084)
		(stroke
			(width 0.087376)
			(type default)
		)
		(layer "F.Cu")
	)
	(gr_line
		(start 38.1 -384.390138)
		(end 39.200074 -384.390138)
		(stroke
			(width 0.087376)
			(type default)
		)
		(layer "F.Cu")
	)
	(gr_line
		(start 38.1 -383.590038)
		(end 39.200074 -383.590038)
		(stroke
			(width 0.087376)
			(type default)
		)
		(layer "F.Cu")
	)
	(gr_line
		(start 38.1 -381.990092)
		(end 39.200074 -381.990092)
		(stroke
			(width 0.087376)
			(type default)
		)
		(layer "F.Cu")
	)
	(gr_line
		(start 38.1 -381.189992)
		(end 39.200074 -381.189992)
		(stroke
			(width 0.087376)
			(type default)
		)
		(layer "F.Cu")
	)
	(gr_line
		(start 38.1 -379.590046)
		(end 39.200074 -379.590046)
		(stroke
			(width 0.087376)
			(type default)
		)
		(layer "F.Cu")
	)
	(gr_line
		(start 38.1 -378.789946)
		(end 39.200074 -378.789946)
		(stroke
			(width 0.087376)
			(type default)
		)
		(layer "F.Cu")
	)
	(gr_line
		(start 38.1 -376.390154)
		(end 39.200074 -376.390154)
		(stroke
			(width 0.087376)
			(type default)
		)
		(layer "F.Cu")
	)
	(gr_line
		(start 38.1 -361.190032)
		(end 39.200074 -361.190032)
		(stroke
			(width 0.087376)
			(type default)
		)
		(layer "F.Cu")
	)
	(gr_line
		(start 38.1 -288.589974)
		(end 39.200074 -288.589974)
		(stroke
			(width 0.085598)
			(type default)
		)
		(layer "F.Cu")
	)
	(gr_line
		(start 38.1 -287.790128)
		(end 39.200074 -287.790128)
		(stroke
			(width 0.085598)
			(type default)
		)
		(layer "F.Cu")
	)
	(gr_line
		(start 38.1 -286.189928)
		(end 39.200074 -286.189928)
		(stroke
			(width 0.087376)
			(type default)
		)
		(layer "F.Cu")
	)
	(gr_line
		(start 38.1 -285.390082)
		(end 39.200074 -285.390082)
		(stroke
			(width 0.087376)
			(type default)
		)
		(layer "F.Cu")
	)
	(gr_line
		(start 38.1 -283.790136)
		(end 39.200074 -283.790136)
		(stroke
			(width 0.087376)
			(type default)
		)
		(layer "F.Cu")
	)
	(gr_line
		(start 38.1 -282.990036)
		(end 39.200074 -282.990036)
		(stroke
			(width 0.087376)
			(type default)
		)
		(layer "F.Cu")
	)
	(gr_line
		(start 38.1 -281.39009)
		(end 39.200074 -281.39009)
		(stroke
			(width 0.087376)
			(type default)
		)
		(layer "F.Cu")
	)
	(gr_line
		(start 38.1 -280.58999)
		(end 39.200074 -280.58999)
		(stroke
			(width 0.087376)
			(type default)
		)
		(layer "F.Cu")
	)
	(gr_line
		(start 38.1 -278.990044)
		(end 39.200074 -278.990044)
		(stroke
			(width 0.087376)
			(type default)
		)
		(layer "F.Cu")
	)
	(gr_line
		(start 38.1 -276.589998)
		(end 39.200074 -276.589998)
		(stroke
			(width 0.087376)
			(type default)
		)
		(layer "F.Cu")
	)
	(gr_line
		(start 38.1 -274.189952)
		(end 39.200074 -274.189952)
		(stroke
			(width 0.087376)
			(type default)
		)
		(layer "F.Cu")
	)
	(gr_line
		(start 38.1 -185.589926)
		(end 39.200074 -185.589926)
		(stroke
			(width 0.085598)
			(type default)
		)
		(layer "F.Cu")
	)
	(gr_line
		(start 38.1 -184.79008)
		(end 39.200074 -184.79008)
		(stroke
			(width 0.085598)
			(type default)
		)
		(layer "F.Cu")
	)
	(gr_line
		(start 38.1 -182.390034)
		(end 39.200074 -182.390034)
		(stroke
			(width 0.087376)
			(type default)
		)
		(layer "F.Cu")
	)
	(gr_line
		(start 38.1 -180.790088)
		(end 39.200074 -180.790088)
		(stroke
			(width 0.087376)
			(type default)
		)
		(layer "F.Cu")
	)
	(gr_line
		(start 38.1 -179.989988)
		(end 39.200074 -179.989988)
		(stroke
			(width 0.087376)
			(type default)
		)
		(layer "F.Cu")
	)
	(gr_line
		(start 38.1 -178.390042)
		(end 39.200074 -178.390042)
		(stroke
			(width 0.087376)
			(type default)
		)
		(layer "F.Cu")
	)
	(gr_line
		(start 38.1 -177.589942)
		(end 39.200074 -177.589942)
		(stroke
			(width 0.087376)
			(type default)
		)
		(layer "F.Cu")
	)
	(gr_line
		(start 38.1 -175.989996)
		(end 39.200074 -175.989996)
		(stroke
			(width 0.087376)
			(type default)
		)
		(layer "F.Cu")
	)
	(gr_line
		(start 38.1 -173.58995)
		(end 39.200074 -173.58995)
		(stroke
			(width 0.087376)
			(type default)
		)
		(layer "F.Cu")
	)
	(gr_line
		(start 38.1 -171.189904)
		(end 39.200074 -171.189904)
		(stroke
			(width 0.087376)
			(type default)
		)
		(layer "F.Cu")
	)
	(gr_line
		(start 38.1 -81.790032)
		(end 39.200074 -81.790032)
		(stroke
			(width 0.085598)
			(type default)
		)
		(layer "F.Cu")
	)
	(gr_line
		(start 38.1 -80.189832)
		(end 39.200074 -80.189832)
		(stroke
			(width 0.087376)
			(type default)
		)
		(layer "F.Cu")
	)
	(gr_line
		(start 38.1 -79.389986)
		(end 39.200074 -79.389986)
		(stroke
			(width 0.087376)
			(type default)
		)
		(layer "F.Cu")
	)
	(gr_line
		(start 38.1 -75.389994)
		(end 39.200074 -75.389994)
		(stroke
			(width 0.087376)
			(type default)
		)
		(layer "F.Cu")
	)
	(gr_line
		(start 38.1 -72.989948)
		(end 39.200074 -72.989948)
		(stroke
			(width 0.087376)
			(type default)
		)
		(layer "F.Cu")
	)
	(gr_line
		(start 38.1 -72.189848)
		(end 39.200074 -72.189848)
		(stroke
			(width 0.087376)
			(type default)
		)
		(layer "F.Cu")
	)
	(gr_line
		(start 38.1 -70.589902)
		(end 39.200074 -70.589902)
		(stroke
			(width 0.087376)
			(type default)
		)
		(layer "F.Cu")
	)
	(gr_line
		(start 38.104064 -155.189936)
		(end 39.200074 -155.189936)
		(stroke
			(width 0.087376)
			(type default)
		)
		(layer "F.Cu")
	)
	(gr_line
		(start 38.11397 -366.78997)
		(end 39.200074 -366.78997)
		(stroke
			(width 0.087376)
			(type default)
		)
		(layer "F.Cu")
	)
	(gr_line
		(start 38.126924 -262.990076)
		(end 39.200074 -262.990076)
		(stroke
			(width 0.087376)
			(type default)
		)
		(layer "F.Cu")
	)
	(gr_line
		(start 38.261036 -130.34137)
		(end 38.438074 -130.34137)
		(stroke
			(width 0.087376)
			(type default)
		)
		(layer "F.Cu")
	)
	(gr_line
		(start 38.32352 -130.891026)
		(end 38.439852 -130.774694)
		(stroke
			(width 0.087376)
			(type default)
		)
		(layer "F.Cu")
	)
	(gr_line
		(start 38.81247 -129.789936)
		(end 38.81247 -129.966974)
		(stroke
			(width 0.087376)
			(type default)
		)
		(layer "F.Cu")
	)
	(gr_line
		(start 38.81247 -129.789936)
		(end 39.183056 -129.419096)
		(stroke
			(width 0.087376)
			(type default)
		)
		(layer "F.Cu")
	)
	(gr_line
		(start 39.082472 -33.165034)
		(end 39.207694 -33.290256)
		(stroke
			(width 0.087376)
			(type default)
		)
		(layer "F.Cu")
	)
	(gr_line
		(start 39.183056 -129.419096)
		(end 39.360348 -129.419096)
		(stroke
			(width 0.087376)
			(type default)
		)
		(layer "F.Cu")
	)
	(gr_line
		(start 39.207694 -33.290256)
		(end 39.73195 -33.290256)
		(stroke
			(width 0.087376)
			(type default)
		)
		(layer "F.Cu")
	)
	(gr_line
		(start 39.245794 -129.968752)
		(end 39.362126 -129.85242)
		(stroke
			(width 0.087376)
			(type default)
		)
		(layer "F.Cu")
	)
	(gr_line
		(start 39.387526 -32.85744)
		(end 39.552118 -32.85744)
		(stroke
			(width 0.087376)
			(type default)
		)
		(layer "F.Cu")
	)
	(gr_line
		(start 39.73195 -33.290256)
		(end 39.857172 -33.165034)
		(stroke
			(width 0.087376)
			(type default)
		)
		(layer "F.Cu")
	)
	(gr_line
		(start 40.386508 -33.165034)
		(end 40.51173 -33.290256)
		(stroke
			(width 0.087376)
			(type default)
		)
		(layer "F.Cu")
	)
	(gr_line
		(start 40.51173 -33.290256)
		(end 41.035986 -33.290256)
		(stroke
			(width 0.087376)
			(type default)
		)
		(layer "F.Cu")
	)
	(gr_line
		(start 40.555418 -338.25053)
		(end 40.68064 -338.125308)
		(stroke
			(width 0.087376)
			(type default)
		)
		(layer "F.Cu")
	)
	(gr_line
		(start 40.68064 -338.125308)
		(end 41.204896 -338.125308)
		(stroke
			(width 0.087376)
			(type default)
		)
		(layer "F.Cu")
	)
	(gr_line
		(start 40.691562 -32.85744)
		(end 40.856154 -32.85744)
		(stroke
			(width 0.087376)
			(type default)
		)
		(layer "F.Cu")
	)
	(gr_line
		(start 40.860472 -338.558124)
		(end 41.025064 -338.558124)
		(stroke
			(width 0.087376)
			(type default)
		)
		(layer "F.Cu")
	)
	(gr_line
		(start 41.035986 -33.290256)
		(end 41.161208 -33.165034)
		(stroke
			(width 0.087376)
			(type default)
		)
		(layer "F.Cu")
	)
	(gr_line
		(start 41.204896 -338.125308)
		(end 41.330118 -338.25053)
		(stroke
			(width 0.087376)
			(type default)
		)
		(layer "F.Cu")
	)
	(gr_line
		(start 41.859454 -338.25053)
		(end 41.984676 -338.125308)
		(stroke
			(width 0.087376)
			(type default)
		)
		(layer "F.Cu")
	)
	(gr_line
		(start 41.945052 -138.975338)
		(end 43.015662 -138.975338)
		(stroke
			(width 0.085598)
			(type default)
		)
		(layer "F.Cu")
	)
	(gr_line
		(start 41.945052 -138.325098)
		(end 42.881042 -138.325098)
		(stroke
			(width 0.085598)
			(type default)
		)
		(layer "F.Cu")
	)
	(gr_line
		(start 41.984676 -338.125308)
		(end 42.508932 -338.125308)
		(stroke
			(width 0.087376)
			(type default)
		)
		(layer "F.Cu")
	)
	(gr_line
		(start 42.164508 -338.558124)
		(end 42.3291 -338.558124)
		(stroke
			(width 0.087376)
			(type default)
		)
		(layer "F.Cu")
	)
	(gr_line
		(start 42.39006 -473.390214)
		(end 43.567604 -473.390214)
		(stroke
			(width 0.087376)
			(type default)
		)
		(layer "F.Cu")
	)
	(gr_line
		(start 42.39006 -472.590114)
		(end 43.561 -472.590114)
		(stroke
			(width 0.087376)
			(type default)
		)
		(layer "F.Cu")
	)
	(gr_line
		(start 42.39006 -370.390166)
		(end 43.440604 -370.390166)
		(stroke
			(width 0.087376)
			(type default)
		)
		(layer "F.Cu")
	)
	(gr_line
		(start 42.39006 -369.590066)
		(end 43.434 -369.590066)
		(stroke
			(width 0.087376)
			(type default)
		)
		(layer "F.Cu")
	)
	(gr_line
		(start 42.39006 -267.390118)
		(end 43.434 -267.390118)
		(stroke
			(width 0.087376)
			(type default)
		)
		(layer "F.Cu")
	)
	(gr_line
		(start 42.39006 -266.590018)
		(end 43.434 -266.590018)
		(stroke
			(width 0.087376)
			(type default)
		)
		(layer "F.Cu")
	)
	(gr_line
		(start 42.39006 -164.39007)
		(end 43.440604 -164.39007)
		(stroke
			(width 0.087376)
			(type default)
		)
		(layer "F.Cu")
	)
	(gr_line
		(start 42.39006 -163.58997)
		(end 43.434 -163.58997)
		(stroke
			(width 0.087376)
			(type default)
		)
		(layer "F.Cu")
	)
	(gr_line
		(start 42.39006 -61.390022)
		(end 43.440604 -61.390022)
		(stroke
			(width 0.087376)
			(type default)
		)
		(layer "F.Cu")
	)
	(gr_line
		(start 42.39006 -60.589922)
		(end 43.434 -60.589922)
		(stroke
			(width 0.087376)
			(type default)
		)
		(layer "F.Cu")
	)
	(gr_line
		(start 42.418 -239.397286)
		(end 42.606976 -239.20831)
		(stroke
			(width 0.087376)
			(type default)
		)
		(layer "F.Cu")
	)
	(gr_line
		(start 42.418 -238.584486)
		(end 42.606976 -238.773462)
		(stroke
			(width 0.087376)
			(type default)
		)
		(layer "F.Cu")
	)
	(gr_line
		(start 42.508932 -338.125308)
		(end 42.634154 -338.25053)
		(stroke
			(width 0.087376)
			(type default)
		)
		(layer "F.Cu")
	)
	(gr_line
		(start 43.16349 -338.25053)
		(end 43.288712 -338.125308)
		(stroke
			(width 0.087376)
			(type default)
		)
		(layer "F.Cu")
	)
	(gr_line
		(start 43.288712 -338.125308)
		(end 43.812968 -338.125308)
		(stroke
			(width 0.087376)
			(type default)
		)
		(layer "F.Cu")
	)
	(gr_line
		(start 43.434 -369.590066)
		(end 43.619928 -369.775994)
		(stroke
			(width 0.087376)
			(type default)
		)
		(layer "F.Cu")
	)
	(gr_line
		(start 43.434 -267.390118)
		(end 43.616626 -267.207492)
		(stroke
			(width 0.087376)
			(type default)
		)
		(layer "F.Cu")
	)
	(gr_line
		(start 43.434 -266.590018)
		(end 43.616626 -266.772644)
		(stroke
			(width 0.087376)
			(type default)
		)
		(layer "F.Cu")
	)
	(gr_line
		(start 43.434 -163.58997)
		(end 43.619928 -163.775898)
		(stroke
			(width 0.087376)
			(type default)
		)
		(layer "F.Cu")
	)
	(gr_line
		(start 43.434 -60.589922)
		(end 43.619928 -60.77585)
		(stroke
			(width 0.087376)
			(type default)
		)
		(layer "F.Cu")
	)
	(gr_line
		(start 43.440604 -370.390166)
		(end 43.619928 -370.210842)
		(stroke
			(width 0.087376)
			(type default)
		)
		(layer "F.Cu")
	)
	(gr_line
		(start 43.440604 -164.39007)
		(end 43.619928 -164.210746)
		(stroke
			(width 0.087376)
			(type default)
		)
		(layer "F.Cu")
	)
	(gr_line
		(start 43.440604 -61.390022)
		(end 43.619928 -61.210698)
		(stroke
			(width 0.087376)
			(type default)
		)
		(layer "F.Cu")
	)
	(gr_line
		(start 43.468544 -338.558124)
		(end 43.633136 -338.558124)
		(stroke
			(width 0.087376)
			(type default)
		)
		(layer "F.Cu")
	)
	(gr_line
		(start 43.561 -472.590114)
		(end 43.746928 -472.776042)
		(stroke
			(width 0.087376)
			(type default)
		)
		(layer "F.Cu")
	)
	(gr_line
		(start 43.567604 -473.390214)
		(end 43.746928 -473.21089)
		(stroke
			(width 0.087376)
			(type default)
		)
		(layer "F.Cu")
	)
	(gr_line
		(start 43.812968 -338.125308)
		(end 43.93819 -338.25053)
		(stroke
			(width 0.087376)
			(type default)
		)
		(layer "F.Cu")
	)
	(gr_line
		(start 43.913552 -462.53654)
		(end 44.038774 -462.661762)
		(stroke
			(width 0.087376)
			(type default)
		)
		(layer "F.Cu")
	)
	(gr_line
		(start 44.038774 -462.661762)
		(end 44.56303 -462.661762)
		(stroke
			(width 0.087376)
			(type default)
		)
		(layer "F.Cu")
	)
	(gr_line
		(start 44.218606 -462.228946)
		(end 44.383198 -462.228946)
		(stroke
			(width 0.087376)
			(type default)
		)
		(layer "F.Cu")
	)
	(gr_line
		(start 44.56303 -462.661762)
		(end 44.688252 -462.53654)
		(stroke
			(width 0.087376)
			(type default)
		)
		(layer "F.Cu")
	)
	(gr_line
		(start 44.9072 -471.790268)
		(end 45.096176 -471.979244)
		(stroke
			(width 0.087376)
			(type default)
		)
		(layer "F.Cu")
	)
	(gr_line
		(start 44.9072 -368.79022)
		(end 45.096176 -368.979196)
		(stroke
			(width 0.087376)
			(type default)
		)
		(layer "F.Cu")
	)
	(gr_line
		(start 44.9072 -265.790172)
		(end 45.096176 -265.979148)
		(stroke
			(width 0.087376)
			(type default)
		)
		(layer "F.Cu")
	)
	(gr_line
		(start 44.9072 -162.790124)
		(end 45.096176 -162.9791)
		(stroke
			(width 0.087376)
			(type default)
		)
		(layer "F.Cu")
	)
	(gr_line
		(start 44.9072 -59.790076)
		(end 45.096176 -59.979052)
		(stroke
			(width 0.087376)
			(type default)
		)
		(layer "F.Cu")
	)
	(gr_line
		(start 45.217588 -462.53654)
		(end 45.34281 -462.661762)
		(stroke
			(width 0.087376)
			(type default)
		)
		(layer "F.Cu")
	)
	(gr_line
		(start 45.34281 -462.661762)
		(end 45.867066 -462.661762)
		(stroke
			(width 0.087376)
			(type default)
		)
		(layer "F.Cu")
	)
	(gr_line
		(start 45.522642 -462.228946)
		(end 45.687234 -462.228946)
		(stroke
			(width 0.087376)
			(type default)
		)
		(layer "F.Cu")
	)
	(gr_line
		(start 45.531024 -471.979244)
		(end 45.72 -471.790268)
		(stroke
			(width 0.087376)
			(type default)
		)
		(layer "F.Cu")
	)
	(gr_line
		(start 45.531024 -368.979196)
		(end 45.72 -368.79022)
		(stroke
			(width 0.087376)
			(type default)
		)
		(layer "F.Cu")
	)
	(gr_line
		(start 45.531024 -265.979148)
		(end 45.72 -265.790172)
		(stroke
			(width 0.087376)
			(type default)
		)
		(layer "F.Cu")
	)
	(gr_line
		(start 45.531024 -162.9791)
		(end 45.72 -162.790124)
		(stroke
			(width 0.087376)
			(type default)
		)
		(layer "F.Cu")
	)
	(gr_line
		(start 45.531024 -59.979052)
		(end 45.72 -59.790076)
		(stroke
			(width 0.087376)
			(type default)
		)
		(layer "F.Cu")
	)
	(gr_line
		(start 45.867066 -462.661762)
		(end 45.992288 -462.53654)
		(stroke
			(width 0.087376)
			(type default)
		)
		(layer "F.Cu")
	)
	(gr_line
		(start 45.88764 -51.148488)
		(end 46.25848 -51.519074)
		(stroke
			(width 0.087376)
			(type default)
		)
		(layer "F.Cu")
	)
	(gr_line
		(start 45.88764 -50.971196)
		(end 45.88764 -51.148488)
		(stroke
			(width 0.087376)
			(type default)
		)
		(layer "F.Cu")
	)
	(gr_line
		(start 46.04893 -134.75843)
		(end 46.1645 -134.874)
		(stroke
			(width 0.085598)
			(type default)
		)
		(layer "F.Cu")
	)
	(gr_line
		(start 46.04893 -133.97357)
		(end 46.1645 -133.858)
		(stroke
			(width 0.085598)
			(type default)
		)
		(layer "F.Cu")
	)
	(gr_line
		(start 46.137068 -28.171394)
		(end 46.26229 -28.296616)
		(stroke
			(width 0.087376)
			(type default)
		)
		(layer "F.Cu")
	)
	(gr_line
		(start 46.25848 -51.519074)
		(end 46.435518 -51.519074)
		(stroke
			(width 0.087376)
			(type default)
		)
		(layer "F.Cu")
	)
	(gr_line
		(start 46.26229 -28.296616)
		(end 46.786546 -28.296616)
		(stroke
			(width 0.087376)
			(type default)
		)
		(layer "F.Cu")
	)
	(gr_line
		(start 46.320964 -50.969418)
		(end 46.437296 -51.08575)
		(stroke
			(width 0.087376)
			(type default)
		)
		(layer "F.Cu")
	)
	(gr_line
		(start 46.442122 -27.8638)
		(end 46.606714 -27.8638)
		(stroke
			(width 0.087376)
			(type default)
		)
		(layer "F.Cu")
	)
	(gr_line
		(start 46.521624 -462.53654)
		(end 46.646846 -462.661762)
		(stroke
			(width 0.087376)
			(type default)
		)
		(layer "F.Cu")
	)
	(gr_line
		(start 46.569376 -205.2828)
		(end 47.19955 -205.2828)
		(stroke
			(width 0.085598)
			(type default)
		)
		(layer "F.Cu")
	)
	(gr_line
		(start 46.646846 -462.661762)
		(end 47.171102 -462.661762)
		(stroke
			(width 0.087376)
			(type default)
		)
		(layer "F.Cu")
	)
	(gr_line
		(start 46.786546 -28.296616)
		(end 46.911768 -28.171394)
		(stroke
			(width 0.087376)
			(type default)
		)
		(layer "F.Cu")
	)
	(gr_line
		(start 46.809914 -52.070508)
		(end 47.1805 -52.441348)
		(stroke
			(width 0.087376)
			(type default)
		)
		(layer "F.Cu")
	)
	(gr_line
		(start 46.809914 -51.89347)
		(end 46.809914 -52.070508)
		(stroke
			(width 0.087376)
			(type default)
		)
		(layer "F.Cu")
	)
	(gr_line
		(start 46.826678 -462.228946)
		(end 46.99127 -462.228946)
		(stroke
			(width 0.087376)
			(type default)
		)
		(layer "F.Cu")
	)
	(gr_line
		(start 47.11954 -338.25053)
		(end 47.244762 -338.125308)
		(stroke
			(width 0.087376)
			(type default)
		)
		(layer "F.Cu")
	)
	(gr_line
		(start 47.171102 -462.661762)
		(end 47.296324 -462.53654)
		(stroke
			(width 0.087376)
			(type default)
		)
		(layer "F.Cu")
	)
	(gr_line
		(start 47.1805 -52.441348)
		(end 47.357792 -52.441348)
		(stroke
			(width 0.087376)
			(type default)
		)
		(layer "F.Cu")
	)
	(gr_line
		(start 47.19955 -205.2828)
		(end 47.254668 -205.227682)
		(stroke
			(width 0.085598)
			(type default)
		)
		(layer "F.Cu")
	)
	(gr_line
		(start 47.243238 -51.891692)
		(end 47.35957 -52.008024)
		(stroke
			(width 0.087376)
			(type default)
		)
		(layer "F.Cu")
	)
	(gr_line
		(start 47.244762 -338.125308)
		(end 47.769018 -338.125308)
		(stroke
			(width 0.087376)
			(type default)
		)
		(layer "F.Cu")
	)
	(gr_line
		(start 47.424594 -338.558124)
		(end 47.589186 -338.558124)
		(stroke
			(width 0.087376)
			(type default)
		)
		(layer "F.Cu")
	)
	(gr_line
		(start 47.441104 -28.171394)
		(end 47.566326 -28.296616)
		(stroke
			(width 0.087376)
			(type default)
		)
		(layer "F.Cu")
	)
	(gr_line
		(start 47.566326 -28.296616)
		(end 48.090582 -28.296616)
		(stroke
			(width 0.087376)
			(type default)
		)
		(layer "F.Cu")
	)
	(gr_line
		(start 47.692564 -255.73609)
		(end 47.808896 -255.619758)
		(stroke
			(width 0.087376)
			(type default)
		)
		(layer "F.Cu")
	)
	(gr_line
		(start 47.694342 -256.169414)
		(end 47.871634 -256.169414)
		(stroke
			(width 0.087376)
			(type default)
		)
		(layer "F.Cu")
	)
	(gr_line
		(start 47.731934 -52.992528)
		(end 48.102774 -53.363368)
		(stroke
			(width 0.087376)
			(type default)
		)
		(layer "F.Cu")
	)
	(gr_line
		(start 47.731934 -52.81549)
		(end 47.731934 -52.992528)
		(stroke
			(width 0.087376)
			(type default)
		)
		(layer "F.Cu")
	)
	(gr_line
		(start 47.746158 -27.8638)
		(end 47.91075 -27.8638)
		(stroke
			(width 0.087376)
			(type default)
		)
		(layer "F.Cu")
	)
	(gr_line
		(start 47.769018 -338.125308)
		(end 47.89424 -338.25053)
		(stroke
			(width 0.087376)
			(type default)
		)
		(layer "F.Cu")
	)
	(gr_line
		(start 47.871634 -256.169414)
		(end 48.24222 -255.798574)
		(stroke
			(width 0.087376)
			(type default)
		)
		(layer "F.Cu")
	)
	(gr_line
		(start 48.039782 -205.227682)
		(end 48.0949 -205.2828)
		(stroke
			(width 0.085598)
			(type default)
		)
		(layer "F.Cu")
	)
	(gr_line
		(start 48.090582 -28.296616)
		(end 48.215804 -28.171394)
		(stroke
			(width 0.087376)
			(type default)
		)
		(layer "F.Cu")
	)
	(gr_line
		(start 48.0949 -205.2828)
		(end 48.474376 -205.2828)
		(stroke
			(width 0.085598)
			(type default)
		)
		(layer "F.Cu")
	)
	(gr_line
		(start 48.102774 -53.363368)
		(end 48.279812 -53.363368)
		(stroke
			(width 0.087376)
			(type default)
		)
		(layer "F.Cu")
	)
	(gr_line
		(start 48.165258 -52.813712)
		(end 48.28159 -52.930044)
		(stroke
			(width 0.087376)
			(type default)
		)
		(layer "F.Cu")
	)
	(gr_line
		(start 48.24222 -255.621536)
		(end 48.24222 -255.798574)
		(stroke
			(width 0.087376)
			(type default)
		)
		(layer "F.Cu")
	)
	(gr_line
		(start 48.387 -473.392246)
		(end 48.575976 -473.20327)
		(stroke
			(width 0.087376)
			(type default)
		)
		(layer "F.Cu")
	)
	(gr_line
		(start 48.387 -472.579446)
		(end 48.575976 -472.768422)
		(stroke
			(width 0.087376)
			(type default)
		)
		(layer "F.Cu")
	)
	(gr_line
		(start 48.387 -370.392198)
		(end 48.575976 -370.203222)
		(stroke
			(width 0.087376)
			(type default)
		)
		(layer "F.Cu")
	)
	(gr_line
		(start 48.387 -369.579398)
		(end 48.575976 -369.768374)
		(stroke
			(width 0.087376)
			(type default)
		)
		(layer "F.Cu")
	)
	(gr_line
		(start 48.387 -267.39215)
		(end 48.575976 -267.203174)
		(stroke
			(width 0.087376)
			(type default)
		)
		(layer "F.Cu")
	)
	(gr_line
		(start 48.387 -266.57935)
		(end 48.575976 -266.768326)
		(stroke
			(width 0.087376)
			(type default)
		)
		(layer "F.Cu")
	)
	(gr_line
		(start 48.387 -164.392102)
		(end 48.575976 -164.203126)
		(stroke
			(width 0.087376)
			(type default)
		)
		(layer "F.Cu")
	)
	(gr_line
		(start 48.387 -163.579302)
		(end 48.575976 -163.768278)
		(stroke
			(width 0.087376)
			(type default)
		)
		(layer "F.Cu")
	)
	(gr_line
		(start 48.387 -61.392054)
		(end 48.575976 -61.203078)
		(stroke
			(width 0.087376)
			(type default)
		)
		(layer "F.Cu")
	)
	(gr_line
		(start 48.387 -60.579254)
		(end 48.575976 -60.76823)
		(stroke
			(width 0.087376)
			(type default)
		)
		(layer "F.Cu")
	)
	(gr_line
		(start 48.422306 -358.637586)
		(end 48.538638 -358.521254)
		(stroke
			(width 0.087376)
			(type default)
		)
		(layer "F.Cu")
	)
	(gr_line
		(start 48.423576 -338.25053)
		(end 48.548798 -338.125308)
		(stroke
			(width 0.087376)
			(type default)
		)
		(layer "F.Cu")
	)
	(gr_line
		(start 48.424084 -359.07091)
		(end 48.601122 -359.07091)
		(stroke
			(width 0.087376)
			(type default)
		)
		(layer "F.Cu")
	)
	(gr_line
		(start 48.548798 -338.125308)
		(end 49.073054 -338.125308)
		(stroke
			(width 0.087376)
			(type default)
		)
		(layer "F.Cu")
	)
	(gr_line
		(start 48.601122 -359.07091)
		(end 48.971962 -358.700324)
		(stroke
			(width 0.087376)
			(type default)
		)
		(layer "F.Cu")
	)
	(gr_line
		(start 48.614838 -254.813816)
		(end 48.73117 -254.697484)
		(stroke
			(width 0.087376)
			(type default)
		)
		(layer "F.Cu")
	)
	(gr_line
		(start 48.616616 -255.24714)
		(end 48.793654 -255.24714)
		(stroke
			(width 0.087376)
			(type default)
		)
		(layer "F.Cu")
	)
	(gr_line
		(start 48.72863 -338.558124)
		(end 48.893222 -338.558124)
		(stroke
			(width 0.087376)
			(type default)
		)
		(layer "F.Cu")
	)
	(gr_line
		(start 48.793654 -255.24714)
		(end 49.164494 -254.876554)
		(stroke
			(width 0.087376)
			(type default)
		)
		(layer "F.Cu")
	)
	(gr_line
		(start 48.886364 -152.86609)
		(end 49.002696 -152.749758)
		(stroke
			(width 0.087376)
			(type default)
		)
		(layer "F.Cu")
	)
	(gr_line
		(start 48.888142 -153.299414)
		(end 49.065434 -153.299414)
		(stroke
			(width 0.087376)
			(type default)
		)
		(layer "F.Cu")
	)
	(gr_line
		(start 48.971962 -358.523032)
		(end 48.971962 -358.700324)
		(stroke
			(width 0.087376)
			(type default)
		)
		(layer "F.Cu")
	)
	(gr_line
		(start 49.065434 -153.299414)
		(end 49.43602 -152.928574)
		(stroke
			(width 0.087376)
			(type default)
		)
		(layer "F.Cu")
	)
	(gr_line
		(start 49.073054 -338.125308)
		(end 49.198276 -338.25053)
		(stroke
			(width 0.087376)
			(type default)
		)
		(layer "F.Cu")
	)
	(gr_line
		(start 49.164494 -254.699262)
		(end 49.164494 -254.876554)
		(stroke
			(width 0.087376)
			(type default)
		)
		(layer "F.Cu")
	)
	(gr_line
		(start 49.344326 -357.715566)
		(end 49.460658 -357.599234)
		(stroke
			(width 0.087376)
			(type default)
		)
		(layer "F.Cu")
	)
	(gr_line
		(start 49.346104 -358.14889)
		(end 49.523396 -358.14889)
		(stroke
			(width 0.087376)
			(type default)
		)
		(layer "F.Cu")
	)
	(gr_line
		(start 49.43602 -152.751536)
		(end 49.43602 -152.928574)
		(stroke
			(width 0.087376)
			(type default)
		)
		(layer "F.Cu")
	)
	(gr_line
		(start 49.523396 -358.14889)
		(end 49.893982 -357.77805)
		(stroke
			(width 0.087376)
			(type default)
		)
		(layer "F.Cu")
	)
	(gr_line
		(start 49.536858 -253.891796)
		(end 49.65319 -253.775464)
		(stroke
			(width 0.087376)
			(type default)
		)
		(layer "F.Cu")
	)
	(gr_line
		(start 49.538636 -254.32512)
		(end 49.715674 -254.32512)
		(stroke
			(width 0.087376)
			(type default)
		)
		(layer "F.Cu")
	)
	(gr_line
		(start 49.715674 -254.32512)
		(end 50.086514 -253.95428)
		(stroke
			(width 0.087376)
			(type default)
		)
		(layer "F.Cu")
	)
	(gr_line
		(start 49.808638 -151.943816)
		(end 49.92497 -151.827484)
		(stroke
			(width 0.087376)
			(type default)
		)
		(layer "F.Cu")
	)
	(gr_line
		(start 49.810416 -152.37714)
		(end 49.987454 -152.37714)
		(stroke
			(width 0.087376)
			(type default)
		)
		(layer "F.Cu")
	)
	(gr_line
		(start 49.893982 -357.601012)
		(end 49.893982 -357.77805)
		(stroke
			(width 0.087376)
			(type default)
		)
		(layer "F.Cu")
	)
	(gr_line
		(start 49.987454 -152.37714)
		(end 50.358294 -152.006554)
		(stroke
			(width 0.087376)
			(type default)
		)
		(layer "F.Cu")
	)
	(gr_line
		(start 50.079402 -55.339996)
		(end 50.449988 -55.710836)
		(stroke
			(width 0.087376)
			(type default)
		)
		(layer "F.Cu")
	)
	(gr_line
		(start 50.079402 -55.162958)
		(end 50.079402 -55.339996)
		(stroke
			(width 0.087376)
			(type default)
		)
		(layer "F.Cu")
	)
	(gr_line
		(start 50.086514 -253.777242)
		(end 50.086514 -253.95428)
		(stroke
			(width 0.087376)
			(type default)
		)
		(layer "F.Cu")
	)
	(gr_line
		(start 50.229516 -472.830652)
		(end 50.354738 -472.70543)
		(stroke
			(width 0.087376)
			(type default)
		)
		(layer "F.Cu")
	)
	(gr_line
		(start 50.266346 -356.793546)
		(end 50.382678 -356.677214)
		(stroke
			(width 0.087376)
			(type default)
		)
		(layer "F.Cu")
	)
	(gr_line
		(start 50.268124 -357.22687)
		(end 50.445416 -357.22687)
		(stroke
			(width 0.087376)
			(type default)
		)
		(layer "F.Cu")
	)
	(gr_line
		(start 50.354738 -472.70543)
		(end 50.878994 -472.70543)
		(stroke
			(width 0.087376)
			(type default)
		)
		(layer "F.Cu")
	)
	(gr_line
		(start 50.358294 -151.829262)
		(end 50.358294 -152.006554)
		(stroke
			(width 0.087376)
			(type default)
		)
		(layer "F.Cu")
	)
	(gr_line
		(start 50.445416 -357.22687)
		(end 50.816002 -356.85603)
		(stroke
			(width 0.087376)
			(type default)
		)
		(layer "F.Cu")
	)
	(gr_line
		(start 50.449988 -55.710836)
		(end 50.62728 -55.710836)
		(stroke
			(width 0.087376)
			(type default)
		)
		(layer "F.Cu")
	)
	(gr_line
		(start 50.512726 -55.16118)
		(end 50.629058 -55.277512)
		(stroke
			(width 0.087376)
			(type default)
		)
		(layer "F.Cu")
	)
	(gr_line
		(start 50.527966 -61.140594)
		(end 50.653188 -61.265816)
		(stroke
			(width 0.087376)
			(type default)
		)
		(layer "F.Cu")
	)
	(gr_line
		(start 50.53457 -473.138246)
		(end 50.699162 -473.138246)
		(stroke
			(width 0.087376)
			(type default)
		)
		(layer "F.Cu")
	)
	(gr_line
		(start 50.545238 -162.034982)
		(end 50.67046 -162.160204)
		(stroke
			(width 0.087376)
			(type default)
		)
		(layer "F.Cu")
	)
	(gr_line
		(start 50.545238 -161.510726)
		(end 50.545238 -162.034982)
		(stroke
			(width 0.087376)
			(type default)
		)
		(layer "F.Cu")
	)
	(gr_line
		(start 50.545238 -161.510726)
		(end 50.67046 -161.385504)
		(stroke
			(width 0.087376)
			(type default)
		)
		(layer "F.Cu")
	)
	(gr_line
		(start 50.545238 -160.730946)
		(end 50.67046 -160.856168)
		(stroke
			(width 0.087376)
			(type default)
		)
		(layer "F.Cu")
	)
	(gr_line
		(start 50.545238 -160.20669)
		(end 50.545238 -160.730946)
		(stroke
			(width 0.087376)
			(type default)
		)
		(layer "F.Cu")
	)
	(gr_line
		(start 50.545238 -160.20669)
		(end 50.67046 -160.081468)
		(stroke
			(width 0.087376)
			(type default)
		)
		(layer "F.Cu")
	)
	(gr_line
		(start 50.545238 -159.42691)
		(end 50.67046 -159.552132)
		(stroke
			(width 0.087376)
			(type default)
		)
		(layer "F.Cu")
	)
	(gr_line
		(start 50.545238 -158.902654)
		(end 50.545238 -159.42691)
		(stroke
			(width 0.087376)
			(type default)
		)
		(layer "F.Cu")
	)
	(gr_line
		(start 50.545238 -158.902654)
		(end 50.67046 -158.777432)
		(stroke
			(width 0.087376)
			(type default)
		)
		(layer "F.Cu")
	)
	(gr_line
		(start 50.653188 -61.265816)
		(end 51.177444 -61.265816)
		(stroke
			(width 0.087376)
			(type default)
		)
		(layer "F.Cu")
	)
	(gr_line
		(start 50.673 -155.91028)
		(end 50.734976 -155.848304)
		(stroke
			(width 0.087376)
			(type default)
		)
		(layer "F.Cu")
	)
	(gr_line
		(start 50.730658 -151.021796)
		(end 50.84699 -150.905464)
		(stroke
			(width 0.087376)
			(type default)
		)
		(layer "F.Cu")
	)
	(gr_line
		(start 50.732436 -151.45512)
		(end 50.909474 -151.45512)
		(stroke
			(width 0.087376)
			(type default)
		)
		(layer "F.Cu")
	)
	(gr_line
		(start 50.816002 -356.678992)
		(end 50.816002 -356.85603)
		(stroke
			(width 0.087376)
			(type default)
		)
		(layer "F.Cu")
	)
	(gr_line
		(start 50.83302 -60.833)
		(end 50.997612 -60.833)
		(stroke
			(width 0.087376)
			(type default)
		)
		(layer "F.Cu")
	)
	(gr_line
		(start 50.878994 -472.70543)
		(end 51.004216 -472.830652)
		(stroke
			(width 0.087376)
			(type default)
		)
		(layer "F.Cu")
	)
	(gr_line
		(start 50.909474 -151.45512)
		(end 51.280314 -151.08428)
		(stroke
			(width 0.087376)
			(type default)
		)
		(layer "F.Cu")
	)
	(gr_line
		(start 50.978054 -161.690558)
		(end 50.978054 -161.85515)
		(stroke
			(width 0.087376)
			(type default)
		)
		(layer "F.Cu")
	)
	(gr_line
		(start 50.978054 -160.386522)
		(end 50.978054 -160.551114)
		(stroke
			(width 0.087376)
			(type default)
		)
		(layer "F.Cu")
	)
	(gr_line
		(start 50.978054 -159.082486)
		(end 50.978054 -159.247078)
		(stroke
			(width 0.087376)
			(type default)
		)
		(layer "F.Cu")
	)
	(gr_line
		(start 51.043586 -155.358846)
		(end 51.043586 -155.536138)
		(stroke
			(width 0.087376)
			(type default)
		)
		(layer "F.Cu")
	)
	(gr_line
		(start 51.043586 -155.358846)
		(end 51.414426 -154.98826)
		(stroke
			(width 0.087376)
			(type default)
		)
		(layer "F.Cu")
	)
	(gr_line
		(start 51.092354 -258.150106)
		(end 51.092354 -258.327144)
		(stroke
			(width 0.087376)
			(type default)
		)
		(layer "F.Cu")
	)
	(gr_line
		(start 51.092354 -258.150106)
		(end 51.46294 -257.779266)
		(stroke
			(width 0.087376)
			(type default)
		)
		(layer "F.Cu")
	)
	(gr_line
		(start 51.177444 -61.265816)
		(end 51.302666 -61.140594)
		(stroke
			(width 0.087376)
			(type default)
		)
		(layer "F.Cu")
	)
	(gr_line
		(start 51.280314 -150.907242)
		(end 51.280314 -151.08428)
		(stroke
			(width 0.087376)
			(type default)
		)
		(layer "F.Cu")
	)
	(gr_line
		(start 51.286664 -155.728162)
		(end 51.593242 -155.421584)
		(stroke
			(width 0.087376)
			(type default)
		)
		(layer "F.Cu")
	)
	(gr_line
		(start 51.414426 -154.98826)
		(end 51.591464 -154.98826)
		(stroke
			(width 0.087376)
			(type default)
		)
		(layer "F.Cu")
	)
	(gr_line
		(start 51.46294 -257.779266)
		(end 51.640232 -257.779266)
		(stroke
			(width 0.087376)
			(type default)
		)
		(layer "F.Cu")
	)
	(gr_line
		(start 51.525678 -258.328922)
		(end 51.64201 -258.21259)
		(stroke
			(width 0.087376)
			(type default)
		)
		(layer "F.Cu")
	)
	(gr_line
		(start 51.533552 -472.830652)
		(end 51.658774 -472.70543)
		(stroke
			(width 0.087376)
			(type default)
		)
		(layer "F.Cu")
	)
	(gr_line
		(start 51.658774 -472.70543)
		(end 52.18303 -472.70543)
		(stroke
			(width 0.087376)
			(type default)
		)
		(layer "F.Cu")
	)
	(gr_line
		(start 51.830986 -360.713528)
		(end 51.830986 -360.89082)
		(stroke
			(width 0.087376)
			(type default)
		)
		(layer "F.Cu")
	)
	(gr_line
		(start 51.830986 -360.713528)
		(end 52.201826 -360.342942)
		(stroke
			(width 0.087376)
			(type default)
		)
		(layer "F.Cu")
	)
	(gr_line
		(start 51.832002 -61.140594)
		(end 51.957224 -61.265816)
		(stroke
			(width 0.087376)
			(type default)
		)
		(layer "F.Cu")
	)
	(gr_line
		(start 51.838606 -473.138246)
		(end 52.003198 -473.138246)
		(stroke
			(width 0.087376)
			(type default)
		)
		(layer "F.Cu")
	)
	(gr_line
		(start 51.884326 -251.544328)
		(end 52.000658 -251.427996)
		(stroke
			(width 0.087376)
			(type default)
		)
		(layer "F.Cu")
	)
	(gr_line
		(start 51.886104 -251.977652)
		(end 52.063142 -251.977652)
		(stroke
			(width 0.087376)
			(type default)
		)
		(layer "F.Cu")
	)
	(gr_line
		(start 51.957224 -61.265816)
		(end 52.48148 -61.265816)
		(stroke
			(width 0.087376)
			(type default)
		)
		(layer "F.Cu")
	)
	(gr_line
		(start 51.96586 -154.436826)
		(end 51.96586 -154.613864)
		(stroke
			(width 0.087376)
			(type default)
		)
		(layer "F.Cu")
	)
	(gr_line
		(start 51.96586 -154.436826)
		(end 52.336446 -154.065986)
		(stroke
			(width 0.087376)
			(type default)
		)
		(layer "F.Cu")
	)
	(gr_line
		(start 52.014374 -257.228086)
		(end 52.014374 -257.405124)
		(stroke
			(width 0.087376)
			(type default)
		)
		(layer "F.Cu")
	)
	(gr_line
		(start 52.014374 -257.228086)
		(end 52.385214 -256.857246)
		(stroke
			(width 0.087376)
			(type default)
		)
		(layer "F.Cu")
	)
	(gr_line
		(start 52.063142 -251.977652)
		(end 52.433982 -251.607066)
		(stroke
			(width 0.087376)
			(type default)
		)
		(layer "F.Cu")
	)
	(gr_line
		(start 52.13604 -361.020868)
		(end 52.570634 -360.586274)
		(stroke
			(width 0.087376)
			(type default)
		)
		(layer "F.Cu")
	)
	(gr_line
		(start 52.137056 -60.833)
		(end 52.301648 -60.833)
		(stroke
			(width 0.087376)
			(type default)
		)
		(layer "F.Cu")
	)
	(gr_line
		(start 52.18303 -472.70543)
		(end 52.308252 -472.830652)
		(stroke
			(width 0.087376)
			(type default)
		)
		(layer "F.Cu")
	)
	(gr_line
		(start 52.201826 -360.342942)
		(end 52.378864 -360.342942)
		(stroke
			(width 0.087376)
			(type default)
		)
		(layer "F.Cu")
	)
	(gr_line
		(start 52.208938 -154.805888)
		(end 52.705762 -154.309064)
		(stroke
			(width 0.087376)
			(type default)
		)
		(layer "F.Cu")
	)
	(gr_line
		(start 52.336446 -154.065986)
		(end 52.513738 -154.065986)
		(stroke
			(width 0.087376)
			(type default)
		)
		(layer "F.Cu")
	)
	(gr_line
		(start 52.385214 -256.857246)
		(end 52.562252 -256.857246)
		(stroke
			(width 0.087376)
			(type default)
		)
		(layer "F.Cu")
	)
	(gr_line
		(start 52.433982 -251.429774)
		(end 52.433982 -251.607066)
		(stroke
			(width 0.087376)
			(type default)
		)
		(layer "F.Cu")
	)
	(gr_line
		(start 52.447698 -257.406902)
		(end 52.56403 -257.29057)
		(stroke
			(width 0.087376)
			(type default)
		)
		(layer "F.Cu")
	)
	(gr_line
		(start 52.48148 -61.265816)
		(end 52.606702 -61.140594)
		(stroke
			(width 0.087376)
			(type default)
		)
		(layer "F.Cu")
	)
	(gr_line
		(start 52.554124 -416.9791)
		(end 52.554124 -416.979354)
		(stroke
			(width 0.087376)
			(type default)
		)
		(layer "F.Cu")
	)
	(gr_line
		(start 52.584604 -57.140348)
		(end 52.709826 -57.26557)
		(stroke
			(width 0.087376)
			(type default)
		)
		(layer "F.Cu")
	)
	(gr_line
		(start 52.697888 -462.53654)
		(end 52.82311 -462.661762)
		(stroke
			(width 0.087376)
			(type default)
		)
		(layer "F.Cu")
	)
	(gr_line
		(start 52.709826 -57.26557)
		(end 53.234082 -57.26557)
		(stroke
			(width 0.087376)
			(type default)
		)
		(layer "F.Cu")
	)
	(gr_line
		(start 52.753006 -359.791508)
		(end 52.753006 -359.9688)
		(stroke
			(width 0.087376)
			(type default)
		)
		(layer "F.Cu")
	)
	(gr_line
		(start 52.753006 -359.791508)
		(end 53.123846 -359.420922)
		(stroke
			(width 0.087376)
			(type default)
		)
		(layer "F.Cu")
	)
	(gr_line
		(start 52.770024 -417.195)
		(end 52.859178 -417.195)
		(stroke
			(width 0.087376)
			(type default)
		)
		(layer "F.Cu")
	)
	(gr_line
		(start 52.806346 -250.622308)
		(end 52.922678 -250.505976)
		(stroke
			(width 0.087376)
			(type default)
		)
		(layer "F.Cu")
	)
	(gr_line
		(start 52.808124 -251.055632)
		(end 52.985416 -251.055632)
		(stroke
			(width 0.087376)
			(type default)
		)
		(layer "F.Cu")
	)
	(gr_line
		(start 52.82311 -462.661762)
		(end 53.347366 -462.661762)
		(stroke
			(width 0.087376)
			(type default)
		)
		(layer "F.Cu")
	)
	(gr_line
		(start 52.837588 -472.830652)
		(end 52.96281 -472.70543)
		(stroke
			(width 0.087376)
			(type default)
		)
		(layer "F.Cu")
	)
	(gr_line
		(start 52.889658 -56.832754)
		(end 53.05425 -56.832754)
		(stroke
			(width 0.087376)
			(type default)
		)
		(layer "F.Cu")
	)
	(gr_line
		(start 52.936394 -256.305812)
		(end 52.936394 -256.483104)
		(stroke
			(width 0.087376)
			(type default)
		)
		(layer "F.Cu")
	)
	(gr_line
		(start 52.936394 -256.305812)
		(end 53.307234 -255.935226)
		(stroke
			(width 0.087376)
			(type default)
		)
		(layer "F.Cu")
	)
	(gr_line
		(start 52.96281 -472.70543)
		(end 53.487066 -472.70543)
		(stroke
			(width 0.087376)
			(type default)
		)
		(layer "F.Cu")
	)
	(gr_line
		(start 52.985416 -251.055632)
		(end 53.356002 -250.684792)
		(stroke
			(width 0.087376)
			(type default)
		)
		(layer "F.Cu")
	)
	(gr_line
		(start 52.995322 -360.161586)
		(end 53.492654 -359.664254)
		(stroke
			(width 0.087376)
			(type default)
		)
		(layer "F.Cu")
	)
	(gr_line
		(start 53.002942 -462.228946)
		(end 53.167534 -462.228946)
		(stroke
			(width 0.087376)
			(type default)
		)
		(layer "F.Cu")
	)
	(gr_line
		(start 53.078126 -148.674328)
		(end 53.194458 -148.557996)
		(stroke
			(width 0.087376)
			(type default)
		)
		(layer "F.Cu")
	)
	(gr_line
		(start 53.079904 -149.107652)
		(end 53.256942 -149.107652)
		(stroke
			(width 0.087376)
			(type default)
		)
		(layer "F.Cu")
	)
	(gr_line
		(start 53.123846 -359.420922)
		(end 53.300884 -359.420922)
		(stroke
			(width 0.087376)
			(type default)
		)
		(layer "F.Cu")
	)
	(gr_line
		(start 53.136038 -61.140594)
		(end 53.26126 -61.265816)
		(stroke
			(width 0.087376)
			(type default)
		)
		(layer "F.Cu")
	)
	(gr_line
		(start 53.142642 -473.138246)
		(end 53.307234 -473.138246)
		(stroke
			(width 0.087376)
			(type default)
		)
		(layer "F.Cu")
	)
	(gr_line
		(start 53.234082 -57.26557)
		(end 53.359304 -57.140348)
		(stroke
			(width 0.087376)
			(type default)
		)
		(layer "F.Cu")
	)
	(gr_line
		(start 53.256942 -149.107652)
		(end 53.627782 -148.737066)
		(stroke
			(width 0.087376)
			(type default)
		)
		(layer "F.Cu")
	)
	(gr_line
		(start 53.26126 -61.265816)
		(end 53.785516 -61.265816)
		(stroke
			(width 0.087376)
			(type default)
		)
		(layer "F.Cu")
	)
	(gr_line
		(start 53.307234 -255.935226)
		(end 53.484272 -255.935226)
		(stroke
			(width 0.087376)
			(type default)
		)
		(layer "F.Cu")
	)
	(gr_line
		(start 53.347366 -462.661762)
		(end 53.472588 -462.53654)
		(stroke
			(width 0.087376)
			(type default)
		)
		(layer "F.Cu")
	)
	(gr_line
		(start 53.356002 -250.507754)
		(end 53.356002 -250.684792)
		(stroke
			(width 0.087376)
			(type default)
		)
		(layer "F.Cu")
	)
	(gr_line
		(start 53.369718 -256.484882)
		(end 53.48605 -256.36855)
		(stroke
			(width 0.087376)
			(type default)
		)
		(layer "F.Cu")
	)
	(gr_line
		(start 53.441092 -60.833)
		(end 53.605684 -60.833)
		(stroke
			(width 0.087376)
			(type default)
		)
		(layer "F.Cu")
	)
	(gr_line
		(start 53.487066 -472.70543)
		(end 53.612288 -472.830652)
		(stroke
			(width 0.087376)
			(type default)
		)
		(layer "F.Cu")
	)
	(gr_line
		(start 53.596794 -353.463098)
		(end 53.713126 -353.346766)
		(stroke
			(width 0.087376)
			(type default)
		)
		(layer "F.Cu")
	)
	(gr_line
		(start 53.598572 -353.896422)
		(end 53.77561 -353.896422)
		(stroke
			(width 0.087376)
			(type default)
		)
		(layer "F.Cu")
	)
	(gr_line
		(start 53.627782 -148.559774)
		(end 53.627782 -148.737066)
		(stroke
			(width 0.087376)
			(type default)
		)
		(layer "F.Cu")
	)
	(gr_line
		(start 53.675026 -358.869488)
		(end 53.675026 -359.04678)
		(stroke
			(width 0.087376)
			(type default)
		)
		(layer "F.Cu")
	)
	(gr_line
		(start 53.675026 -358.869488)
		(end 54.045866 -358.498902)
		(stroke
			(width 0.087376)
			(type default)
		)
		(layer "F.Cu")
	)
	(gr_line
		(start 53.77561 -353.896422)
		(end 54.14645 -353.525836)
		(stroke
			(width 0.087376)
			(type default)
		)
		(layer "F.Cu")
	)
	(gr_line
		(start 53.785516 -61.265816)
		(end 53.910738 -61.140594)
		(stroke
			(width 0.087376)
			(type default)
		)
		(layer "F.Cu")
	)
	(gr_line
		(start 53.88864 -57.140348)
		(end 54.013862 -57.26557)
		(stroke
			(width 0.087376)
			(type default)
		)
		(layer "F.Cu")
	)
	(gr_line
		(start 53.917342 -359.239566)
		(end 54.414674 -358.742234)
		(stroke
			(width 0.087376)
			(type default)
		)
		(layer "F.Cu")
	)
	(gr_line
		(start 54.000146 -147.752308)
		(end 54.116478 -147.635976)
		(stroke
			(width 0.087376)
			(type default)
		)
		(layer "F.Cu")
	)
	(gr_line
		(start 54.001924 -462.53654)
		(end 54.127146 -462.661762)
		(stroke
			(width 0.087376)
			(type default)
		)
		(layer "F.Cu")
	)
	(gr_line
		(start 54.001924 -148.185632)
		(end 54.179216 -148.185632)
		(stroke
			(width 0.087376)
			(type default)
		)
		(layer "F.Cu")
	)
	(gr_line
		(start 54.013862 -57.26557)
		(end 54.538118 -57.26557)
		(stroke
			(width 0.087376)
			(type default)
		)
		(layer "F.Cu")
	)
	(gr_line
		(start 54.045866 -358.498902)
		(end 54.222904 -358.498902)
		(stroke
			(width 0.087376)
			(type default)
		)
		(layer "F.Cu")
	)
	(gr_line
		(start 54.127146 -462.661762)
		(end 54.651402 -462.661762)
		(stroke
			(width 0.087376)
			(type default)
		)
		(layer "F.Cu")
	)
	(gr_line
		(start 54.14645 -353.348544)
		(end 54.14645 -353.525836)
		(stroke
			(width 0.087376)
			(type default)
		)
		(layer "F.Cu")
	)
	(gr_line
		(start 54.179216 -148.185632)
		(end 54.549802 -147.814792)
		(stroke
			(width 0.087376)
			(type default)
		)
		(layer "F.Cu")
	)
	(gr_line
		(start 54.193694 -56.832754)
		(end 54.358286 -56.832754)
		(stroke
			(width 0.087376)
			(type default)
		)
		(layer "F.Cu")
	)
	(gr_line
		(start 54.306978 -462.228946)
		(end 54.47157 -462.228946)
		(stroke
			(width 0.087376)
			(type default)
		)
		(layer "F.Cu")
	)
	(gr_line
		(start 54.518814 -352.541078)
		(end 54.635146 -352.424746)
		(stroke
			(width 0.087376)
			(type default)
		)
		(layer "F.Cu")
	)
	(gr_line
		(start 54.520592 -352.974402)
		(end 54.697884 -352.974402)
		(stroke
			(width 0.087376)
			(type default)
		)
		(layer "F.Cu")
	)
	(gr_line
		(start 54.538118 -57.26557)
		(end 54.66334 -57.140348)
		(stroke
			(width 0.087376)
			(type default)
		)
		(layer "F.Cu")
	)
	(gr_line
		(start 54.549802 -147.637754)
		(end 54.549802 -147.814792)
		(stroke
			(width 0.087376)
			(type default)
		)
		(layer "F.Cu")
	)
	(gr_line
		(start 54.651402 -462.661762)
		(end 54.776624 -462.53654)
		(stroke
			(width 0.087376)
			(type default)
		)
		(layer "F.Cu")
	)
	(gr_line
		(start 54.697884 -352.974402)
		(end 55.06847 -352.603562)
		(stroke
			(width 0.087376)
			(type default)
		)
		(layer "F.Cu")
	)
	(gr_line
		(start 55.06847 -352.426524)
		(end 55.06847 -352.603562)
		(stroke
			(width 0.087376)
			(type default)
		)
		(layer "F.Cu")
	)
	(gr_line
		(start 55.192676 -57.140348)
		(end 55.317898 -57.26557)
		(stroke
			(width 0.087376)
			(type default)
		)
		(layer "F.Cu")
	)
	(gr_line
		(start 55.283862 -253.958344)
		(end 55.283862 -254.135636)
		(stroke
			(width 0.087376)
			(type default)
		)
		(layer "F.Cu")
	)
	(gr_line
		(start 55.283862 -253.958344)
		(end 55.654702 -253.587758)
		(stroke
			(width 0.087376)
			(type default)
		)
		(layer "F.Cu")
	)
	(gr_line
		(start 55.317898 -57.26557)
		(end 55.842154 -57.26557)
		(stroke
			(width 0.087376)
			(type default)
		)
		(layer "F.Cu")
	)
	(gr_line
		(start 55.49773 -56.832754)
		(end 55.662322 -56.832754)
		(stroke
			(width 0.087376)
			(type default)
		)
		(layer "F.Cu")
	)
	(gr_line
		(start 55.654702 -253.587758)
		(end 55.83174 -253.587758)
		(stroke
			(width 0.087376)
			(type default)
		)
		(layer "F.Cu")
	)
	(gr_line
		(start 55.717186 -254.137414)
		(end 55.833518 -254.021082)
		(stroke
			(width 0.087376)
			(type default)
		)
		(layer "F.Cu")
	)
	(gr_line
		(start 55.842154 -57.26557)
		(end 55.967376 -57.140348)
		(stroke
			(width 0.087376)
			(type default)
		)
		(layer "F.Cu")
	)
	(gr_line
		(start 56.046624 -111.379)
		(end 56.4261 -111.379)
		(stroke
			(width 0.085598)
			(type default)
		)
		(layer "F.Cu")
	)
	(gr_line
		(start 56.206136 -253.036324)
		(end 56.206136 -253.213362)
		(stroke
			(width 0.087376)
			(type default)
		)
		(layer "F.Cu")
	)
	(gr_line
		(start 56.206136 -253.036324)
		(end 56.576722 -252.665738)
		(stroke
			(width 0.087376)
			(type default)
		)
		(layer "F.Cu")
	)
	(gr_line
		(start 56.4261 -111.379)
		(end 56.481218 -111.434118)
		(stroke
			(width 0.085598)
			(type default)
		)
		(layer "F.Cu")
	)
	(gr_line
		(start 56.455818 -61.140594)
		(end 56.58104 -61.265816)
		(stroke
			(width 0.087376)
			(type default)
		)
		(layer "F.Cu")
	)
	(gr_line
		(start 56.576722 -252.665738)
		(end 56.75376 -252.665738)
		(stroke
			(width 0.087376)
			(type default)
		)
		(layer "F.Cu")
	)
	(gr_line
		(start 56.58104 -61.265816)
		(end 57.105296 -61.265816)
		(stroke
			(width 0.087376)
			(type default)
		)
		(layer "F.Cu")
	)
	(gr_line
		(start 56.63946 -253.21514)
		(end 56.755538 -253.099062)
		(stroke
			(width 0.087376)
			(type default)
		)
		(layer "F.Cu")
	)
	(gr_line
		(start 56.760872 -60.833)
		(end 56.925464 -60.833)
		(stroke
			(width 0.087376)
			(type default)
		)
		(layer "F.Cu")
	)
	(gr_line
		(start 57.105296 -61.265816)
		(end 57.230518 -61.140594)
		(stroke
			(width 0.087376)
			(type default)
		)
		(layer "F.Cu")
	)
	(gr_line
		(start 57.266332 -111.434118)
		(end 57.32145 -111.379)
		(stroke
			(width 0.085598)
			(type default)
		)
		(layer "F.Cu")
	)
	(gr_line
		(start 57.32145 -111.379)
		(end 57.951624 -111.379)
		(stroke
			(width 0.085598)
			(type default)
		)
		(layer "F.Cu")
	)
	(gr_line
		(start 57.497472 -101.399594)
		(end 57.622694 -101.524816)
		(stroke
			(width 0.087376)
			(type default)
		)
		(layer "F.Cu")
	)
	(gr_line
		(start 57.622694 -101.524816)
		(end 58.14695 -101.524816)
		(stroke
			(width 0.087376)
			(type default)
		)
		(layer "F.Cu")
	)
	(gr_line
		(start 57.759854 -61.140594)
		(end 57.885076 -61.265816)
		(stroke
			(width 0.087376)
			(type default)
		)
		(layer "F.Cu")
	)
	(gr_line
		(start 57.802526 -101.092)
		(end 57.967118 -101.092)
		(stroke
			(width 0.087376)
			(type default)
		)
		(layer "F.Cu")
	)
	(gr_line
		(start 57.885076 -61.265816)
		(end 58.409332 -61.265816)
		(stroke
			(width 0.087376)
			(type default)
		)
		(layer "F.Cu")
	)
	(gr_line
		(start 58.064908 -60.833)
		(end 58.2295 -60.833)
		(stroke
			(width 0.087376)
			(type default)
		)
		(layer "F.Cu")
	)
	(gr_line
		(start 58.14695 -101.524816)
		(end 58.272172 -101.399594)
		(stroke
			(width 0.087376)
			(type default)
		)
		(layer "F.Cu")
	)
	(gr_line
		(start 58.409332 -61.265816)
		(end 58.534554 -61.140594)
		(stroke
			(width 0.087376)
			(type default)
		)
		(layer "F.Cu")
	)
	(gr_line
		(start 58.512456 -57.140348)
		(end 58.637678 -57.26557)
		(stroke
			(width 0.087376)
			(type default)
		)
		(layer "F.Cu")
	)
	(gr_line
		(start 58.637678 -57.26557)
		(end 59.161934 -57.26557)
		(stroke
			(width 0.087376)
			(type default)
		)
		(layer "F.Cu")
	)
	(gr_line
		(start 58.801508 -101.399594)
		(end 58.92673 -101.524816)
		(stroke
			(width 0.087376)
			(type default)
		)
		(layer "F.Cu")
	)
	(gr_line
		(start 58.81751 -56.832754)
		(end 58.982102 -56.832754)
		(stroke
			(width 0.087376)
			(type default)
		)
		(layer "F.Cu")
	)
	(gr_line
		(start 58.92673 -101.524816)
		(end 59.450986 -101.524816)
		(stroke
			(width 0.087376)
			(type default)
		)
		(layer "F.Cu")
	)
	(gr_line
		(start 59.015376 -441.96)
		(end 59.64555 -441.96)
		(stroke
			(width 0.085598)
			(type default)
		)
		(layer "F.Cu")
	)
	(gr_line
		(start 59.106562 -101.092)
		(end 59.271154 -101.092)
		(stroke
			(width 0.087376)
			(type default)
		)
		(layer "F.Cu")
	)
	(gr_line
		(start 59.161934 -57.26557)
		(end 59.287156 -57.140348)
		(stroke
			(width 0.087376)
			(type default)
		)
		(layer "F.Cu")
	)
	(gr_line
		(start 59.450986 -101.524816)
		(end 59.576208 -101.399594)
		(stroke
			(width 0.087376)
			(type default)
		)
		(layer "F.Cu")
	)
	(gr_line
		(start 59.611768 -352.932492)
		(end 59.611768 -353.109784)
		(stroke
			(width 0.087376)
			(type default)
		)
		(layer "F.Cu")
	)
	(gr_line
		(start 59.611768 -352.932492)
		(end 59.982608 -352.561652)
		(stroke
			(width 0.087376)
			(type default)
		)
		(layer "F.Cu")
	)
	(gr_line
		(start 59.64555 -441.96)
		(end 59.700668 -441.904882)
		(stroke
			(width 0.085598)
			(type default)
		)
		(layer "F.Cu")
	)
	(gr_line
		(start 59.816492 -57.140348)
		(end 59.941714 -57.26557)
		(stroke
			(width 0.087376)
			(type default)
		)
		(layer "F.Cu")
	)
	(gr_line
		(start 59.829446 -472.830652)
		(end 59.954668 -472.70543)
		(stroke
			(width 0.087376)
			(type default)
		)
		(layer "F.Cu")
	)
	(gr_line
		(start 59.854338 -353.302316)
		(end 60.161678 -352.994976)
		(stroke
			(width 0.087376)
			(type default)
		)
		(layer "F.Cu")
	)
	(gr_line
		(start 59.856624 -97.04324)
		(end 60.23864 -97.04324)
		(stroke
			(width 0.085598)
			(type default)
		)
		(layer "F.Cu")
	)
	(gr_line
		(start 59.941714 -57.26557)
		(end 60.46597 -57.26557)
		(stroke
			(width 0.087376)
			(type default)
		)
		(layer "F.Cu")
	)
	(gr_line
		(start 59.954668 -472.70543)
		(end 60.478924 -472.70543)
		(stroke
			(width 0.087376)
			(type default)
		)
		(layer "F.Cu")
	)
	(gr_line
		(start 59.982608 -352.561652)
		(end 60.1599 -352.561652)
		(stroke
			(width 0.087376)
			(type default)
		)
		(layer "F.Cu")
	)
	(gr_line
		(start 60.121546 -56.832754)
		(end 60.286138 -56.832754)
		(stroke
			(width 0.087376)
			(type default)
		)
		(layer "F.Cu")
	)
	(gr_line
		(start 60.1345 -473.138246)
		(end 60.299092 -473.138246)
		(stroke
			(width 0.087376)
			(type default)
		)
		(layer "F.Cu")
	)
	(gr_line
		(start 60.23864 -97.04324)
		(end 60.292742 -97.097342)
		(stroke
			(width 0.085598)
			(type default)
		)
		(layer "F.Cu")
	)
	(gr_line
		(start 60.46597 -57.26557)
		(end 60.591192 -57.140348)
		(stroke
			(width 0.087376)
			(type default)
		)
		(layer "F.Cu")
	)
	(gr_line
		(start 60.478924 -472.70543)
		(end 60.604146 -472.830652)
		(stroke
			(width 0.087376)
			(type default)
		)
		(layer "F.Cu")
	)
	(gr_line
		(start 60.485782 -441.904882)
		(end 60.5409 -441.96)
		(stroke
			(width 0.085598)
			(type default)
		)
		(layer "F.Cu")
	)
	(gr_line
		(start 60.533788 -352.010218)
		(end 60.533788 -352.187764)
		(stroke
			(width 0.087376)
			(type default)
		)
		(layer "F.Cu")
	)
	(gr_line
		(start 60.533788 -352.010218)
		(end 60.904628 -351.639632)
		(stroke
			(width 0.087376)
			(type default)
		)
		(layer "F.Cu")
	)
	(gr_line
		(start 60.5409 -441.96)
		(end 60.920376 -441.96)
		(stroke
			(width 0.085598)
			(type default)
		)
		(layer "F.Cu")
	)
	(gr_line
		(start 60.776104 -352.38055)
		(end 61.274706 -351.881948)
		(stroke
			(width 0.087376)
			(type default)
		)
		(layer "F.Cu")
	)
	(gr_line
		(start 60.904628 -351.639632)
		(end 61.08192 -351.639632)
		(stroke
			(width 0.087376)
			(type default)
		)
		(layer "F.Cu")
	)
	(gr_line
		(start 61.025024 -97.14992)
		(end 61.13145 -97.04324)
		(stroke
			(width 0.085598)
			(type default)
		)
		(layer "F.Cu")
	)
	(gr_line
		(start 61.08573 -321.170554)
		(end 61.6458 -321.730624)
		(stroke
			(width 0.085598)
			(type default)
		)
		(layer "F.Cu")
	)
	(gr_line
		(start 61.08573 -320.385694)
		(end 61.6458 -319.825624)
		(stroke
			(width 0.085598)
			(type default)
		)
		(layer "F.Cu")
	)
	(gr_line
		(start 61.120528 -57.140348)
		(end 61.24575 -57.26557)
		(stroke
			(width 0.087376)
			(type default)
		)
		(layer "F.Cu")
	)
	(gr_line
		(start 61.13145 -97.04324)
		(end 61.761624 -97.04324)
		(stroke
			(width 0.085598)
			(type default)
		)
		(layer "F.Cu")
	)
	(gr_line
		(start 61.133482 -472.830652)
		(end 61.258704 -472.70543)
		(stroke
			(width 0.087376)
			(type default)
		)
		(layer "F.Cu")
	)
	(gr_line
		(start 61.24575 -57.26557)
		(end 61.770006 -57.26557)
		(stroke
			(width 0.087376)
			(type default)
		)
		(layer "F.Cu")
	)
	(gr_line
		(start 61.258704 -472.70543)
		(end 61.78296 -472.70543)
		(stroke
			(width 0.087376)
			(type default)
		)
		(layer "F.Cu")
	)
	(gr_line
		(start 61.425582 -56.832754)
		(end 61.590174 -56.832754)
		(stroke
			(width 0.087376)
			(type default)
		)
		(layer "F.Cu")
	)
	(gr_line
		(start 61.438536 -473.138246)
		(end 61.603128 -473.138246)
		(stroke
			(width 0.087376)
			(type default)
		)
		(layer "F.Cu")
	)
	(gr_line
		(start 61.770006 -57.26557)
		(end 61.895228 -57.140348)
		(stroke
			(width 0.087376)
			(type default)
		)
		(layer "F.Cu")
	)
	(gr_line
		(start 61.78296 -472.70543)
		(end 61.908182 -472.830652)
		(stroke
			(width 0.087376)
			(type default)
		)
		(layer "F.Cu")
	)
	(gr_line
		(start 63.028576 -435.978808)
		(end 63.119 -436.069232)
		(stroke
			(width 0.085598)
			(type default)
		)
		(layer "F.Cu")
	)
	(gr_line
		(start 63.028576 -435.193694)
		(end 63.119 -435.10327)
		(stroke
			(width 0.085598)
			(type default)
		)
		(layer "F.Cu")
	)
	(gr_line
		(start 63.929768 -441.597542)
		(end 64.020192 -441.507118)
		(stroke
			(width 0.085598)
			(type default)
		)
		(layer "F.Cu")
	)
	(gr_line
		(start 64.289686 -57.140348)
		(end 64.414908 -57.26557)
		(stroke
			(width 0.087376)
			(type default)
		)
		(layer "F.Cu")
	)
	(gr_line
		(start 64.310514 -101.399594)
		(end 64.435736 -101.524816)
		(stroke
			(width 0.087376)
			(type default)
		)
		(layer "F.Cu")
	)
	(gr_line
		(start 64.414908 -57.26557)
		(end 64.939164 -57.26557)
		(stroke
			(width 0.087376)
			(type default)
		)
		(layer "F.Cu")
	)
	(gr_line
		(start 64.435736 -101.524816)
		(end 64.959992 -101.524816)
		(stroke
			(width 0.087376)
			(type default)
		)
		(layer "F.Cu")
	)
	(gr_line
		(start 64.59474 -56.832754)
		(end 64.759332 -56.832754)
		(stroke
			(width 0.087376)
			(type default)
		)
		(layer "F.Cu")
	)
	(gr_line
		(start 64.615568 -101.092)
		(end 64.78016 -101.092)
		(stroke
			(width 0.087376)
			(type default)
		)
		(layer "F.Cu")
	)
	(gr_line
		(start 64.805306 -441.507118)
		(end 64.89573 -441.597542)
		(stroke
			(width 0.085598)
			(type default)
		)
		(layer "F.Cu")
	)
	(gr_line
		(start 64.939164 -57.26557)
		(end 65.064386 -57.140348)
		(stroke
			(width 0.087376)
			(type default)
		)
		(layer "F.Cu")
	)
	(gr_line
		(start 64.959992 -101.524816)
		(end 65.085214 -101.399594)
		(stroke
			(width 0.087376)
			(type default)
		)
		(layer "F.Cu")
	)
	(gr_line
		(start 65.593722 -57.140348)
		(end 65.718944 -57.26557)
		(stroke
			(width 0.087376)
			(type default)
		)
		(layer "F.Cu")
	)
	(gr_line
		(start 65.61455 -101.399594)
		(end 65.739772 -101.524816)
		(stroke
			(width 0.087376)
			(type default)
		)
		(layer "F.Cu")
	)
	(gr_line
		(start 65.718944 -57.26557)
		(end 66.2432 -57.26557)
		(stroke
			(width 0.087376)
			(type default)
		)
		(layer "F.Cu")
	)
	(gr_line
		(start 65.739772 -101.524816)
		(end 66.264028 -101.524816)
		(stroke
			(width 0.087376)
			(type default)
		)
		(layer "F.Cu")
	)
	(gr_line
		(start 65.898776 -56.832754)
		(end 66.063368 -56.832754)
		(stroke
			(width 0.087376)
			(type default)
		)
		(layer "F.Cu")
	)
	(gr_line
		(start 65.919604 -101.092)
		(end 66.084196 -101.092)
		(stroke
			(width 0.087376)
			(type default)
		)
		(layer "F.Cu")
	)
	(gr_line
		(start 66.2432 -57.26557)
		(end 66.368422 -57.140348)
		(stroke
			(width 0.087376)
			(type default)
		)
		(layer "F.Cu")
	)
	(gr_line
		(start 66.264028 -101.524816)
		(end 66.38925 -101.399594)
		(stroke
			(width 0.087376)
			(type default)
		)
		(layer "F.Cu")
	)
	(gr_line
		(start 66.841624 -345.882976)
		(end 66.9036 -345.821)
		(stroke
			(width 0.087376)
			(type default)
		)
		(layer "F.Cu")
	)
	(gr_line
		(start 66.897758 -57.140348)
		(end 67.02298 -57.26557)
		(stroke
			(width 0.087376)
			(type default)
		)
		(layer "F.Cu")
	)
	(gr_line
		(start 67.02298 -57.26557)
		(end 67.547236 -57.26557)
		(stroke
			(width 0.087376)
			(type default)
		)
		(layer "F.Cu")
	)
	(gr_line
		(start 67.202812 -56.832754)
		(end 67.367404 -56.832754)
		(stroke
			(width 0.087376)
			(type default)
		)
		(layer "F.Cu")
	)
	(gr_line
		(start 67.547236 -57.26557)
		(end 67.672458 -57.140348)
		(stroke
			(width 0.087376)
			(type default)
		)
		(layer "F.Cu")
	)
	(gr_line
		(start 67.91579 -433.8828)
		(end 67.991736 -433.8828)
		(stroke
			(width 0.085598)
			(type default)
		)
		(layer "F.Cu")
	)
	(gr_line
		(start 68.286376 -300.49724)
		(end 68.879466 -300.49724)
		(stroke
			(width 0.085598)
			(type default)
		)
		(layer "F.Cu")
	)
	(gr_line
		(start 68.326 -434.217064)
		(end 69.215 -435.106064)
		(stroke
			(width 0.085598)
			(type default)
		)
		(layer "F.Cu")
	)
	(gr_line
		(start 68.46824 -433.578)
		(end 68.544186 -433.578)
		(stroke
			(width 0.085598)
			(type default)
		)
		(layer "F.Cu")
	)
	(gr_line
		(start 68.5292 -151.062182)
		(end 68.619624 -150.971758)
		(stroke
			(width 0.085598)
			(type default)
		)
		(layer "F.Cu")
	)
	(gr_line
		(start 68.5292 -150.09622)
		(end 68.619624 -150.186644)
		(stroke
			(width 0.085598)
			(type default)
		)
		(layer "F.Cu")
	)
	(gr_line
		(start 68.546726 -433.578)
		(end 69.6214 -433.578)
		(stroke
			(width 0.085598)
			(type default)
		)
		(layer "F.Cu")
	)
	(gr_line
		(start 68.58 -360.002582)
		(end 68.670424 -359.912158)
		(stroke
			(width 0.085598)
			(type default)
		)
		(layer "F.Cu")
	)
	(gr_line
		(start 68.58 -359.03662)
		(end 68.670424 -359.127044)
		(stroke
			(width 0.085598)
			(type default)
		)
		(layer "F.Cu")
	)
	(gr_line
		(start 68.58 -148.039582)
		(end 68.670424 -147.949158)
		(stroke
			(width 0.085598)
			(type default)
		)
		(layer "F.Cu")
	)
	(gr_line
		(start 68.58 -147.07362)
		(end 68.670424 -147.164044)
		(stroke
			(width 0.085598)
			(type default)
		)
		(layer "F.Cu")
	)
	(gr_line
		(start 68.58 -145.016982)
		(end 68.670424 -144.926558)
		(stroke
			(width 0.085598)
			(type default)
		)
		(layer "F.Cu")
	)
	(gr_line
		(start 68.58 -144.05102)
		(end 68.670424 -144.141444)
		(stroke
			(width 0.085598)
			(type default)
		)
		(layer "F.Cu")
	)
	(gr_line
		(start 68.6054 -363.093)
		(end 68.695824 -363.002576)
		(stroke
			(width 0.085598)
			(type default)
		)
		(layer "F.Cu")
	)
	(gr_line
		(start 68.6054 -362.127038)
		(end 68.695824 -362.217462)
		(stroke
			(width 0.085598)
			(type default)
		)
		(layer "F.Cu")
	)
	(gr_line
		(start 68.879466 -300.49724)
		(end 68.903342 -300.521116)
		(stroke
			(width 0.085598)
			(type default)
		)
		(layer "F.Cu")
	)
	(gr_line
		(start 69.215 -435.106064)
		(end 69.215 -435.4195)
		(stroke
			(width 0.085598)
			(type default)
		)
		(layer "F.Cu")
	)
	(gr_line
		(start 69.247766 -210.47456)
		(end 69.372988 -210.599782)
		(stroke
			(width 0.087376)
			(type default)
		)
		(layer "F.Cu")
	)
	(gr_line
		(start 69.372988 -210.599782)
		(end 69.897244 -210.599782)
		(stroke
			(width 0.087376)
			(type default)
		)
		(layer "F.Cu")
	)
	(gr_line
		(start 69.55282 -210.166966)
		(end 69.717412 -210.166966)
		(stroke
			(width 0.087376)
			(type default)
		)
		(layer "F.Cu")
	)
	(gr_line
		(start 69.6214 -433.578)
		(end 70.231 -434.1876)
		(stroke
			(width 0.085598)
			(type default)
		)
		(layer "F.Cu")
	)
	(gr_line
		(start 69.688456 -300.521116)
		(end 69.712332 -300.49724)
		(stroke
			(width 0.085598)
			(type default)
		)
		(layer "F.Cu")
	)
	(gr_line
		(start 69.712332 -300.49724)
		(end 70.191376 -300.49724)
		(stroke
			(width 0.085598)
			(type default)
		)
		(layer "F.Cu")
	)
	(gr_line
		(start 69.897244 -210.599782)
		(end 70.022466 -210.47456)
		(stroke
			(width 0.087376)
			(type default)
		)
		(layer "F.Cu")
	)
	(gr_line
		(start 70.231 -434.1876)
		(end 70.231 -435.4195)
		(stroke
			(width 0.085598)
			(type default)
		)
		(layer "F.Cu")
	)
	(gr_line
		(start 70.551802 -210.47456)
		(end 70.694804 -210.617562)
		(stroke
			(width 0.087376)
			(type default)
		)
		(layer "F.Cu")
	)
	(gr_line
		(start 70.556882 -359.926382)
		(end 71.1835 -360.553)
		(stroke
			(width 0.085598)
			(type default)
		)
		(layer "F.Cu")
	)
	(gr_line
		(start 70.556882 -359.141268)
		(end 71.17715 -358.521)
		(stroke
			(width 0.085598)
			(type default)
		)
		(layer "F.Cu")
	)
	(gr_line
		(start 70.55993 -362.97743)
		(end 71.1835 -363.601)
		(stroke
			(width 0.085598)
			(type default)
		)
		(layer "F.Cu")
	)
	(gr_line
		(start 70.55993 -362.19257)
		(end 71.1835 -361.569)
		(stroke
			(width 0.085598)
			(type default)
		)
		(layer "F.Cu")
	)
	(gr_line
		(start 70.55993 -151.01443)
		(end 71.1835 -151.638)
		(stroke
			(width 0.085598)
			(type default)
		)
		(layer "F.Cu")
	)
	(gr_line
		(start 70.55993 -150.22957)
		(end 71.1835 -149.606)
		(stroke
			(width 0.085598)
			(type default)
		)
		(layer "F.Cu")
	)
	(gr_line
		(start 70.55993 -147.96643)
		(end 71.1835 -148.59)
		(stroke
			(width 0.085598)
			(type default)
		)
		(layer "F.Cu")
	)
	(gr_line
		(start 70.55993 -147.18157)
		(end 71.1835 -146.558)
		(stroke
			(width 0.085598)
			(type default)
		)
		(layer "F.Cu")
	)
	(gr_line
		(start 70.55993 -144.91843)
		(end 71.1835 -145.542)
		(stroke
			(width 0.085598)
			(type default)
		)
		(layer "F.Cu")
	)
	(gr_line
		(start 70.55993 -144.13357)
		(end 71.1835 -143.51)
		(stroke
			(width 0.085598)
			(type default)
		)
		(layer "F.Cu")
	)
	(gr_line
		(start 70.694804 -210.617562)
		(end 71.1835 -210.617562)
		(stroke
			(width 0.087376)
			(type default)
		)
		(layer "F.Cu")
	)
	(gr_line
		(start 70.856856 -210.166966)
		(end 71.021448 -210.166966)
		(stroke
			(width 0.087376)
			(type default)
		)
		(layer "F.Cu")
	)
	(gr_line
		(start 71.0311 -366.0775)
		(end 71.64832 -366.69472)
		(stroke
			(width 0.085598)
			(type default)
		)
		(layer "F.Cu")
	)
	(gr_line
		(start 71.0311 -366.0775)
		(end 71.64832 -365.46028)
		(stroke
			(width 0.085598)
			(type default)
		)
		(layer "F.Cu")
	)
	(gr_line
		(start 71.17715 -358.521)
		(end 71.1835 -358.521)
		(stroke
			(width 0.085598)
			(type default)
		)
		(layer "F.Cu")
	)
	(gr_line
		(start 71.1835 -363.601)
		(end 71.80707 -362.97743)
		(stroke
			(width 0.085598)
			(type default)
		)
		(layer "F.Cu")
	)
	(gr_line
		(start 71.1835 -361.569)
		(end 71.80707 -362.19257)
		(stroke
			(width 0.085598)
			(type default)
		)
		(layer "F.Cu")
	)
	(gr_line
		(start 71.1835 -360.4133)
		(end 71.1835 -360.553)
		(stroke
			(width 0.085598)
			(type default)
		)
		(layer "F.Cu")
	)
	(gr_line
		(start 71.1835 -360.4133)
		(end 71.68007 -359.91673)
		(stroke
			(width 0.085598)
			(type default)
		)
		(layer "F.Cu")
	)
	(gr_line
		(start 71.1835 -358.6353)
		(end 71.68007 -359.13187)
		(stroke
			(width 0.085598)
			(type default)
		)
		(layer "F.Cu")
	)
	(gr_line
		(start 71.1835 -358.521)
		(end 71.1835 -358.6353)
		(stroke
			(width 0.085598)
			(type default)
		)
		(layer "F.Cu")
	)
	(gr_line
		(start 71.1835 -210.617562)
		(end 71.326502 -210.47456)
		(stroke
			(width 0.087376)
			(type default)
		)
		(layer "F.Cu")
	)
	(gr_line
		(start 71.1835 -151.638)
		(end 71.80707 -151.01443)
		(stroke
			(width 0.085598)
			(type default)
		)
		(layer "F.Cu")
	)
	(gr_line
		(start 71.1835 -149.606)
		(end 71.80707 -150.22957)
		(stroke
			(width 0.085598)
			(type default)
		)
		(layer "F.Cu")
	)
	(gr_line
		(start 71.1835 -148.59)
		(end 71.80707 -147.96643)
		(stroke
			(width 0.085598)
			(type default)
		)
		(layer "F.Cu")
	)
	(gr_line
		(start 71.1835 -146.558)
		(end 71.80707 -147.18157)
		(stroke
			(width 0.085598)
			(type default)
		)
		(layer "F.Cu")
	)
	(gr_line
		(start 71.1835 -145.542)
		(end 71.80707 -144.91843)
		(stroke
			(width 0.085598)
			(type default)
		)
		(layer "F.Cu")
	)
	(gr_line
		(start 71.1835 -143.51)
		(end 71.88962 -144.21612)
		(stroke
			(width 0.085598)
			(type default)
		)
		(layer "F.Cu")
	)
	(gr_line
		(start 71.63562 -368.6556)
		(end 71.726044 -368.565176)
		(stroke
			(width 0.085598)
			(type default)
		)
		(layer "F.Cu")
	)
	(gr_line
		(start 71.986648 -101.399594)
		(end 72.11187 -101.524816)
		(stroke
			(width 0.087376)
			(type default)
		)
		(layer "F.Cu")
	)
	(gr_line
		(start 72.11187 -101.524816)
		(end 72.636126 -101.524816)
		(stroke
			(width 0.087376)
			(type default)
		)
		(layer "F.Cu")
	)
	(gr_line
		(start 72.136 -153.7335)
		(end 72.75957 -154.35707)
		(stroke
			(width 0.085598)
			(type default)
		)
		(layer "F.Cu")
	)
	(gr_line
		(start 72.136 -153.7335)
		(end 72.75957 -153.10993)
		(stroke
			(width 0.085598)
			(type default)
		)
		(layer "F.Cu")
	)
	(gr_line
		(start 72.136 -138.9634)
		(end 72.136 -139.406376)
		(stroke
			(width 0.085598)
			(type default)
		)
		(layer "F.Cu")
	)
	(gr_line
		(start 72.136 -138.9634)
		(end 72.159368 -138.940032)
		(stroke
			(width 0.085598)
			(type default)
		)
		(layer "F.Cu")
	)
	(gr_line
		(start 72.136 -138.13155)
		(end 72.159368 -138.154918)
		(stroke
			(width 0.085598)
			(type default)
		)
		(layer "F.Cu")
	)
	(gr_line
		(start 72.136 -137.501376)
		(end 72.136 -138.13155)
		(stroke
			(width 0.085598)
			(type default)
		)
		(layer "F.Cu")
	)
	(gr_line
		(start 72.201024 -431.763424)
		(end 72.39 -431.9524)
		(stroke
			(width 0.087376)
			(type default)
		)
		(layer "F.Cu")
	)
	(gr_line
		(start 72.201024 -431.328576)
		(end 72.39 -431.1396)
		(stroke
			(width 0.087376)
			(type default)
		)
		(layer "F.Cu")
	)
	(gr_line
		(start 72.291702 -101.092)
		(end 72.456294 -101.092)
		(stroke
			(width 0.087376)
			(type default)
		)
		(layer "F.Cu")
	)
	(gr_line
		(start 72.43318 -366.69472)
		(end 73.0504 -366.0775)
		(stroke
			(width 0.085598)
			(type default)
		)
		(layer "F.Cu")
	)
	(gr_line
		(start 72.43318 -365.46028)
		(end 73.0504 -366.0775)
		(stroke
			(width 0.085598)
			(type default)
		)
		(layer "F.Cu")
	)
	(gr_line
		(start 72.511158 -368.565176)
		(end 72.601582 -368.6556)
		(stroke
			(width 0.085598)
			(type default)
		)
		(layer "F.Cu")
	)
	(gr_line
		(start 72.5678 -356.8954)
		(end 72.9234 -357.251)
		(stroke
			(width 0.085598)
			(type default)
		)
		(layer "F.Cu")
	)
	(gr_line
		(start 72.5678 -356.6414)
		(end 72.5678 -356.8954)
		(stroke
			(width 0.085598)
			(type default)
		)
		(layer "F.Cu")
	)
	(gr_line
		(start 72.5678 -356.2096)
		(end 72.5678 -356.6414)
		(stroke
			(width 0.085598)
			(type default)
		)
		(layer "F.Cu")
	)
	(gr_line
		(start 72.5678 -356.2096)
		(end 72.898 -355.8794)
		(stroke
			(width 0.085598)
			(type default)
		)
		(layer "F.Cu")
	)
	(gr_line
		(start 72.636126 -101.524816)
		(end 72.761348 -101.399594)
		(stroke
			(width 0.087376)
			(type default)
		)
		(layer "F.Cu")
	)
	(gr_line
		(start 72.67702 -156.3878)
		(end 72.767444 -156.297376)
		(stroke
			(width 0.085598)
			(type default)
		)
		(layer "F.Cu")
	)
	(gr_line
		(start 72.801734 -360.811064)
		(end 74.2188 -360.811064)
		(stroke
			(width 0.085598)
			(type default)
		)
		(layer "F.Cu")
	)
	(gr_line
		(start 72.82561 -57.140348)
		(end 72.950832 -57.26557)
		(stroke
			(width 0.087376)
			(type default)
		)
		(layer "F.Cu")
	)
	(gr_line
		(start 72.898 -355.4095)
		(end 72.898 -355.8794)
		(stroke
			(width 0.085598)
			(type default)
		)
		(layer "F.Cu")
	)
	(gr_line
		(start 72.9234 -357.251)
		(end 73.539096 -357.251)
		(stroke
			(width 0.085598)
			(type default)
		)
		(layer "F.Cu")
	)
	(gr_line
		(start 72.950832 -57.26557)
		(end 73.475088 -57.26557)
		(stroke
			(width 0.087376)
			(type default)
		)
		(layer "F.Cu")
	)
	(gr_line
		(start 73.030588 -360.258614)
		(end 73.082912 -360.310938)
		(stroke
			(width 0.085598)
			(type default)
		)
		(layer "F.Cu")
	)
	(gr_line
		(start 73.082912 -360.310938)
		(end 74.2188 -360.310938)
		(stroke
			(width 0.085598)
			(type default)
		)
		(layer "F.Cu")
	)
	(gr_line
		(start 73.130664 -56.832754)
		(end 73.295256 -56.832754)
		(stroke
			(width 0.087376)
			(type default)
		)
		(layer "F.Cu")
	)
	(gr_line
		(start 73.283064 -361.310936)
		(end 74.2188 -361.310936)
		(stroke
			(width 0.085598)
			(type default)
		)
		(layer "F.Cu")
	)
	(gr_line
		(start 73.290684 -101.399594)
		(end 73.415906 -101.524816)
		(stroke
			(width 0.087376)
			(type default)
		)
		(layer "F.Cu")
	)
	(gr_line
		(start 73.415906 -101.524816)
		(end 73.940162 -101.524816)
		(stroke
			(width 0.087376)
			(type default)
		)
		(layer "F.Cu")
	)
	(gr_line
		(start 73.435464 -148.467064)
		(end 74.2188 -148.467064)
		(stroke
			(width 0.085598)
			(type default)
		)
		(layer "F.Cu")
	)
	(gr_line
		(start 73.475088 -57.26557)
		(end 73.60031 -57.140348)
		(stroke
			(width 0.087376)
			(type default)
		)
		(layer "F.Cu")
	)
	(gr_line
		(start 73.498964 -149.467062)
		(end 74.2188 -149.467062)
		(stroke
			(width 0.085598)
			(type default)
		)
		(layer "F.Cu")
	)
	(gr_line
		(start 73.511918 -361.863386)
		(end 73.564242 -361.811062)
		(stroke
			(width 0.085598)
			(type default)
		)
		(layer "F.Cu")
	)
	(gr_line
		(start 73.539096 -357.251)
		(end 73.689718 -357.401622)
		(stroke
			(width 0.085598)
			(type default)
		)
		(layer "F.Cu")
	)
	(gr_line
		(start 73.54443 -154.35707)
		(end 74.168 -153.7335)
		(stroke
			(width 0.085598)
			(type default)
		)
		(layer "F.Cu")
	)
	(gr_line
		(start 73.54443 -153.10993)
		(end 74.168 -153.7335)
		(stroke
			(width 0.085598)
			(type default)
		)
		(layer "F.Cu")
	)
	(gr_line
		(start 73.552558 -156.297376)
		(end 73.642982 -156.3878)
		(stroke
			(width 0.085598)
			(type default)
		)
		(layer "F.Cu")
	)
	(gr_line
		(start 73.564242 -361.811062)
		(end 74.2188 -361.811062)
		(stroke
			(width 0.085598)
			(type default)
		)
		(layer "F.Cu")
	)
	(gr_line
		(start 73.595738 -101.092)
		(end 73.76033 -101.092)
		(stroke
			(width 0.087376)
			(type default)
		)
		(layer "F.Cu")
	)
	(gr_line
		(start 73.664318 -147.914614)
		(end 73.716642 -147.966938)
		(stroke
			(width 0.085598)
			(type default)
		)
		(layer "F.Cu")
	)
	(gr_line
		(start 73.716642 -147.966938)
		(end 74.2188 -147.966938)
		(stroke
			(width 0.085598)
			(type default)
		)
		(layer "F.Cu")
	)
	(gr_line
		(start 73.727818 -150.019512)
		(end 73.780396 -149.966934)
		(stroke
			(width 0.085598)
			(type default)
		)
		(layer "F.Cu")
	)
	(gr_line
		(start 73.780396 -149.966934)
		(end 74.1426 -149.966934)
		(stroke
			(width 0.085598)
			(type default)
		)
		(layer "F.Cu")
	)
	(gr_line
		(start 73.80732 -143.7005)
		(end 74.41438 -144.30756)
		(stroke
			(width 0.085598)
			(type default)
		)
		(layer "F.Cu")
	)
	(gr_line
		(start 73.80732 -143.7005)
		(end 74.41438 -143.09344)
		(stroke
			(width 0.085598)
			(type default)
		)
		(layer "F.Cu")
	)
	(gr_line
		(start 73.914 -356.0826)
		(end 74.4728 -356.6414)
		(stroke
			(width 0.085598)
			(type default)
		)
		(layer "F.Cu")
	)
	(gr_line
		(start 73.914 -355.4095)
		(end 73.914 -356.0826)
		(stroke
			(width 0.085598)
			(type default)
		)
		(layer "F.Cu")
	)
	(gr_line
		(start 73.940162 -101.524816)
		(end 74.065384 -101.399594)
		(stroke
			(width 0.087376)
			(type default)
		)
		(layer "F.Cu")
	)
	(gr_line
		(start 74.0664 -366.0775)
		(end 74.68997 -366.70107)
		(stroke
			(width 0.085598)
			(type default)
		)
		(layer "F.Cu")
	)
	(gr_line
		(start 74.0664 -366.0775)
		(end 74.68997 -365.45393)
		(stroke
			(width 0.085598)
			(type default)
		)
		(layer "F.Cu")
	)
	(gr_line
		(start 74.126344 -132.456682)
		(end 74.18832 -132.394706)
		(stroke
			(width 0.087376)
			(type default)
		)
		(layer "F.Cu")
	)
	(gr_line
		(start 74.1426 -362.56595)
		(end 74.1426 -362.641896)
		(stroke
			(width 0.085598)
			(type default)
		)
		(layer "F.Cu")
	)
	(gr_line
		(start 74.1426 -362.310934)
		(end 74.1426 -362.56341)
		(stroke
			(width 0.085598)
			(type default)
		)
		(layer "F.Cu")
	)
	(gr_line
		(start 74.1426 -146.866356)
		(end 74.1426 -147.467066)
		(stroke
			(width 0.085598)
			(type default)
		)
		(layer "F.Cu")
	)
	(gr_line
		(start 74.2696 -430.1236)
		(end 74.458576 -430.312576)
		(stroke
			(width 0.087376)
			(type default)
		)
		(layer "F.Cu")
	)
	(gr_line
		(start 74.337418 -141.097)
		(end 74.427842 -141.187424)
		(stroke
			(width 0.085598)
			(type default)
		)
		(layer "F.Cu")
	)
	(gr_line
		(start 74.4474 -363.1184)
		(end 74.69505 -363.1184)
		(stroke
			(width 0.085598)
			(type default)
		)
		(layer "F.Cu")
	)
	(gr_line
		(start 74.4728 -357.1494)
		(end 74.4728 -357.399844)
		(stroke
			(width 0.085598)
			(type default)
		)
		(layer "F.Cu")
	)
	(gr_line
		(start 74.4728 -356.6414)
		(end 74.4728 -357.1494)
		(stroke
			(width 0.085598)
			(type default)
		)
		(layer "F.Cu")
	)
	(gr_line
		(start 74.63282 -368.681)
		(end 74.723244 -368.590576)
		(stroke
			(width 0.085598)
			(type default)
		)
		(layer "F.Cu")
	)
	(gr_line
		(start 74.69759 -363.1184)
		(end 74.950066 -363.1184)
		(stroke
			(width 0.085598)
			(type default)
		)
		(layer "F.Cu")
	)
	(gr_line
		(start 74.720704 -146.6596)
		(end 74.950066 -146.6596)
		(stroke
			(width 0.085598)
			(type default)
		)
		(layer "F.Cu")
	)
	(gr_line
		(start 74.893424 -430.312576)
		(end 75.0824 -430.1236)
		(stroke
			(width 0.087376)
			(type default)
		)
		(layer "F.Cu")
	)
	(gr_line
		(start 74.897488 -358.609392)
		(end 74.950066 -358.66197)
		(stroke
			(width 0.085598)
			(type default)
		)
		(layer "F.Cu")
	)
	(gr_line
		(start 74.897488 -151.467312)
		(end 74.950066 -151.414734)
		(stroke
			(width 0.085598)
			(type default)
		)
		(layer "F.Cu")
	)
	(gr_line
		(start 74.950066 -358.66197)
		(end 74.950066 -359.0036)
		(stroke
			(width 0.085598)
			(type default)
		)
		(layer "F.Cu")
	)
	(gr_line
		(start 74.950066 -150.7744)
		(end 74.950066 -151.414734)
		(stroke
			(width 0.085598)
			(type default)
		)
		(layer "F.Cu")
	)
	(gr_line
		(start 75.184 -153.7335)
		(end 75.80757 -154.35707)
		(stroke
			(width 0.085598)
			(type default)
		)
		(layer "F.Cu")
	)
	(gr_line
		(start 75.184 -153.7335)
		(end 75.80757 -153.10993)
		(stroke
			(width 0.085598)
			(type default)
		)
		(layer "F.Cu")
	)
	(gr_line
		(start 75.19924 -144.30756)
		(end 75.8063 -143.7005)
		(stroke
			(width 0.085598)
			(type default)
		)
		(layer "F.Cu")
	)
	(gr_line
		(start 75.19924 -143.09344)
		(end 75.8063 -143.7005)
		(stroke
			(width 0.085598)
			(type default)
		)
		(layer "F.Cu")
	)
	(gr_line
		(start 75.212956 -141.187424)
		(end 75.30338 -141.097)
		(stroke
			(width 0.085598)
			(type default)
		)
		(layer "F.Cu")
	)
	(gr_line
		(start 75.393804 -145.725134)
		(end 75.449938 -145.781268)
		(stroke
			(width 0.085598)
			(type default)
		)
		(layer "F.Cu")
	)
	(gr_line
		(start 75.397614 -363.799882)
		(end 75.449938 -363.747558)
		(stroke
			(width 0.085598)
			(type default)
		)
		(layer "F.Cu")
	)
	(gr_line
		(start 75.449938 -363.0422)
		(end 75.449938 -363.747558)
		(stroke
			(width 0.085598)
			(type default)
		)
		(layer "F.Cu")
	)
	(gr_line
		(start 75.449938 -358.380538)
		(end 75.449938 -359.0798)
		(stroke
			(width 0.085598)
			(type default)
		)
		(layer "F.Cu")
	)
	(gr_line
		(start 75.449938 -150.6982)
		(end 75.449938 -151.696166)
		(stroke
			(width 0.085598)
			(type default)
		)
		(layer "F.Cu")
	)
	(gr_line
		(start 75.449938 -145.781268)
		(end 75.449938 -146.7358)
		(stroke
			(width 0.085598)
			(type default)
		)
		(layer "F.Cu")
	)
	(gr_line
		(start 75.47483 -366.70107)
		(end 76.0984 -366.0775)
		(stroke
			(width 0.085598)
			(type default)
		)
		(layer "F.Cu")
	)
	(gr_line
		(start 75.47483 -365.45393)
		(end 76.0984 -366.0775)
		(stroke
			(width 0.085598)
			(type default)
		)
		(layer "F.Cu")
	)
	(gr_line
		(start 75.508358 -368.590576)
		(end 75.598782 -368.681)
		(stroke
			(width 0.085598)
			(type default)
		)
		(layer "F.Cu")
	)
	(gr_line
		(start 75.69962 -157.734)
		(end 75.790044 -157.643576)
		(stroke
			(width 0.085598)
			(type default)
		)
		(layer "F.Cu")
	)
	(gr_line
		(start 75.950064 -363.0422)
		(end 75.950064 -364.028736)
		(stroke
			(width 0.085598)
			(type default)
		)
		(layer "F.Cu")
	)
	(gr_line
		(start 75.950064 -151.584914)
		(end 75.95235 -151.5872)
		(stroke
			(width 0.085598)
			(type default)
		)
		(layer "F.Cu")
	)
	(gr_line
		(start 75.950064 -150.6982)
		(end 75.950064 -151.584914)
		(stroke
			(width 0.085598)
			(type default)
		)
		(layer "F.Cu")
	)
	(gr_line
		(start 75.950064 -145.949924)
		(end 75.950064 -146.7358)
		(stroke
			(width 0.085598)
			(type default)
		)
		(layer "F.Cu")
	)
	(gr_line
		(start 75.950064 -145.949924)
		(end 76.002388 -145.8976)
		(stroke
			(width 0.085598)
			(type default)
		)
		(layer "F.Cu")
	)
	(gr_line
		(start 75.95235 -151.5872)
		(end 75.95235 -152.110186)
		(stroke
			(width 0.085598)
			(type default)
		)
		(layer "F.Cu")
	)
	(gr_line
		(start 76.449936 -151.557736)
		(end 76.5048 -151.6126)
		(stroke
			(width 0.085598)
			(type default)
		)
		(layer "F.Cu")
	)
	(gr_line
		(start 76.449936 -150.6982)
		(end 76.449936 -151.557736)
		(stroke
			(width 0.085598)
			(type default)
		)
		(layer "F.Cu")
	)
	(gr_line
		(start 76.575158 -157.643576)
		(end 76.665582 -157.734)
		(stroke
			(width 0.085598)
			(type default)
		)
		(layer "F.Cu")
	)
	(gr_line
		(start 76.59243 -154.35707)
		(end 77.216 -153.7335)
		(stroke
			(width 0.085598)
			(type default)
		)
		(layer "F.Cu")
	)
	(gr_line
		(start 76.59243 -153.10993)
		(end 77.216 -153.7335)
		(stroke
			(width 0.085598)
			(type default)
		)
		(layer "F.Cu")
	)
	(gr_line
		(start 76.950062 -363.0422)
		(end 76.950062 -364.116366)
		(stroke
			(width 0.085598)
			(type default)
		)
		(layer "F.Cu")
	)
	(gr_line
		(start 76.950062 -150.6982)
		(end 76.950062 -151.645366)
		(stroke
			(width 0.085598)
			(type default)
		)
		(layer "F.Cu")
	)
	(gr_line
		(start 77.052424 -210.542124)
		(end 77.343 -210.8327)
		(stroke
			(width 0.087376)
			(type default)
		)
		(layer "F.Cu")
	)
	(gr_line
		(start 77.052424 -210.107276)
		(end 77.343 -209.8167)
		(stroke
			(width 0.087376)
			(type default)
		)
		(layer "F.Cu")
	)
	(gr_line
		(start 77.1144 -366.0775)
		(end 77.724 -365.4679)
		(stroke
			(width 0.085598)
			(type default)
		)
		(layer "F.Cu")
	)
	(gr_line
		(start 77.1144 -366.0775)
		(end 77.73797 -366.70107)
		(stroke
			(width 0.085598)
			(type default)
		)
		(layer "F.Cu")
	)
	(gr_line
		(start 77.204824 -101.449124)
		(end 77.4954 -101.7397)
		(stroke
			(width 0.087376)
			(type default)
		)
		(layer "F.Cu")
	)
	(gr_line
		(start 77.204824 -101.014276)
		(end 77.4954 -100.7237)
		(stroke
			(width 0.087376)
			(type default)
		)
		(layer "F.Cu")
	)
	(gr_line
		(start 77.230224 -304.890424)
		(end 77.5208 -305.181)
		(stroke
			(width 0.087376)
			(type default)
		)
		(layer "F.Cu")
	)
	(gr_line
		(start 77.230224 -304.455576)
		(end 77.5208 -304.165)
		(stroke
			(width 0.087376)
			(type default)
		)
		(layer "F.Cu")
	)
	(gr_line
		(start 77.343 -210.8327)
		(end 77.633576 -210.542124)
		(stroke
			(width 0.087376)
			(type default)
		)
		(layer "F.Cu")
	)
	(gr_line
		(start 77.343 -209.8167)
		(end 77.633576 -210.107276)
		(stroke
			(width 0.087376)
			(type default)
		)
		(layer "F.Cu")
	)
	(gr_line
		(start 77.449934 -363.834934)
		(end 77.502512 -363.887512)
		(stroke
			(width 0.085598)
			(type default)
		)
		(layer "F.Cu")
	)
	(gr_line
		(start 77.449934 -363.1184)
		(end 77.449934 -363.834934)
		(stroke
			(width 0.085598)
			(type default)
		)
		(layer "F.Cu")
	)
	(gr_line
		(start 77.449934 -151.363934)
		(end 77.502512 -151.416512)
		(stroke
			(width 0.085598)
			(type default)
		)
		(layer "F.Cu")
	)
	(gr_line
		(start 77.449934 -150.7744)
		(end 77.449934 -151.363934)
		(stroke
			(width 0.085598)
			(type default)
		)
		(layer "F.Cu")
	)
	(gr_line
		(start 77.484224 -431.509424)
		(end 77.7748 -431.8)
		(stroke
			(width 0.087376)
			(type default)
		)
		(layer "F.Cu")
	)
	(gr_line
		(start 77.484224 -431.074576)
		(end 77.7748 -430.784)
		(stroke
			(width 0.087376)
			(type default)
		)
		(layer "F.Cu")
	)
	(gr_line
		(start 77.4954 -101.7397)
		(end 77.785976 -101.449124)
		(stroke
			(width 0.087376)
			(type default)
		)
		(layer "F.Cu")
	)
	(gr_line
		(start 77.4954 -100.7237)
		(end 77.785976 -101.014276)
		(stroke
			(width 0.087376)
			(type default)
		)
		(layer "F.Cu")
	)
	(gr_line
		(start 77.5208 -305.181)
		(end 77.811376 -304.890424)
		(stroke
			(width 0.087376)
			(type default)
		)
		(layer "F.Cu")
	)
	(gr_line
		(start 77.5208 -304.165)
		(end 77.811376 -304.455576)
		(stroke
			(width 0.087376)
			(type default)
		)
		(layer "F.Cu")
	)
	(gr_line
		(start 77.68082 -368.6302)
		(end 77.771244 -368.539776)
		(stroke
			(width 0.085598)
			(type default)
		)
		(layer "F.Cu")
	)
	(gr_line
		(start 77.7748 -431.8)
		(end 78.065376 -431.509424)
		(stroke
			(width 0.087376)
			(type default)
		)
		(layer "F.Cu")
	)
	(gr_line
		(start 77.7748 -430.784)
		(end 78.065376 -431.074576)
		(stroke
			(width 0.087376)
			(type default)
		)
		(layer "F.Cu")
	)
	(gr_line
		(start 78.093824 -210.542124)
		(end 78.3844 -210.8327)
		(stroke
			(width 0.087376)
			(type default)
		)
		(layer "F.Cu")
	)
	(gr_line
		(start 78.093824 -210.107276)
		(end 78.3844 -209.8167)
		(stroke
			(width 0.087376)
			(type default)
		)
		(layer "F.Cu")
	)
	(gr_line
		(start 78.1812 -361.811062)
		(end 79.007462 -361.811062)
		(stroke
			(width 0.085598)
			(type default)
		)
		(layer "F.Cu")
	)
	(gr_line
		(start 78.1812 -361.310936)
		(end 78.992222 -361.310936)
		(stroke
			(width 0.085598)
			(type default)
		)
		(layer "F.Cu")
	)
	(gr_line
		(start 78.1812 -360.811064)
		(end 79.544672 -360.811064)
		(stroke
			(width 0.085598)
			(type default)
		)
		(layer "F.Cu")
	)
	(gr_line
		(start 78.1812 -360.310938)
		(end 79.058262 -360.310938)
		(stroke
			(width 0.085598)
			(type default)
		)
		(layer "F.Cu")
	)
	(gr_line
		(start 78.1812 -147.966938)
		(end 78.923642 -147.966938)
		(stroke
			(width 0.085598)
			(type default)
		)
		(layer "F.Cu")
	)
	(gr_line
		(start 78.232 -153.7335)
		(end 78.85557 -154.35707)
		(stroke
			(width 0.085598)
			(type default)
		)
		(layer "F.Cu")
	)
	(gr_line
		(start 78.232 -153.7335)
		(end 78.85557 -153.10993)
		(stroke
			(width 0.085598)
			(type default)
		)
		(layer "F.Cu")
	)
	(gr_line
		(start 78.2574 -362.310934)
		(end 78.72603 -362.310934)
		(stroke
			(width 0.085598)
			(type default)
		)
		(layer "F.Cu")
	)
	(gr_line
		(start 78.2574 -359.811066)
		(end 78.77683 -359.811066)
		(stroke
			(width 0.085598)
			(type default)
		)
		(layer "F.Cu")
	)
	(gr_line
		(start 78.2574 -147.467066)
		(end 78.64221 -147.467066)
		(stroke
			(width 0.085598)
			(type default)
		)
		(layer "F.Cu")
	)
	(gr_line
		(start 78.271624 -304.890424)
		(end 78.5622 -305.181)
		(stroke
			(width 0.087376)
			(type default)
		)
		(layer "F.Cu")
	)
	(gr_line
		(start 78.271624 -304.455576)
		(end 78.5622 -304.165)
		(stroke
			(width 0.087376)
			(type default)
		)
		(layer "F.Cu")
	)
	(gr_line
		(start 78.271624 -101.449124)
		(end 78.5622 -101.7397)
		(stroke
			(width 0.087376)
			(type default)
		)
		(layer "F.Cu")
	)
	(gr_line
		(start 78.271624 -101.014276)
		(end 78.5622 -100.7237)
		(stroke
			(width 0.087376)
			(type default)
		)
		(layer "F.Cu")
	)
	(gr_line
		(start 78.27899 -365.21009)
		(end 79.1464 -366.0775)
		(stroke
			(width 0.085598)
			(type default)
		)
		(layer "F.Cu")
	)
	(gr_line
		(start 78.3844 -210.8327)
		(end 78.674976 -210.542124)
		(stroke
			(width 0.087376)
			(type default)
		)
		(layer "F.Cu")
	)
	(gr_line
		(start 78.3844 -209.8167)
		(end 78.674976 -210.107276)
		(stroke
			(width 0.087376)
			(type default)
		)
		(layer "F.Cu")
	)
	(gr_line
		(start 78.52283 -366.70107)
		(end 79.1464 -366.0775)
		(stroke
			(width 0.085598)
			(type default)
		)
		(layer "F.Cu")
	)
	(gr_line
		(start 78.525624 -431.509424)
		(end 78.8162 -431.8)
		(stroke
			(width 0.087376)
			(type default)
		)
		(layer "F.Cu")
	)
	(gr_line
		(start 78.525624 -431.074576)
		(end 78.8162 -430.784)
		(stroke
			(width 0.087376)
			(type default)
		)
		(layer "F.Cu")
	)
	(gr_line
		(start 78.556358 -368.539776)
		(end 78.646782 -368.6302)
		(stroke
			(width 0.085598)
			(type default)
		)
		(layer "F.Cu")
	)
	(gr_line
		(start 78.5622 -305.181)
		(end 78.852776 -304.890424)
		(stroke
			(width 0.087376)
			(type default)
		)
		(layer "F.Cu")
	)
	(gr_line
		(start 78.5622 -304.165)
		(end 78.852776 -304.455576)
		(stroke
			(width 0.087376)
			(type default)
		)
		(layer "F.Cu")
	)
	(gr_line
		(start 78.5622 -101.7397)
		(end 78.852776 -101.449124)
		(stroke
			(width 0.087376)
			(type default)
		)
		(layer "F.Cu")
	)
	(gr_line
		(start 78.5622 -100.7237)
		(end 78.852776 -101.014276)
		(stroke
			(width 0.087376)
			(type default)
		)
		(layer "F.Cu")
	)
	(gr_line
		(start 78.64221 -147.467066)
		(end 78.694788 -147.414488)
		(stroke
			(width 0.085598)
			(type default)
		)
		(layer "F.Cu")
	)
	(gr_line
		(start 78.72603 -362.310934)
		(end 78.778608 -362.363512)
		(stroke
			(width 0.085598)
			(type default)
		)
		(layer "F.Cu")
	)
	(gr_line
		(start 78.74762 -156.337)
		(end 78.838044 -156.246576)
		(stroke
			(width 0.085598)
			(type default)
		)
		(layer "F.Cu")
	)
	(gr_line
		(start 78.77683 -359.811066)
		(end 78.829408 -359.758488)
		(stroke
			(width 0.085598)
			(type default)
		)
		(layer "F.Cu")
	)
	(gr_line
		(start 78.8162 -431.8)
		(end 79.106776 -431.509424)
		(stroke
			(width 0.087376)
			(type default)
		)
		(layer "F.Cu")
	)
	(gr_line
		(start 78.8162 -430.784)
		(end 79.106776 -431.074576)
		(stroke
			(width 0.087376)
			(type default)
		)
		(layer "F.Cu")
	)
	(gr_line
		(start 78.992222 -361.310936)
		(end 79.0448 -361.363514)
		(stroke
			(width 0.085598)
			(type default)
		)
		(layer "F.Cu")
	)
	(gr_line
		(start 79.623158 -156.246576)
		(end 79.713582 -156.337)
		(stroke
			(width 0.085598)
			(type default)
		)
		(layer "F.Cu")
	)
	(gr_line
		(start 79.64043 -154.35707)
		(end 80.264 -153.7335)
		(stroke
			(width 0.085598)
			(type default)
		)
		(layer "F.Cu")
	)
	(gr_line
		(start 79.64043 -153.10993)
		(end 80.264 -153.7335)
		(stroke
			(width 0.085598)
			(type default)
		)
		(layer "F.Cu")
	)
	(gr_line
		(start 79.953358 -146.155918)
		(end 80.01 -146.099276)
		(stroke
			(width 0.085598)
			(type default)
		)
		(layer "F.Cu")
	)
	(gr_line
		(start 79.955136 -146.939)
		(end 80.01 -146.939)
		(stroke
			(width 0.085598)
			(type default)
		)
		(layer "F.Cu")
	)
	(gr_line
		(start 80.01 -146.939)
		(end 80.518 -146.431)
		(stroke
			(width 0.085598)
			(type default)
		)
		(layer "F.Cu")
	)
	(gr_line
		(start 80.01 -145.87855)
		(end 80.01 -146.099276)
		(stroke
			(width 0.085598)
			(type default)
		)
		(layer "F.Cu")
	)
	(gr_line
		(start 80.01 -145.034)
		(end 80.01 -145.87601)
		(stroke
			(width 0.085598)
			(type default)
		)
		(layer "F.Cu")
	)
	(gr_line
		(start 80.01 -145.034)
		(end 80.391 -145.415)
		(stroke
			(width 0.085598)
			(type default)
		)
		(layer "F.Cu")
	)
	(gr_line
		(start 80.391 -145.415)
		(end 81.3435 -145.415)
		(stroke
			(width 0.085598)
			(type default)
		)
		(layer "F.Cu")
	)
	(gr_line
		(start 80.518 -146.431)
		(end 80.56245 -146.431)
		(stroke
			(width 0.085598)
			(type default)
		)
		(layer "F.Cu")
	)
	(gr_line
		(start 80.557624 -303.13376)
		(end 80.9371 -303.13376)
		(stroke
			(width 0.085598)
			(type default)
		)
		(layer "F.Cu")
	)
	(gr_line
		(start 80.56499 -146.431)
		(end 81.3435 -146.431)
		(stroke
			(width 0.085598)
			(type default)
		)
		(layer "F.Cu")
	)
	(gr_line
		(start 80.56753 -361.47883)
		(end 81.2165 -362.1278)
		(stroke
			(width 0.085598)
			(type default)
		)
		(layer "F.Cu")
	)
	(gr_line
		(start 80.56753 -360.69397)
		(end 81.2165 -360.045)
		(stroke
			(width 0.085598)
			(type default)
		)
		(layer "F.Cu")
	)
	(gr_line
		(start 80.59293 -364.55223)
		(end 81.2165 -365.1758)
		(stroke
			(width 0.085598)
			(type default)
		)
		(layer "F.Cu")
	)
	(gr_line
		(start 80.59293 -363.76737)
		(end 81.2165 -363.1438)
		(stroke
			(width 0.085598)
			(type default)
		)
		(layer "F.Cu")
	)
	(gr_line
		(start 80.602582 -358.415082)
		(end 81.2165 -359.029)
		(stroke
			(width 0.085598)
			(type default)
		)
		(layer "F.Cu")
	)
	(gr_line
		(start 80.602582 -357.629968)
		(end 81.2165 -357.01605)
		(stroke
			(width 0.085598)
			(type default)
		)
		(layer "F.Cu")
	)
	(gr_line
		(start 80.9371 -303.13376)
		(end 80.992218 -303.078642)
		(stroke
			(width 0.085598)
			(type default)
		)
		(layer "F.Cu")
	)
	(gr_line
		(start 80.938624 -99.42576)
		(end 81.3181 -99.42576)
		(stroke
			(width 0.085598)
			(type default)
		)
		(layer "F.Cu")
	)
	(gr_line
		(start 81.2165 -365.1758)
		(end 81.84007 -364.55223)
		(stroke
			(width 0.085598)
			(type default)
		)
		(layer "F.Cu")
	)
	(gr_line
		(start 81.2165 -363.1438)
		(end 81.84007 -363.76737)
		(stroke
			(width 0.085598)
			(type default)
		)
		(layer "F.Cu")
	)
	(gr_line
		(start 81.2165 -362.1278)
		(end 81.86547 -361.47883)
		(stroke
			(width 0.085598)
			(type default)
		)
		(layer "F.Cu")
	)
	(gr_line
		(start 81.2165 -360.045)
		(end 81.86547 -360.69397)
		(stroke
			(width 0.085598)
			(type default)
		)
		(layer "F.Cu")
	)
	(gr_line
		(start 81.2165 -359.029)
		(end 81.85277 -358.39273)
		(stroke
			(width 0.085598)
			(type default)
		)
		(layer "F.Cu")
	)
	(gr_line
		(start 81.2165 -356.9716)
		(end 81.2165 -357.01605)
		(stroke
			(width 0.085598)
			(type default)
		)
		(layer "F.Cu")
	)
	(gr_line
		(start 81.2165 -356.9716)
		(end 81.85277 -357.60787)
		(stroke
			(width 0.085598)
			(type default)
		)
		(layer "F.Cu")
	)
	(gr_line
		(start 81.3181 -99.42576)
		(end 81.373218 -99.370642)
		(stroke
			(width 0.085598)
			(type default)
		)
		(layer "F.Cu")
	)
	(gr_line
		(start 81.777332 -303.078642)
		(end 81.83245 -303.13376)
		(stroke
			(width 0.085598)
			(type default)
		)
		(layer "F.Cu")
	)
	(gr_line
		(start 81.83245 -303.13376)
		(end 82.462624 -303.13376)
		(stroke
			(width 0.085598)
			(type default)
		)
		(layer "F.Cu")
	)
	(gr_line
		(start 82.158332 -99.370642)
		(end 82.21345 -99.42576)
		(stroke
			(width 0.085598)
			(type default)
		)
		(layer "F.Cu")
	)
	(gr_line
		(start 82.21345 -99.42576)
		(end 82.843624 -99.42576)
		(stroke
			(width 0.085598)
			(type default)
		)
		(layer "F.Cu")
	)
	(gr_line
		(start 82.755994 -206.894684)
		(end 82.846418 -206.985108)
		(stroke
			(width 0.085598)
			(type default)
		)
		(layer "F.Cu")
	)
	(gr_line
		(start 82.755994 -206.10957)
		(end 82.846418 -206.019146)
		(stroke
			(width 0.085598)
			(type default)
		)
		(layer "F.Cu")
	)
	(gr_line
		(start 83.402424 -431.522124)
		(end 83.4644 -431.5841)
		(stroke
			(width 0.087376)
			(type default)
		)
		(layer "F.Cu")
	)
	(gr_line
		(start 83.402424 -431.087276)
		(end 83.4644 -431.0253)
		(stroke
			(width 0.087376)
			(type default)
		)
		(layer "F.Cu")
	)
	(gr_line
		(start 83.4644 -431.5841)
		(end 83.526376 -431.522124)
		(stroke
			(width 0.087376)
			(type default)
		)
		(layer "F.Cu")
	)
	(gr_line
		(start 83.4644 -431.0253)
		(end 83.526376 -431.087276)
		(stroke
			(width 0.087376)
			(type default)
		)
		(layer "F.Cu")
	)
	(gr_line
		(start 83.46567 -301.25543)
		(end 83.58124 -301.371)
		(stroke
			(width 0.085598)
			(type default)
		)
		(layer "F.Cu")
	)
	(gr_line
		(start 83.46567 -300.47057)
		(end 83.58124 -300.355)
		(stroke
			(width 0.085598)
			(type default)
		)
		(layer "F.Cu")
	)
	(gr_line
		(start 83.46567 -97.67443)
		(end 83.58124 -97.79)
		(stroke
			(width 0.085598)
			(type default)
		)
		(layer "F.Cu")
	)
	(gr_line
		(start 83.46567 -96.88957)
		(end 83.58124 -96.774)
		(stroke
			(width 0.085598)
			(type default)
		)
		(layer "F.Cu")
	)
	(gr_line
		(start 83.58124 -301.371)
		(end 84.0105 -301.371)
		(stroke
			(width 0.085598)
			(type default)
		)
		(layer "F.Cu")
	)
	(gr_line
		(start 83.58124 -300.355)
		(end 84.0105 -300.355)
		(stroke
			(width 0.085598)
			(type default)
		)
		(layer "F.Cu")
	)
	(gr_line
		(start 83.58124 -97.79)
		(end 84.0105 -97.79)
		(stroke
			(width 0.085598)
			(type default)
		)
		(layer "F.Cu")
	)
	(gr_line
		(start 83.58124 -96.774)
		(end 84.0105 -96.774)
		(stroke
			(width 0.085598)
			(type default)
		)
		(layer "F.Cu")
	)
	(gr_line
		(start 83.729576 -364.442756)
		(end 83.82 -364.53318)
		(stroke
			(width 0.085598)
			(type default)
		)
		(layer "F.Cu")
	)
	(gr_line
		(start 83.729576 -363.657642)
		(end 83.82 -363.567218)
		(stroke
			(width 0.085598)
			(type default)
		)
		(layer "F.Cu")
	)
	(gr_line
		(start 83.729576 -361.470956)
		(end 83.82 -361.56138)
		(stroke
			(width 0.085598)
			(type default)
		)
		(layer "F.Cu")
	)
	(gr_line
		(start 83.729576 -360.685842)
		(end 83.82 -360.595418)
		(stroke
			(width 0.085598)
			(type default)
		)
		(layer "F.Cu")
	)
	(gr_line
		(start 83.805776 -358.328976)
		(end 83.8962 -358.4194)
		(stroke
			(width 0.085598)
			(type default)
		)
		(layer "F.Cu")
	)
	(gr_line
		(start 83.805776 -357.543862)
		(end 83.8962 -357.453438)
		(stroke
			(width 0.085598)
			(type default)
		)
		(layer "F.Cu")
	)
	(gr_line
		(start 84.8995 -427.99)
		(end 85.36051 -427.52899)
		(stroke
			(width 0.085598)
			(type default)
		)
		(layer "F.Cu")
	)
	(gr_line
		(start 84.8995 -301.371)
		(end 86.52256 -301.371)
		(stroke
			(width 0.085598)
			(type default)
		)
		(layer "F.Cu")
	)
	(gr_line
		(start 84.8995 -300.355)
		(end 85.598 -300.355)
		(stroke
			(width 0.085598)
			(type default)
		)
		(layer "F.Cu")
	)
	(gr_line
		(start 84.8995 -207.01)
		(end 85.36051 -206.54899)
		(stroke
			(width 0.085598)
			(type default)
		)
		(layer "F.Cu")
	)
	(gr_line
		(start 84.8995 -97.79)
		(end 86.995 -97.79)
		(stroke
			(width 0.085598)
			(type default)
		)
		(layer "F.Cu")
	)
	(gr_line
		(start 84.8995 -96.774)
		(end 85.598 -96.774)
		(stroke
			(width 0.085598)
			(type default)
		)
		(layer "F.Cu")
	)
	(gr_line
		(start 85.485224 -210.542124)
		(end 85.5472 -210.6041)
		(stroke
			(width 0.087376)
			(type default)
		)
		(layer "F.Cu")
	)
	(gr_line
		(start 85.485224 -210.107276)
		(end 85.5472 -210.0453)
		(stroke
			(width 0.087376)
			(type default)
		)
		(layer "F.Cu")
	)
	(gr_line
		(start 85.5472 -210.6041)
		(end 85.609176 -210.542124)
		(stroke
			(width 0.087376)
			(type default)
		)
		(layer "F.Cu")
	)
	(gr_line
		(start 85.5472 -210.0453)
		(end 85.609176 -210.107276)
		(stroke
			(width 0.087376)
			(type default)
		)
		(layer "F.Cu")
	)
	(gr_line
		(start 85.598 -300.355)
		(end 86.106 -299.847)
		(stroke
			(width 0.085598)
			(type default)
		)
		(layer "F.Cu")
	)
	(gr_line
		(start 85.598 -96.774)
		(end 86.106 -96.266)
		(stroke
			(width 0.085598)
			(type default)
		)
		(layer "F.Cu")
	)
	(gr_line
		(start 85.60054 -426.97146)
		(end 85.9536 -426.6184)
		(stroke
			(width 0.085598)
			(type default)
		)
		(layer "F.Cu")
	)
	(gr_line
		(start 85.60054 -205.99146)
		(end 86.106 -205.486)
		(stroke
			(width 0.085598)
			(type default)
		)
		(layer "F.Cu")
	)
	(gr_line
		(start 85.663024 -304.903124)
		(end 85.725 -304.9651)
		(stroke
			(width 0.087376)
			(type default)
		)
		(layer "F.Cu")
	)
	(gr_line
		(start 85.663024 -304.468276)
		(end 85.725 -304.4063)
		(stroke
			(width 0.087376)
			(type default)
		)
		(layer "F.Cu")
	)
	(gr_line
		(start 85.725 -304.9651)
		(end 85.786976 -304.903124)
		(stroke
			(width 0.087376)
			(type default)
		)
		(layer "F.Cu")
	)
	(gr_line
		(start 85.725 -304.4063)
		(end 85.786976 -304.468276)
		(stroke
			(width 0.087376)
			(type default)
		)
		(layer "F.Cu")
	)
	(gr_line
		(start 85.739224 -101.461824)
		(end 85.8012 -101.5238)
		(stroke
			(width 0.087376)
			(type default)
		)
		(layer "F.Cu")
	)
	(gr_line
		(start 85.739224 -101.026976)
		(end 85.8012 -100.965)
		(stroke
			(width 0.087376)
			(type default)
		)
		(layer "F.Cu")
	)
	(gr_line
		(start 85.8012 -101.5238)
		(end 85.863176 -101.461824)
		(stroke
			(width 0.087376)
			(type default)
		)
		(layer "F.Cu")
	)
	(gr_line
		(start 85.8012 -100.965)
		(end 85.863176 -101.026976)
		(stroke
			(width 0.087376)
			(type default)
		)
		(layer "F.Cu")
	)
	(gr_line
		(start 85.9536 -426.6184)
		(end 86.1314 -426.6184)
		(stroke
			(width 0.085598)
			(type default)
		)
		(layer "F.Cu")
	)
	(gr_line
		(start 86.106 -299.847)
		(end 86.92007 -300.66107)
		(stroke
			(width 0.085598)
			(type default)
		)
		(layer "F.Cu")
	)
	(gr_line
		(start 86.106 -205.486)
		(end 86.116414 -205.496414)
		(stroke
			(width 0.085598)
			(type default)
		)
		(layer "F.Cu")
	)
	(gr_line
		(start 86.106 -96.266)
		(end 87.0204 -97.1804)
		(stroke
			(width 0.085598)
			(type default)
		)
		(layer "F.Cu")
	)
	(gr_line
		(start 86.116414 -205.496414)
		(end 86.345014 -205.496414)
		(stroke
			(width 0.085598)
			(type default)
		)
		(layer "F.Cu")
	)
	(gr_line
		(start 86.1314 -426.6184)
		(end 86.2584 -426.6184)
		(stroke
			(width 0.085598)
			(type default)
		)
		(layer "F.Cu")
	)
	(gr_line
		(start 86.15299 -427.52645)
		(end 86.38159 -427.52645)
		(stroke
			(width 0.085598)
			(type default)
		)
		(layer "F.Cu")
	)
	(gr_line
		(start 86.15299 -206.54645)
		(end 86.61019 -206.54645)
		(stroke
			(width 0.085598)
			(type default)
		)
		(layer "F.Cu")
	)
	(gr_line
		(start 86.233 -146.42338)
		(end 86.323424 -146.332956)
		(stroke
			(width 0.085598)
			(type default)
		)
		(layer "F.Cu")
	)
	(gr_line
		(start 86.233 -145.457418)
		(end 86.323424 -145.547842)
		(stroke
			(width 0.085598)
			(type default)
		)
		(layer "F.Cu")
	)
	(gr_line
		(start 86.2584 -426.6184)
		(end 86.383368 -426.743368)
		(stroke
			(width 0.085598)
			(type default)
		)
		(layer "F.Cu")
	)
	(gr_line
		(start 86.345014 -205.496414)
		(end 86.611968 -205.763368)
		(stroke
			(width 0.085598)
			(type default)
		)
		(layer "F.Cu")
	)
	(gr_line
		(start 86.487 -440.8805)
		(end 86.777576 -441.171076)
		(stroke
			(width 0.087376)
			(type default)
		)
		(layer "F.Cu")
	)
	(gr_line
		(start 86.487 -439.9915)
		(end 86.6267 -439.9915)
		(stroke
			(width 0.087376)
			(type default)
		)
		(layer "F.Cu")
	)
	(gr_line
		(start 86.487 -423.6085)
		(end 86.6775 -423.6085)
		(stroke
			(width 0.087376)
			(type default)
		)
		(layer "F.Cu")
	)
	(gr_line
		(start 86.487 -422.7195)
		(end 86.777576 -422.428924)
		(stroke
			(width 0.087376)
			(type default)
		)
		(layer "F.Cu")
	)
	(gr_line
		(start 86.487 -314.2615)
		(end 86.777576 -314.552076)
		(stroke
			(width 0.087376)
			(type default)
		)
		(layer "F.Cu")
	)
	(gr_line
		(start 86.487 -313.3725)
		(end 86.6521 -313.3725)
		(stroke
			(width 0.087376)
			(type default)
		)
		(layer "F.Cu")
	)
	(gr_line
		(start 86.487 -219.9005)
		(end 86.777576 -220.191076)
		(stroke
			(width 0.087376)
			(type default)
		)
		(layer "F.Cu")
	)
	(gr_line
		(start 86.487 -219.0115)
		(end 86.5759 -219.0115)
		(stroke
			(width 0.087376)
			(type default)
		)
		(layer "F.Cu")
	)
	(gr_line
		(start 86.487 -110.6805)
		(end 86.764876 -110.958376)
		(stroke
			(width 0.087376)
			(type default)
		)
		(layer "F.Cu")
	)
	(gr_line
		(start 86.487 -109.7915)
		(end 86.5251 -109.7915)
		(stroke
			(width 0.087376)
			(type default)
		)
		(layer "F.Cu")
	)
	(gr_line
		(start 86.487 -93.4085)
		(end 86.5251 -93.4085)
		(stroke
			(width 0.087376)
			(type default)
		)
		(layer "F.Cu")
	)
	(gr_line
		(start 86.487 -92.5195)
		(end 86.777576 -92.228924)
		(stroke
			(width 0.087376)
			(type default)
		)
		(layer "F.Cu")
	)
	(gr_line
		(start 86.5251 -109.7915)
		(end 86.796626 -109.519974)
		(stroke
			(width 0.087376)
			(type default)
		)
		(layer "F.Cu")
	)
	(gr_line
		(start 86.5251 -93.4085)
		(end 86.796626 -93.680026)
		(stroke
			(width 0.087376)
			(type default)
		)
		(layer "F.Cu")
	)
	(gr_line
		(start 86.5759 -219.0115)
		(end 86.822026 -218.765374)
		(stroke
			(width 0.087376)
			(type default)
		)
		(layer "F.Cu")
	)
	(gr_line
		(start 86.6267 -439.9915)
		(end 86.847426 -439.770774)
		(stroke
			(width 0.087376)
			(type default)
		)
		(layer "F.Cu")
	)
	(gr_line
		(start 86.6521 -313.3725)
		(end 86.842346 -313.182254)
		(stroke
			(width 0.087376)
			(type default)
		)
		(layer "F.Cu")
	)
	(gr_line
		(start 86.6775 -423.6085)
		(end 86.842346 -423.773346)
		(stroke
			(width 0.087376)
			(type default)
		)
		(layer "F.Cu")
	)
	(gr_line
		(start 86.995 -97.79)
		(end 87.122 -97.917)
		(stroke
			(width 0.085598)
			(type default)
		)
		(layer "F.Cu")
	)
	(gr_line
		(start 87.0204 -97.1804)
		(end 87.249 -97.1804)
		(stroke
			(width 0.085598)
			(type default)
		)
		(layer "F.Cu")
	)
	(gr_line
		(start 87.0458 -428.2948)
		(end 87.0458 -428.5488)
		(stroke
			(width 0.085598)
			(type default)
		)
		(layer "F.Cu")
	)
	(gr_line
		(start 87.0458 -428.19066)
		(end 87.0458 -428.2948)
		(stroke
			(width 0.085598)
			(type default)
		)
		(layer "F.Cu")
	)
	(gr_line
		(start 87.122 -301.498)
		(end 87.22741 -301.60341)
		(stroke
			(width 0.085598)
			(type default)
		)
		(layer "F.Cu")
	)
	(gr_line
		(start 87.122 -207.137)
		(end 87.20201 -207.21701)
		(stroke
			(width 0.085598)
			(type default)
		)
		(layer "F.Cu")
	)
	(gr_line
		(start 87.122 -207.05826)
		(end 87.122 -207.137)
		(stroke
			(width 0.085598)
			(type default)
		)
		(layer "F.Cu")
	)
	(gr_line
		(start 87.122 -97.917)
		(end 87.20201 -97.99701)
		(stroke
			(width 0.085598)
			(type default)
		)
		(layer "F.Cu")
	)
	(gr_line
		(start 87.14994 -423.96156)
		(end 87.503 -423.6085)
		(stroke
			(width 0.087376)
			(type default)
		)
		(layer "F.Cu")
	)
	(gr_line
		(start 87.14994 -313.01944)
		(end 87.503 -313.3725)
		(stroke
			(width 0.087376)
			(type default)
		)
		(layer "F.Cu")
	)
	(gr_line
		(start 87.199724 -110.958376)
		(end 87.4776 -110.6805)
		(stroke
			(width 0.087376)
			(type default)
		)
		(layer "F.Cu")
	)
	(gr_line
		(start 87.212424 -441.171076)
		(end 87.503 -440.8805)
		(stroke
			(width 0.087376)
			(type default)
		)
		(layer "F.Cu")
	)
	(gr_line
		(start 87.212424 -422.428924)
		(end 87.503 -422.7195)
		(stroke
			(width 0.087376)
			(type default)
		)
		(layer "F.Cu")
	)
	(gr_line
		(start 87.212424 -314.552076)
		(end 87.503 -314.2615)
		(stroke
			(width 0.087376)
			(type default)
		)
		(layer "F.Cu")
	)
	(gr_line
		(start 87.212424 -220.191076)
		(end 87.503 -219.9005)
		(stroke
			(width 0.087376)
			(type default)
		)
		(layer "F.Cu")
	)
	(gr_line
		(start 87.212424 -92.228924)
		(end 87.503 -92.5195)
		(stroke
			(width 0.087376)
			(type default)
		)
		(layer "F.Cu")
	)
	(gr_line
		(start 87.231474 -109.519974)
		(end 87.503 -109.7915)
		(stroke
			(width 0.087376)
			(type default)
		)
		(layer "F.Cu")
	)
	(gr_line
		(start 87.231474 -93.680026)
		(end 87.503 -93.4085)
		(stroke
			(width 0.087376)
			(type default)
		)
		(layer "F.Cu")
	)
	(gr_line
		(start 87.238586 -438.741566)
		(end 87.238586 -438.918858)
		(stroke
			(width 0.087376)
			(type default)
		)
		(layer "F.Cu")
	)
	(gr_line
		(start 87.238586 -438.741566)
		(end 87.609426 -438.37098)
		(stroke
			(width 0.087376)
			(type default)
		)
		(layer "F.Cu")
	)
	(gr_line
		(start 87.249 -97.1804)
		(end 87.757 -97.6884)
		(stroke
			(width 0.085598)
			(type default)
		)
		(layer "F.Cu")
	)
	(gr_line
		(start 87.256874 -218.765374)
		(end 87.503 -219.0115)
		(stroke
			(width 0.087376)
			(type default)
		)
		(layer "F.Cu")
	)
	(gr_line
		(start 87.282274 -439.770774)
		(end 87.503 -439.9915)
		(stroke
			(width 0.087376)
			(type default)
		)
		(layer "F.Cu")
	)
	(gr_line
		(start 87.33155 -300.81855)
		(end 87.7824 -301.2694)
		(stroke
			(width 0.085598)
			(type default)
		)
		(layer "F.Cu")
	)
	(gr_line
		(start 87.4776 -110.6805)
		(end 87.503 -110.6805)
		(stroke
			(width 0.087376)
			(type default)
		)
		(layer "F.Cu")
	)
	(gr_line
		(start 87.609426 -438.37098)
		(end 87.786464 -438.37098)
		(stroke
			(width 0.087376)
			(type default)
		)
		(layer "F.Cu")
	)
	(gr_line
		(start 87.66683 -428.02683)
		(end 87.66683 -428.38497)
		(stroke
			(width 0.085598)
			(type default)
		)
		(layer "F.Cu")
	)
	(gr_line
		(start 87.67191 -438.920636)
		(end 87.788242 -438.804304)
		(stroke
			(width 0.087376)
			(type default)
		)
		(layer "F.Cu")
	)
	(gr_line
		(start 88.357964 -101.092)
		(end 88.489282 -101.092)
		(stroke
			(width 0.087376)
			(type default)
		)
		(layer "F.Cu")
	)
	(gr_line
		(start 88.41994 -99.84994)
		(end 89.55659 -99.84994)
		(stroke
			(width 0.085598)
			(type default)
		)
		(layer "F.Cu")
	)
	(gr_line
		(start 88.47074 -209.06994)
		(end 89.55659 -209.06994)
		(stroke
			(width 0.085598)
			(type default)
		)
		(layer "F.Cu")
	)
	(gr_line
		(start 88.54694 -430.04994)
		(end 89.55659 -430.04994)
		(stroke
			(width 0.085598)
			(type default)
		)
		(layer "F.Cu")
	)
	(gr_line
		(start 88.571324 -312.42)
		(end 88.63203 -312.35904)
		(stroke
			(width 0.087376)
			(type default)
		)
		(layer "F.Cu")
	)
	(gr_line
		(start 88.599264 -302.93056)
		(end 89.55659 -302.93056)
		(stroke
			(width 0.085598)
			(type default)
		)
		(layer "F.Cu")
	)
	(gr_line
		(start 88.648794 -99.29749)
		(end 88.700864 -99.34956)
		(stroke
			(width 0.085598)
			(type default)
		)
		(layer "F.Cu")
	)
	(gr_line
		(start 88.663018 -101.34981)
		(end 88.794336 -101.34981)
		(stroke
			(width 0.087376)
			(type default)
		)
		(layer "F.Cu")
	)
	(gr_line
		(start 88.664796 -100.916486)
		(end 88.731852 -100.84943)
		(stroke
			(width 0.087376)
			(type default)
		)
		(layer "F.Cu")
	)
	(gr_line
		(start 88.69934 -431.517044)
		(end 88.732106 -431.54981)
		(stroke
			(width 0.087376)
			(type default)
		)
		(layer "F.Cu")
	)
	(gr_line
		(start 88.69934 -431.081942)
		(end 88.731852 -431.04943)
		(stroke
			(width 0.087376)
			(type default)
		)
		(layer "F.Cu")
	)
	(gr_line
		(start 88.69934 -304.898044)
		(end 88.732106 -304.93081)
		(stroke
			(width 0.087376)
			(type default)
		)
		(layer "F.Cu")
	)
	(gr_line
		(start 88.69934 -304.462942)
		(end 88.731852 -304.43043)
		(stroke
			(width 0.087376)
			(type default)
		)
		(layer "F.Cu")
	)
	(gr_line
		(start 88.69934 -210.537044)
		(end 88.732106 -210.56981)
		(stroke
			(width 0.087376)
			(type default)
		)
		(layer "F.Cu")
	)
	(gr_line
		(start 88.69934 -210.101942)
		(end 88.731852 -210.06943)
		(stroke
			(width 0.087376)
			(type default)
		)
		(layer "F.Cu")
	)
	(gr_line
		(start 88.699594 -208.51749)
		(end 88.751664 -208.56956)
		(stroke
			(width 0.085598)
			(type default)
		)
		(layer "F.Cu")
	)
	(gr_line
		(start 88.700864 -99.34956)
		(end 89.55659 -99.34956)
		(stroke
			(width 0.085598)
			(type default)
		)
		(layer "F.Cu")
	)
	(gr_line
		(start 88.731852 -431.04943)
		(end 89.55659 -431.04943)
		(stroke
			(width 0.087376)
			(type default)
		)
		(layer "F.Cu")
	)
	(gr_line
		(start 88.731852 -304.43043)
		(end 89.55659 -304.43043)
		(stroke
			(width 0.087376)
			(type default)
		)
		(layer "F.Cu")
	)
	(gr_line
		(start 88.731852 -210.06943)
		(end 89.55659 -210.06943)
		(stroke
			(width 0.087376)
			(type default)
		)
		(layer "F.Cu")
	)
	(gr_line
		(start 88.731852 -100.84943)
		(end 89.55659 -100.84943)
		(stroke
			(width 0.087376)
			(type default)
		)
		(layer "F.Cu")
	)
	(gr_line
		(start 88.732106 -431.54981)
		(end 89.55659 -431.54981)
		(stroke
			(width 0.087376)
			(type default)
		)
		(layer "F.Cu")
	)
	(gr_line
		(start 88.732106 -304.93081)
		(end 89.55659 -304.93081)
		(stroke
			(width 0.087376)
			(type default)
		)
		(layer "F.Cu")
	)
	(gr_line
		(start 88.732106 -210.56981)
		(end 89.55659 -210.56981)
		(stroke
			(width 0.087376)
			(type default)
		)
		(layer "F.Cu")
	)
	(gr_line
		(start 88.751664 -208.56956)
		(end 89.55659 -208.56956)
		(stroke
			(width 0.085598)
			(type default)
		)
		(layer "F.Cu")
	)
	(gr_line
		(start 88.775794 -429.49749)
		(end 88.827864 -429.54956)
		(stroke
			(width 0.085598)
			(type default)
		)
		(layer "F.Cu")
	)
	(gr_line
		(start 88.796876 -101.34981)
		(end 89.55659 -101.34981)
		(stroke
			(width 0.087376)
			(type default)
		)
		(layer "F.Cu")
	)
	(gr_line
		(start 88.827864 -429.54956)
		(end 89.55659 -429.54956)
		(stroke
			(width 0.085598)
			(type default)
		)
		(layer "F.Cu")
	)
	(gr_line
		(start 88.8492 -303.48301)
		(end 88.90127 -303.43094)
		(stroke
			(width 0.085598)
			(type default)
		)
		(layer "F.Cu")
	)
	(gr_line
		(start 88.90127 -303.43094)
		(end 89.55659 -303.43094)
		(stroke
			(width 0.085598)
			(type default)
		)
		(layer "F.Cu")
	)
	(gr_line
		(start 89.066624 -358.394)
		(end 89.4207 -358.394)
		(stroke
			(width 0.085598)
			(type default)
		)
		(layer "F.Cu")
	)
	(gr_line
		(start 89.07526 -425.417488)
		(end 89.4461 -425.788074)
		(stroke
			(width 0.087376)
			(type default)
		)
		(layer "F.Cu")
	)
	(gr_line
		(start 89.07526 -425.240196)
		(end 89.07526 -425.417488)
		(stroke
			(width 0.087376)
			(type default)
		)
		(layer "F.Cu")
	)
	(gr_line
		(start 89.092786 -95.090234)
		(end 89.463626 -95.46082)
		(stroke
			(width 0.087376)
			(type default)
		)
		(layer "F.Cu")
	)
	(gr_line
		(start 89.092786 -94.912942)
		(end 89.092786 -95.090234)
		(stroke
			(width 0.087376)
			(type default)
		)
		(layer "F.Cu")
	)
	(gr_line
		(start 89.09304 -217.278966)
		(end 89.09304 -217.456258)
		(stroke
			(width 0.087376)
			(type default)
		)
		(layer "F.Cu")
	)
	(gr_line
		(start 89.09304 -217.278966)
		(end 89.46388 -216.90838)
		(stroke
			(width 0.087376)
			(type default)
		)
		(layer "F.Cu")
	)
	(gr_line
		(start 89.282778 -311.095136)
		(end 89.282778 -311.272428)
		(stroke
			(width 0.087376)
			(type default)
		)
		(layer "F.Cu")
	)
	(gr_line
		(start 89.282778 -311.095136)
		(end 89.65311 -310.724296)
		(stroke
			(width 0.087376)
			(type default)
		)
		(layer "F.Cu")
	)
	(gr_line
		(start 89.37244 -107.753912)
		(end 89.37244 -107.931204)
		(stroke
			(width 0.087376)
			(type default)
		)
		(layer "F.Cu")
	)
	(gr_line
		(start 89.37244 -107.753912)
		(end 89.74328 -107.383326)
		(stroke
			(width 0.087376)
			(type default)
		)
		(layer "F.Cu")
	)
	(gr_line
		(start 89.4207 -358.394)
		(end 89.528142 -358.501442)
		(stroke
			(width 0.085598)
			(type default)
		)
		(layer "F.Cu")
	)
	(gr_line
		(start 89.4461 -425.788074)
		(end 89.623138 -425.788074)
		(stroke
			(width 0.087376)
			(type default)
		)
		(layer "F.Cu")
	)
	(gr_line
		(start 89.463626 -95.46082)
		(end 89.640664 -95.46082)
		(stroke
			(width 0.087376)
			(type default)
		)
		(layer "F.Cu")
	)
	(gr_line
		(start 89.46388 -216.90838)
		(end 89.640918 -216.90838)
		(stroke
			(width 0.087376)
			(type default)
		)
		(layer "F.Cu")
	)
	(gr_line
		(start 89.508584 -425.238418)
		(end 89.624916 -425.35475)
		(stroke
			(width 0.087376)
			(type default)
		)
		(layer "F.Cu")
	)
	(gr_line
		(start 89.52611 -94.911164)
		(end 89.642442 -95.027496)
		(stroke
			(width 0.087376)
			(type default)
		)
		(layer "F.Cu")
	)
	(gr_line
		(start 89.526364 -217.458036)
		(end 89.642696 -217.341704)
		(stroke
			(width 0.087376)
			(type default)
		)
		(layer "F.Cu")
	)
	(gr_line
		(start 89.526618 -311.46369)
		(end 90.02395 -310.96585)
		(stroke
			(width 0.087376)
			(type default)
		)
		(layer "F.Cu")
	)
	(gr_line
		(start 89.65311 -310.724296)
		(end 89.830656 -310.724042)
		(stroke
			(width 0.087376)
			(type default)
		)
		(layer "F.Cu")
	)
	(gr_line
		(start 89.74328 -107.383326)
		(end 89.920318 -107.383326)
		(stroke
			(width 0.087376)
			(type default)
		)
		(layer "F.Cu")
	)
	(gr_line
		(start 89.805764 -107.932982)
		(end 89.922096 -107.81665)
		(stroke
			(width 0.087376)
			(type default)
		)
		(layer "F.Cu")
	)
	(gr_line
		(start 90.22969 -436.350918)
		(end 90.22969 -437.091328)
		(stroke
			(width 0.087376)
			(type default)
		)
		(layer "F.Cu")
	)
	(gr_line
		(start 90.22969 -426.394626)
		(end 90.22969 -427.249082)
		(stroke
			(width 0.087376)
			(type default)
		)
		(layer "F.Cu")
	)
	(gr_line
		(start 90.22969 -309.731918)
		(end 90.22969 -310.3245)
		(stroke
			(width 0.087376)
			(type default)
		)
		(layer "F.Cu")
	)
	(gr_line
		(start 90.22969 -215.985344)
		(end 90.244422 -216.000076)
		(stroke
			(width 0.087376)
			(type default)
		)
		(layer "F.Cu")
	)
	(gr_line
		(start 90.22969 -215.370918)
		(end 90.22969 -215.985344)
		(stroke
			(width 0.087376)
			(type default)
		)
		(layer "F.Cu")
	)
	(gr_line
		(start 90.22969 -106.73969)
		(end 90.244676 -106.754676)
		(stroke
			(width 0.087376)
			(type default)
		)
		(layer "F.Cu")
	)
	(gr_line
		(start 90.22969 -106.150918)
		(end 90.22969 -106.73969)
		(stroke
			(width 0.087376)
			(type default)
		)
		(layer "F.Cu")
	)
	(gr_line
		(start 90.22969 -96.43491)
		(end 90.22969 -97.049082)
		(stroke
			(width 0.087376)
			(type default)
		)
		(layer "F.Cu")
	)
	(gr_line
		(start 90.22969 -96.43491)
		(end 90.270584 -96.394016)
		(stroke
			(width 0.087376)
			(type default)
		)
		(layer "F.Cu")
	)
	(gr_line
		(start 90.297 -440.8805)
		(end 90.587576 -441.171076)
		(stroke
			(width 0.087376)
			(type default)
		)
		(layer "F.Cu")
	)
	(gr_line
		(start 90.297 -439.9915)
		(end 90.587576 -439.700924)
		(stroke
			(width 0.087376)
			(type default)
		)
		(layer "F.Cu")
	)
	(gr_line
		(start 90.297 -423.6085)
		(end 90.587576 -423.899076)
		(stroke
			(width 0.087376)
			(type default)
		)
		(layer "F.Cu")
	)
	(gr_line
		(start 90.297 -422.7195)
		(end 90.587576 -422.428924)
		(stroke
			(width 0.087376)
			(type default)
		)
		(layer "F.Cu")
	)
	(gr_line
		(start 90.297 -314.2615)
		(end 90.587576 -314.552076)
		(stroke
			(width 0.087376)
			(type default)
		)
		(layer "F.Cu")
	)
	(gr_line
		(start 90.297 -313.3725)
		(end 90.587576 -313.081924)
		(stroke
			(width 0.087376)
			(type default)
		)
		(layer "F.Cu")
	)
	(gr_line
		(start 90.297 -219.9005)
		(end 90.587576 -220.191076)
		(stroke
			(width 0.087376)
			(type default)
		)
		(layer "F.Cu")
	)
	(gr_line
		(start 90.297 -219.0115)
		(end 90.587576 -218.720924)
		(stroke
			(width 0.087376)
			(type default)
		)
		(layer "F.Cu")
	)
	(gr_line
		(start 90.297 -110.6805)
		(end 90.587576 -110.971076)
		(stroke
			(width 0.087376)
			(type default)
		)
		(layer "F.Cu")
	)
	(gr_line
		(start 90.297 -109.7915)
		(end 90.587576 -109.500924)
		(stroke
			(width 0.087376)
			(type default)
		)
		(layer "F.Cu")
	)
	(gr_line
		(start 90.297 -93.4085)
		(end 90.587576 -93.699076)
		(stroke
			(width 0.087376)
			(type default)
		)
		(layer "F.Cu")
	)
	(gr_line
		(start 90.297 -92.5195)
		(end 90.587576 -92.228924)
		(stroke
			(width 0.087376)
			(type default)
		)
		(layer "F.Cu")
	)
	(gr_line
		(start 90.313256 -358.501442)
		(end 90.420698 -358.394)
		(stroke
			(width 0.085598)
			(type default)
		)
		(layer "F.Cu")
	)
	(gr_line
		(start 90.420698 -358.394)
		(end 90.971624 -358.394)
		(stroke
			(width 0.085598)
			(type default)
		)
		(layer "F.Cu")
	)
	(gr_line
		(start 90.472768 -310.516524)
		(end 90.73007 -310.258714)
		(stroke
			(width 0.087376)
			(type default)
		)
		(layer "F.Cu")
	)
	(gr_line
		(start 90.652346 -438.810654)
		(end 90.714322 -438.748678)
		(stroke
			(width 0.087376)
			(type default)
		)
		(layer "F.Cu")
	)
	(gr_line
		(start 90.663014 -437.093106)
		(end 90.73007 -437.02605)
		(stroke
			(width 0.087376)
			(type default)
		)
		(layer "F.Cu")
	)
	(gr_line
		(start 90.663014 -426.392848)
		(end 90.73007 -426.459904)
		(stroke
			(width 0.087376)
			(type default)
		)
		(layer "F.Cu")
	)
	(gr_line
		(start 90.679524 -216.000076)
		(end 90.73007 -215.94953)
		(stroke
			(width 0.087376)
			(type default)
		)
		(layer "F.Cu")
	)
	(gr_line
		(start 90.679524 -106.754676)
		(end 90.73007 -106.70413)
		(stroke
			(width 0.087376)
			(type default)
		)
		(layer "F.Cu")
	)
	(gr_line
		(start 90.705686 -96.394016)
		(end 90.73007 -96.4184)
		(stroke
			(width 0.087376)
			(type default)
		)
		(layer "F.Cu")
	)
	(gr_line
		(start 90.73007 -436.22341)
		(end 90.73007 -437.02605)
		(stroke
			(width 0.087376)
			(type default)
		)
		(layer "F.Cu")
	)
	(gr_line
		(start 90.73007 -426.459904)
		(end 90.73007 -427.37659)
		(stroke
			(width 0.087376)
			(type default)
		)
		(layer "F.Cu")
	)
	(gr_line
		(start 90.73007 -309.60441)
		(end 90.73007 -310.258714)
		(stroke
			(width 0.087376)
			(type default)
		)
		(layer "F.Cu")
	)
	(gr_line
		(start 90.73007 -215.24341)
		(end 90.73007 -215.94953)
		(stroke
			(width 0.087376)
			(type default)
		)
		(layer "F.Cu")
	)
	(gr_line
		(start 90.73007 -106.02341)
		(end 90.73007 -106.70413)
		(stroke
			(width 0.087376)
			(type default)
		)
		(layer "F.Cu")
	)
	(gr_line
		(start 90.73007 -96.4184)
		(end 90.73007 -97.17659)
		(stroke
			(width 0.087376)
			(type default)
		)
		(layer "F.Cu")
	)
	(gr_line
		(start 91.022424 -441.171076)
		(end 91.313 -440.8805)
		(stroke
			(width 0.087376)
			(type default)
		)
		(layer "F.Cu")
	)
	(gr_line
		(start 91.022424 -439.700924)
		(end 91.313 -439.9915)
		(stroke
			(width 0.087376)
			(type default)
		)
		(layer "F.Cu")
	)
	(gr_line
		(start 91.022424 -423.899076)
		(end 91.313 -423.6085)
		(stroke
			(width 0.087376)
			(type default)
		)
		(layer "F.Cu")
	)
	(gr_line
		(start 91.022424 -422.428924)
		(end 91.313 -422.7195)
		(stroke
			(width 0.087376)
			(type default)
		)
		(layer "F.Cu")
	)
	(gr_line
		(start 91.022424 -314.552076)
		(end 91.313 -314.2615)
		(stroke
			(width 0.087376)
			(type default)
		)
		(layer "F.Cu")
	)
	(gr_line
		(start 91.022424 -313.081924)
		(end 91.313 -313.3725)
		(stroke
			(width 0.087376)
			(type default)
		)
		(layer "F.Cu")
	)
	(gr_line
		(start 91.022424 -220.191076)
		(end 91.313 -219.9005)
		(stroke
			(width 0.087376)
			(type default)
		)
		(layer "F.Cu")
	)
	(gr_line
		(start 91.022424 -218.720924)
		(end 91.313 -219.0115)
		(stroke
			(width 0.087376)
			(type default)
		)
		(layer "F.Cu")
	)
	(gr_line
		(start 91.022424 -110.971076)
		(end 91.313 -110.6805)
		(stroke
			(width 0.087376)
			(type default)
		)
		(layer "F.Cu")
	)
	(gr_line
		(start 91.022424 -109.500924)
		(end 91.313 -109.7915)
		(stroke
			(width 0.087376)
			(type default)
		)
		(layer "F.Cu")
	)
	(gr_line
		(start 91.022424 -93.699076)
		(end 91.313 -93.4085)
		(stroke
			(width 0.087376)
			(type default)
		)
		(layer "F.Cu")
	)
	(gr_line
		(start 91.022424 -92.228924)
		(end 91.313 -92.5195)
		(stroke
			(width 0.087376)
			(type default)
		)
		(layer "F.Cu")
	)
	(gr_line
		(start 92.22994 -436.88)
		(end 92.277184 -436.927244)
		(stroke
			(width 0.087376)
			(type default)
		)
		(layer "F.Cu")
	)
	(gr_line
		(start 92.22994 -436.22341)
		(end 92.22994 -436.88)
		(stroke
			(width 0.087376)
			(type default)
		)
		(layer "F.Cu")
	)
	(gr_line
		(start 92.22994 -426.72)
		(end 92.22994 -427.37659)
		(stroke
			(width 0.087376)
			(type default)
		)
		(layer "F.Cu")
	)
	(gr_line
		(start 92.22994 -426.72)
		(end 92.262706 -426.687234)
		(stroke
			(width 0.087376)
			(type default)
		)
		(layer "F.Cu")
	)
	(gr_line
		(start 92.22994 -310.428894)
		(end 92.262706 -310.46166)
		(stroke
			(width 0.087376)
			(type default)
		)
		(layer "F.Cu")
	)
	(gr_line
		(start 92.22994 -309.60441)
		(end 92.22994 -310.428894)
		(stroke
			(width 0.087376)
			(type default)
		)
		(layer "F.Cu")
	)
	(gr_line
		(start 92.22994 -215.9)
		(end 92.277184 -215.947244)
		(stroke
			(width 0.087376)
			(type default)
		)
		(layer "F.Cu")
	)
	(gr_line
		(start 92.22994 -215.24341)
		(end 92.22994 -215.9)
		(stroke
			(width 0.087376)
			(type default)
		)
		(layer "F.Cu")
	)
	(gr_line
		(start 92.22994 -106.709464)
		(end 92.262452 -106.741976)
		(stroke
			(width 0.087376)
			(type default)
		)
		(layer "F.Cu")
	)
	(gr_line
		(start 92.22994 -106.02341)
		(end 92.22994 -106.709464)
		(stroke
			(width 0.087376)
			(type default)
		)
		(layer "F.Cu")
	)
	(gr_line
		(start 92.22994 -96.52)
		(end 92.22994 -97.17659)
		(stroke
			(width 0.087376)
			(type default)
		)
		(layer "F.Cu")
	)
	(gr_line
		(start 92.22994 -96.52)
		(end 92.27693 -96.47301)
		(stroke
			(width 0.087376)
			(type default)
		)
		(layer "F.Cu")
	)
	(gr_line
		(start 92.570554 -216.343992)
		(end 92.63253 -216.282016)
		(stroke
			(width 0.087376)
			(type default)
		)
		(layer "F.Cu")
	)
	(gr_line
		(start 92.57157 -437.322722)
		(end 92.63253 -437.262016)
		(stroke
			(width 0.087376)
			(type default)
		)
		(layer "F.Cu")
	)
	(gr_line
		(start 92.697554 -426.687234)
		(end 92.73032 -426.72)
		(stroke
			(width 0.087376)
			(type default)
		)
		(layer "F.Cu")
	)
	(gr_line
		(start 92.697554 -106.741976)
		(end 92.73032 -106.70921)
		(stroke
			(width 0.087376)
			(type default)
		)
		(layer "F.Cu")
	)
	(gr_line
		(start 92.697808 -310.46166)
		(end 92.73032 -310.429148)
		(stroke
			(width 0.087376)
			(type default)
		)
		(layer "F.Cu")
	)
	(gr_line
		(start 92.712032 -96.47301)
		(end 92.73032 -96.491298)
		(stroke
			(width 0.087376)
			(type default)
		)
		(layer "F.Cu")
	)
	(gr_line
		(start 92.712286 -436.927244)
		(end 92.73032 -436.90921)
		(stroke
			(width 0.087376)
			(type default)
		)
		(layer "F.Cu")
	)
	(gr_line
		(start 92.712286 -215.947244)
		(end 92.73032 -215.92921)
		(stroke
			(width 0.087376)
			(type default)
		)
		(layer "F.Cu")
	)
	(gr_line
		(start 92.73032 -436.22341)
		(end 92.73032 -436.90921)
		(stroke
			(width 0.087376)
			(type default)
		)
		(layer "F.Cu")
	)
	(gr_line
		(start 92.73032 -426.72)
		(end 92.73032 -427.37659)
		(stroke
			(width 0.087376)
			(type default)
		)
		(layer "F.Cu")
	)
	(gr_line
		(start 92.73032 -309.60441)
		(end 92.73032 -310.429148)
		(stroke
			(width 0.087376)
			(type default)
		)
		(layer "F.Cu")
	)
	(gr_line
		(start 92.73032 -215.24341)
		(end 92.73032 -215.92921)
		(stroke
			(width 0.087376)
			(type default)
		)
		(layer "F.Cu")
	)
	(gr_line
		(start 92.73032 -106.02341)
		(end 92.73032 -106.70921)
		(stroke
			(width 0.087376)
			(type default)
		)
		(layer "F.Cu")
	)
	(gr_line
		(start 92.73032 -96.491298)
		(end 92.73032 -97.17659)
		(stroke
			(width 0.087376)
			(type default)
		)
		(layer "F.Cu")
	)
	(gr_line
		(start 93.853 -202.6285)
		(end 94.143576 -202.919076)
		(stroke
			(width 0.087376)
			(type default)
		)
		(layer "F.Cu")
	)
	(gr_line
		(start 93.853 -201.7395)
		(end 94.143576 -201.448924)
		(stroke
			(width 0.087376)
			(type default)
		)
		(layer "F.Cu")
	)
	(gr_line
		(start 94.578424 -202.919076)
		(end 94.869 -202.6285)
		(stroke
			(width 0.087376)
			(type default)
		)
		(layer "F.Cu")
	)
	(gr_line
		(start 94.578424 -201.448924)
		(end 94.869 -201.7395)
		(stroke
			(width 0.087376)
			(type default)
		)
		(layer "F.Cu")
	)
	(gr_line
		(start 94.73057 -310.429656)
		(end 94.762574 -310.46166)
		(stroke
			(width 0.087376)
			(type default)
		)
		(layer "F.Cu")
	)
	(gr_line
		(start 94.73057 -309.60441)
		(end 94.73057 -310.429656)
		(stroke
			(width 0.087376)
			(type default)
		)
		(layer "F.Cu")
	)
	(gr_line
		(start 94.73057 -299.932344)
		(end 94.73057 -300.75759)
		(stroke
			(width 0.087376)
			(type default)
		)
		(layer "F.Cu")
	)
	(gr_line
		(start 94.73057 -299.932344)
		(end 94.762574 -299.90034)
		(stroke
			(width 0.087376)
			(type default)
		)
		(layer "F.Cu")
	)
	(gr_line
		(start 94.73057 -215.929972)
		(end 94.747588 -215.94699)
		(stroke
			(width 0.087376)
			(type default)
		)
		(layer "F.Cu")
	)
	(gr_line
		(start 94.73057 -215.24341)
		(end 94.73057 -215.929972)
		(stroke
			(width 0.087376)
			(type default)
		)
		(layer "F.Cu")
	)
	(gr_line
		(start 94.73057 -205.70952)
		(end 94.73057 -206.39659)
		(stroke
			(width 0.087376)
			(type default)
		)
		(layer "F.Cu")
	)
	(gr_line
		(start 94.73057 -205.70952)
		(end 94.762066 -205.678024)
		(stroke
			(width 0.087376)
			(type default)
		)
		(layer "F.Cu")
	)
	(gr_line
		(start 94.73057 -106.807)
		(end 94.762574 -106.839004)
		(stroke
			(width 0.087376)
			(type default)
		)
		(layer "F.Cu")
	)
	(gr_line
		(start 94.73057 -106.02341)
		(end 94.73057 -106.807)
		(stroke
			(width 0.087376)
			(type default)
		)
		(layer "F.Cu")
	)
	(gr_line
		(start 94.73057 -96.52)
		(end 94.73057 -97.17659)
		(stroke
			(width 0.087376)
			(type default)
		)
		(layer "F.Cu")
	)
	(gr_line
		(start 94.73057 -96.52)
		(end 94.762574 -96.487996)
		(stroke
			(width 0.087376)
			(type default)
		)
		(layer "F.Cu")
	)
	(gr_line
		(start 94.74327 -445.880236)
		(end 94.833694 -445.97066)
		(stroke
			(width 0.085598)
			(type default)
		)
		(layer "F.Cu")
	)
	(gr_line
		(start 95.18269 -215.94699)
		(end 95.22968 -215.9)
		(stroke
			(width 0.087376)
			(type default)
		)
		(layer "F.Cu")
	)
	(gr_line
		(start 95.197168 -205.678024)
		(end 95.22968 -205.710536)
		(stroke
			(width 0.087376)
			(type default)
		)
		(layer "F.Cu")
	)
	(gr_line
		(start 95.197676 -310.46166)
		(end 95.22968 -310.429656)
		(stroke
			(width 0.087376)
			(type default)
		)
		(layer "F.Cu")
	)
	(gr_line
		(start 95.197676 -299.90034)
		(end 95.22968 -299.932344)
		(stroke
			(width 0.087376)
			(type default)
		)
		(layer "F.Cu")
	)
	(gr_line
		(start 95.197676 -106.839004)
		(end 95.22968 -106.807)
		(stroke
			(width 0.087376)
			(type default)
		)
		(layer "F.Cu")
	)
	(gr_line
		(start 95.197676 -96.487996)
		(end 95.22968 -96.52)
		(stroke
			(width 0.087376)
			(type default)
		)
		(layer "F.Cu")
	)
	(gr_line
		(start 95.22968 -309.60441)
		(end 95.22968 -310.429656)
		(stroke
			(width 0.087376)
			(type default)
		)
		(layer "F.Cu")
	)
	(gr_line
		(start 95.22968 -299.932344)
		(end 95.22968 -300.75759)
		(stroke
			(width 0.087376)
			(type default)
		)
		(layer "F.Cu")
	)
	(gr_line
		(start 95.22968 -215.24341)
		(end 95.22968 -215.9)
		(stroke
			(width 0.087376)
			(type default)
		)
		(layer "F.Cu")
	)
	(gr_line
		(start 95.22968 -205.710536)
		(end 95.22968 -206.39659)
		(stroke
			(width 0.087376)
			(type default)
		)
		(layer "F.Cu")
	)
	(gr_line
		(start 95.22968 -106.02341)
		(end 95.22968 -106.807)
		(stroke
			(width 0.087376)
			(type default)
		)
		(layer "F.Cu")
	)
	(gr_line
		(start 95.22968 -96.52)
		(end 95.22968 -97.17659)
		(stroke
			(width 0.087376)
			(type default)
		)
		(layer "F.Cu")
	)
	(gr_line
		(start 95.504 -314.2615)
		(end 95.794576 -314.552076)
		(stroke
			(width 0.087376)
			(type default)
		)
		(layer "F.Cu")
	)
	(gr_line
		(start 95.504 -313.3725)
		(end 95.794576 -313.081924)
		(stroke
			(width 0.087376)
			(type default)
		)
		(layer "F.Cu")
	)
	(gr_line
		(start 95.504 -296.9895)
		(end 95.794576 -297.280076)
		(stroke
			(width 0.087376)
			(type default)
		)
		(layer "F.Cu")
	)
	(gr_line
		(start 95.504 -296.1005)
		(end 95.794576 -295.809924)
		(stroke
			(width 0.087376)
			(type default)
		)
		(layer "F.Cu")
	)
	(gr_line
		(start 95.504 -219.9005)
		(end 95.794576 -220.191076)
		(stroke
			(width 0.087376)
			(type default)
		)
		(layer "F.Cu")
	)
	(gr_line
		(start 95.504 -219.0115)
		(end 95.794576 -218.720924)
		(stroke
			(width 0.087376)
			(type default)
		)
		(layer "F.Cu")
	)
	(gr_line
		(start 95.504 -110.6805)
		(end 95.794576 -110.971076)
		(stroke
			(width 0.087376)
			(type default)
		)
		(layer "F.Cu")
	)
	(gr_line
		(start 95.504 -109.7915)
		(end 95.794576 -109.500924)
		(stroke
			(width 0.087376)
			(type default)
		)
		(layer "F.Cu")
	)
	(gr_line
		(start 95.504 -93.4085)
		(end 95.794576 -93.699076)
		(stroke
			(width 0.087376)
			(type default)
		)
		(layer "F.Cu")
	)
	(gr_line
		(start 95.504 -92.5195)
		(end 95.794576 -92.228924)
		(stroke
			(width 0.087376)
			(type default)
		)
		(layer "F.Cu")
	)
	(gr_line
		(start 95.618808 -445.97066)
		(end 95.709232 -445.880236)
		(stroke
			(width 0.085598)
			(type default)
		)
		(layer "F.Cu")
	)
	(gr_line
		(start 96.229424 -314.552076)
		(end 96.52 -314.2615)
		(stroke
			(width 0.087376)
			(type default)
		)
		(layer "F.Cu")
	)
	(gr_line
		(start 96.229424 -313.081924)
		(end 96.52 -313.3725)
		(stroke
			(width 0.087376)
			(type default)
		)
		(layer "F.Cu")
	)
	(gr_line
		(start 96.229424 -297.280076)
		(end 96.52 -296.9895)
		(stroke
			(width 0.087376)
			(type default)
		)
		(layer "F.Cu")
	)
	(gr_line
		(start 96.229424 -295.809924)
		(end 96.52 -296.1005)
		(stroke
			(width 0.087376)
			(type default)
		)
		(layer "F.Cu")
	)
	(gr_line
		(start 96.229424 -220.191076)
		(end 96.52 -219.9005)
		(stroke
			(width 0.087376)
			(type default)
		)
		(layer "F.Cu")
	)
	(gr_line
		(start 96.229424 -218.720924)
		(end 96.52 -219.0115)
		(stroke
			(width 0.087376)
			(type default)
		)
		(layer "F.Cu")
	)
	(gr_line
		(start 96.229424 -110.971076)
		(end 96.52 -110.6805)
		(stroke
			(width 0.087376)
			(type default)
		)
		(layer "F.Cu")
	)
	(gr_line
		(start 96.229424 -109.500924)
		(end 96.52 -109.7915)
		(stroke
			(width 0.087376)
			(type default)
		)
		(layer "F.Cu")
	)
	(gr_line
		(start 96.229424 -93.699076)
		(end 96.52 -93.4085)
		(stroke
			(width 0.087376)
			(type default)
		)
		(layer "F.Cu")
	)
	(gr_line
		(start 96.229424 -92.228924)
		(end 96.52 -92.5195)
		(stroke
			(width 0.087376)
			(type default)
		)
		(layer "F.Cu")
	)
	(gr_line
		(start 96.72955 -310.429148)
		(end 96.762062 -310.46166)
		(stroke
			(width 0.087376)
			(type default)
		)
		(layer "F.Cu")
	)
	(gr_line
		(start 96.72955 -309.60441)
		(end 96.72955 -310.429148)
		(stroke
			(width 0.087376)
			(type default)
		)
		(layer "F.Cu")
	)
	(gr_line
		(start 96.72955 -299.932852)
		(end 96.72955 -300.75759)
		(stroke
			(width 0.087376)
			(type default)
		)
		(layer "F.Cu")
	)
	(gr_line
		(start 96.72955 -299.932852)
		(end 96.762062 -299.90034)
		(stroke
			(width 0.087376)
			(type default)
		)
		(layer "F.Cu")
	)
	(gr_line
		(start 96.72955 -215.929464)
		(end 96.814132 -216.014046)
		(stroke
			(width 0.087376)
			(type default)
		)
		(layer "F.Cu")
	)
	(gr_line
		(start 96.72955 -215.24341)
		(end 96.72955 -215.929464)
		(stroke
			(width 0.087376)
			(type default)
		)
		(layer "F.Cu")
	)
	(gr_line
		(start 96.72955 -205.74)
		(end 96.72955 -206.39659)
		(stroke
			(width 0.087376)
			(type default)
		)
		(layer "F.Cu")
	)
	(gr_line
		(start 96.72955 -205.74)
		(end 96.762316 -205.707234)
		(stroke
			(width 0.087376)
			(type default)
		)
		(layer "F.Cu")
	)
	(gr_line
		(start 96.72955 -106.709464)
		(end 96.814132 -106.794046)
		(stroke
			(width 0.087376)
			(type default)
		)
		(layer "F.Cu")
	)
	(gr_line
		(start 96.72955 -106.02341)
		(end 96.72955 -106.709464)
		(stroke
			(width 0.087376)
			(type default)
		)
		(layer "F.Cu")
	)
	(gr_line
		(start 96.72955 -96.352106)
		(end 96.72955 -97.17659)
		(stroke
			(width 0.087376)
			(type default)
		)
		(layer "F.Cu")
	)
	(gr_line
		(start 96.72955 -96.352106)
		(end 96.762316 -96.31934)
		(stroke
			(width 0.087376)
			(type default)
		)
		(layer "F.Cu")
	)
	(gr_line
		(start 96.82734 -95.832168)
		(end 96.889316 -95.770192)
		(stroke
			(width 0.087376)
			(type default)
		)
		(layer "F.Cu")
	)
	(gr_line
		(start 97.182432 -215.947498)
		(end 97.22993 -215.9)
		(stroke
			(width 0.087376)
			(type default)
		)
		(layer "F.Cu")
	)
	(gr_line
		(start 97.182432 -106.727498)
		(end 97.22993 -106.68)
		(stroke
			(width 0.087376)
			(type default)
		)
		(layer "F.Cu")
	)
	(gr_line
		(start 97.197164 -310.46166)
		(end 97.22993 -310.428894)
		(stroke
			(width 0.087376)
			(type default)
		)
		(layer "F.Cu")
	)
	(gr_line
		(start 97.197164 -299.90034)
		(end 97.22993 -299.933106)
		(stroke
			(width 0.087376)
			(type default)
		)
		(layer "F.Cu")
	)
	(gr_line
		(start 97.197164 -205.707234)
		(end 97.22993 -205.74)
		(stroke
			(width 0.087376)
			(type default)
		)
		(layer "F.Cu")
	)
	(gr_line
		(start 97.197418 -96.31934)
		(end 97.22993 -96.351852)
		(stroke
			(width 0.087376)
			(type default)
		)
		(layer "F.Cu")
	)
	(gr_line
		(start 97.22993 -309.60441)
		(end 97.22993 -310.428894)
		(stroke
			(width 0.087376)
			(type default)
		)
		(layer "F.Cu")
	)
	(gr_line
		(start 97.22993 -299.933106)
		(end 97.22993 -300.75759)
		(stroke
			(width 0.087376)
			(type default)
		)
		(layer "F.Cu")
	)
	(gr_line
		(start 97.22993 -215.24341)
		(end 97.22993 -215.9)
		(stroke
			(width 0.087376)
			(type default)
		)
		(layer "F.Cu")
	)
	(gr_line
		(start 97.22993 -205.74)
		(end 97.22993 -206.39659)
		(stroke
			(width 0.087376)
			(type default)
		)
		(layer "F.Cu")
	)
	(gr_line
		(start 97.22993 -106.02341)
		(end 97.22993 -106.68)
		(stroke
			(width 0.087376)
			(type default)
		)
		(layer "F.Cu")
	)
	(gr_line
		(start 97.22993 -96.351852)
		(end 97.22993 -97.17659)
		(stroke
			(width 0.087376)
			(type default)
		)
		(layer "F.Cu")
	)
	(gr_line
		(start 97.663 -202.6285)
		(end 97.953576 -202.919076)
		(stroke
			(width 0.087376)
			(type default)
		)
		(layer "F.Cu")
	)
	(gr_line
		(start 97.663 -201.7395)
		(end 97.953576 -201.448924)
		(stroke
			(width 0.087376)
			(type default)
		)
		(layer "F.Cu")
	)
	(gr_line
		(start 98.388424 -202.919076)
		(end 98.679 -202.6285)
		(stroke
			(width 0.087376)
			(type default)
		)
		(layer "F.Cu")
	)
	(gr_line
		(start 98.388424 -201.448924)
		(end 98.679 -201.7395)
		(stroke
			(width 0.087376)
			(type default)
		)
		(layer "F.Cu")
	)
	(gr_line
		(start 98.40341 -435.04993)
		(end 99.228148 -435.04993)
		(stroke
			(width 0.087376)
			(type default)
		)
		(layer "F.Cu")
	)
	(gr_line
		(start 98.40341 -434.54955)
		(end 99.227894 -434.54955)
		(stroke
			(width 0.087376)
			(type default)
		)
		(layer "F.Cu")
	)
	(gr_line
		(start 98.40341 -433.04968)
		(end 99.187 -433.04968)
		(stroke
			(width 0.087376)
			(type default)
		)
		(layer "F.Cu")
	)
	(gr_line
		(start 98.40341 -432.55057)
		(end 99.187 -432.55057)
		(stroke
			(width 0.087376)
			(type default)
		)
		(layer "F.Cu")
	)
	(gr_line
		(start 98.40341 -308.43093)
		(end 99.228148 -308.43093)
		(stroke
			(width 0.087376)
			(type default)
		)
		(layer "F.Cu")
	)
	(gr_line
		(start 98.40341 -307.93055)
		(end 99.227894 -307.93055)
		(stroke
			(width 0.087376)
			(type default)
		)
		(layer "F.Cu")
	)
	(gr_line
		(start 98.40341 -306.43068)
		(end 99.228656 -306.43068)
		(stroke
			(width 0.087376)
			(type default)
		)
		(layer "F.Cu")
	)
	(gr_line
		(start 98.40341 -305.93157)
		(end 99.228656 -305.93157)
		(stroke
			(width 0.087376)
			(type default)
		)
		(layer "F.Cu")
	)
	(gr_line
		(start 98.40341 -210.06943)
		(end 99.06 -210.06943)
		(stroke
			(width 0.087376)
			(type default)
		)
		(layer "F.Cu")
	)
	(gr_line
		(start 98.40341 -209.57032)
		(end 99.06 -209.57032)
		(stroke
			(width 0.087376)
			(type default)
		)
		(layer "F.Cu")
	)
	(gr_line
		(start 98.40341 -208.07045)
		(end 99.06 -208.07045)
		(stroke
			(width 0.087376)
			(type default)
		)
		(layer "F.Cu")
	)
	(gr_line
		(start 98.40341 -207.57007)
		(end 99.06 -207.57007)
		(stroke
			(width 0.087376)
			(type default)
		)
		(layer "F.Cu")
	)
	(gr_line
		(start 99.06 -210.06943)
		(end 99.092004 -210.037426)
		(stroke
			(width 0.087376)
			(type default)
		)
		(layer "F.Cu")
	)
	(gr_line
		(start 99.06 -209.57032)
		(end 99.092004 -209.602324)
		(stroke
			(width 0.087376)
			(type default)
		)
		(layer "F.Cu")
	)
	(gr_line
		(start 99.06 -208.07045)
		(end 99.092766 -208.037684)
		(stroke
			(width 0.087376)
			(type default)
		)
		(layer "F.Cu")
	)
	(gr_line
		(start 99.06 -207.57007)
		(end 99.092766 -207.602836)
		(stroke
			(width 0.087376)
			(type default)
		)
		(layer "F.Cu")
	)
	(gr_line
		(start 99.187 -433.04968)
		(end 99.219004 -433.017676)
		(stroke
			(width 0.087376)
			(type default)
		)
		(layer "F.Cu")
	)
	(gr_line
		(start 99.187 -432.55057)
		(end 99.219004 -432.582574)
		(stroke
			(width 0.087376)
			(type default)
		)
		(layer "F.Cu")
	)
	(gr_line
		(start 99.227894 -434.54955)
		(end 99.26066 -434.582316)
		(stroke
			(width 0.087376)
			(type default)
		)
		(layer "F.Cu")
	)
	(gr_line
		(start 99.227894 -307.93055)
		(end 99.319588 -308.022244)
		(stroke
			(width 0.087376)
			(type default)
		)
		(layer "F.Cu")
	)
	(gr_line
		(start 99.228148 -435.04993)
		(end 99.26066 -435.017418)
		(stroke
			(width 0.087376)
			(type default)
		)
		(layer "F.Cu")
	)
	(gr_line
		(start 99.228148 -308.43093)
		(end 99.26066 -308.398418)
		(stroke
			(width 0.087376)
			(type default)
		)
		(layer "F.Cu")
	)
	(gr_line
		(start 99.228656 -306.43068)
		(end 99.26066 -306.398676)
		(stroke
			(width 0.087376)
			(type default)
		)
		(layer "F.Cu")
	)
	(gr_line
		(start 99.228656 -305.93157)
		(end 99.26066 -305.963574)
		(stroke
			(width 0.087376)
			(type default)
		)
		(layer "F.Cu")
	)
	(gr_line
		(start 99.314 -314.2615)
		(end 99.604576 -314.552076)
		(stroke
			(width 0.087376)
			(type default)
		)
		(layer "F.Cu")
	)
	(gr_line
		(start 99.314 -313.3725)
		(end 99.604576 -313.081924)
		(stroke
			(width 0.087376)
			(type default)
		)
		(layer "F.Cu")
	)
	(gr_line
		(start 99.314 -296.9895)
		(end 99.604576 -297.280076)
		(stroke
			(width 0.087376)
			(type default)
		)
		(layer "F.Cu")
	)
	(gr_line
		(start 99.314 -296.1005)
		(end 99.604576 -295.809924)
		(stroke
			(width 0.087376)
			(type default)
		)
		(layer "F.Cu")
	)
	(gr_line
		(start 99.314 -219.9005)
		(end 99.604576 -220.191076)
		(stroke
			(width 0.087376)
			(type default)
		)
		(layer "F.Cu")
	)
	(gr_line
		(start 99.314 -219.0115)
		(end 99.604576 -218.720924)
		(stroke
			(width 0.087376)
			(type default)
		)
		(layer "F.Cu")
	)
	(gr_line
		(start 99.314 -110.6805)
		(end 99.604576 -110.971076)
		(stroke
			(width 0.087376)
			(type default)
		)
		(layer "F.Cu")
	)
	(gr_line
		(start 99.314 -109.7915)
		(end 99.604576 -109.500924)
		(stroke
			(width 0.087376)
			(type default)
		)
		(layer "F.Cu")
	)
	(gr_line
		(start 99.314 -93.4085)
		(end 99.604576 -93.699076)
		(stroke
			(width 0.087376)
			(type default)
		)
		(layer "F.Cu")
	)
	(gr_line
		(start 99.314 -92.5195)
		(end 99.604576 -92.228924)
		(stroke
			(width 0.087376)
			(type default)
		)
		(layer "F.Cu")
	)
	(gr_line
		(start 100.039424 -314.552076)
		(end 100.33 -314.2615)
		(stroke
			(width 0.087376)
			(type default)
		)
		(layer "F.Cu")
	)
	(gr_line
		(start 100.039424 -313.081924)
		(end 100.33 -313.3725)
		(stroke
			(width 0.087376)
			(type default)
		)
		(layer "F.Cu")
	)
	(gr_line
		(start 100.039424 -297.280076)
		(end 100.33 -296.9895)
		(stroke
			(width 0.087376)
			(type default)
		)
		(layer "F.Cu")
	)
	(gr_line
		(start 100.039424 -295.809924)
		(end 100.33 -296.1005)
		(stroke
			(width 0.087376)
			(type default)
		)
		(layer "F.Cu")
	)
	(gr_line
		(start 100.039424 -220.191076)
		(end 100.33 -219.9005)
		(stroke
			(width 0.087376)
			(type default)
		)
		(layer "F.Cu")
	)
	(gr_line
		(start 100.039424 -218.720924)
		(end 100.33 -219.0115)
		(stroke
			(width 0.087376)
			(type default)
		)
		(layer "F.Cu")
	)
	(gr_line
		(start 100.039424 -110.971076)
		(end 100.33 -110.6805)
		(stroke
			(width 0.087376)
			(type default)
		)
		(layer "F.Cu")
	)
	(gr_line
		(start 100.039424 -109.500924)
		(end 100.33 -109.7915)
		(stroke
			(width 0.087376)
			(type default)
		)
		(layer "F.Cu")
	)
	(gr_line
		(start 100.039424 -93.699076)
		(end 100.33 -93.4085)
		(stroke
			(width 0.087376)
			(type default)
		)
		(layer "F.Cu")
	)
	(gr_line
		(start 100.039424 -92.228924)
		(end 100.33 -92.5195)
		(stroke
			(width 0.087376)
			(type default)
		)
		(layer "F.Cu")
	)
	(gr_line
		(start 101.880924 -437.859424)
		(end 102.1715 -438.15)
		(stroke
			(width 0.087376)
			(type default)
		)
		(layer "F.Cu")
	)
	(gr_line
		(start 101.880924 -437.424576)
		(end 102.1715 -437.134)
		(stroke
			(width 0.087376)
			(type default)
		)
		(layer "F.Cu")
	)
	(gr_line
		(start 101.880924 -434.049424)
		(end 102.1715 -434.34)
		(stroke
			(width 0.087376)
			(type default)
		)
		(layer "F.Cu")
	)
	(gr_line
		(start 101.880924 -433.614576)
		(end 102.1715 -433.324)
		(stroke
			(width 0.087376)
			(type default)
		)
		(layer "F.Cu")
	)
	(gr_line
		(start 101.880924 -311.240424)
		(end 102.1715 -311.531)
		(stroke
			(width 0.087376)
			(type default)
		)
		(layer "F.Cu")
	)
	(gr_line
		(start 101.880924 -310.805576)
		(end 102.1715 -310.515)
		(stroke
			(width 0.087376)
			(type default)
		)
		(layer "F.Cu")
	)
	(gr_line
		(start 101.880924 -307.430424)
		(end 102.1715 -307.721)
		(stroke
			(width 0.087376)
			(type default)
		)
		(layer "F.Cu")
	)
	(gr_line
		(start 101.880924 -306.995576)
		(end 102.1715 -306.705)
		(stroke
			(width 0.087376)
			(type default)
		)
		(layer "F.Cu")
	)
	(gr_line
		(start 101.880924 -209.005424)
		(end 102.1715 -209.296)
		(stroke
			(width 0.087376)
			(type default)
		)
		(layer "F.Cu")
	)
	(gr_line
		(start 101.880924 -208.570576)
		(end 102.1715 -208.28)
		(stroke
			(width 0.087376)
			(type default)
		)
		(layer "F.Cu")
	)
	(gr_line
		(start 101.880924 -205.195424)
		(end 102.1715 -205.486)
		(stroke
			(width 0.087376)
			(type default)
		)
		(layer "F.Cu")
	)
	(gr_line
		(start 101.880924 -204.760576)
		(end 102.1715 -204.47)
		(stroke
			(width 0.087376)
			(type default)
		)
		(layer "F.Cu")
	)
	(gr_line
		(start 103.0605 -438.15)
		(end 103.351076 -437.859424)
		(stroke
			(width 0.087376)
			(type default)
		)
		(layer "F.Cu")
	)
	(gr_line
		(start 103.0605 -437.134)
		(end 103.351076 -437.424576)
		(stroke
			(width 0.087376)
			(type default)
		)
		(layer "F.Cu")
	)
	(gr_line
		(start 103.0605 -434.34)
		(end 103.351076 -434.049424)
		(stroke
			(width 0.087376)
			(type default)
		)
		(layer "F.Cu")
	)
	(gr_line
		(start 103.0605 -433.324)
		(end 103.351076 -433.614576)
		(stroke
			(width 0.087376)
			(type default)
		)
		(layer "F.Cu")
	)
	(gr_line
		(start 103.0605 -311.531)
		(end 103.351076 -311.240424)
		(stroke
			(width 0.087376)
			(type default)
		)
		(layer "F.Cu")
	)
	(gr_line
		(start 103.0605 -310.515)
		(end 103.351076 -310.805576)
		(stroke
			(width 0.087376)
			(type default)
		)
		(layer "F.Cu")
	)
	(gr_line
		(start 103.0605 -307.721)
		(end 103.351076 -307.430424)
		(stroke
			(width 0.087376)
			(type default)
		)
		(layer "F.Cu")
	)
	(gr_line
		(start 103.0605 -306.705)
		(end 103.351076 -306.995576)
		(stroke
			(width 0.087376)
			(type default)
		)
		(layer "F.Cu")
	)
	(gr_line
		(start 103.0605 -209.296)
		(end 103.351076 -209.005424)
		(stroke
			(width 0.087376)
			(type default)
		)
		(layer "F.Cu")
	)
	(gr_line
		(start 103.0605 -208.28)
		(end 103.351076 -208.570576)
		(stroke
			(width 0.087376)
			(type default)
		)
		(layer "F.Cu")
	)
	(gr_line
		(start 103.0605 -205.486)
		(end 103.351076 -205.195424)
		(stroke
			(width 0.087376)
			(type default)
		)
		(layer "F.Cu")
	)
	(gr_line
		(start 103.0605 -204.47)
		(end 103.351076 -204.760576)
		(stroke
			(width 0.087376)
			(type default)
		)
		(layer "F.Cu")
	)
	(gr_line
		(start 104.775 -289.1155)
		(end 105.33507 -288.55543)
		(stroke
			(width 0.085598)
			(type default)
		)
		(layer "F.Cu")
	)
	(gr_line
		(start 104.775 -287.2105)
		(end 105.33507 -287.77057)
		(stroke
			(width 0.085598)
			(type default)
		)
		(layer "F.Cu")
	)
	(gr_line
		(start 109.513624 -423.926)
		(end 110.018576 -423.926)
		(stroke
			(width 0.085598)
			(type default)
		)
		(layer "F.Cu")
	)
	(gr_line
		(start 110.018576 -423.926)
		(end 110.073694 -423.870882)
		(stroke
			(width 0.085598)
			(type default)
		)
		(layer "F.Cu")
	)
	(gr_line
		(start 110.858808 -423.870882)
		(end 110.913926 -423.926)
		(stroke
			(width 0.085598)
			(type default)
		)
		(layer "F.Cu")
	)
	(gr_line
		(start 110.913926 -423.926)
		(end 111.418624 -423.926)
		(stroke
			(width 0.085598)
			(type default)
		)
		(layer "F.Cu")
	)
	(gr_line
		(start 114.466624 -442.722)
		(end 114.841274 -442.722)
		(stroke
			(width 0.085598)
			(type default)
		)
		(layer "F.Cu")
	)
	(gr_line
		(start 114.841274 -442.722)
		(end 114.898932 -442.779658)
		(stroke
			(width 0.085598)
			(type default)
		)
		(layer "F.Cu")
	)
	(gr_line
		(start 115.683792 -442.779658)
		(end 115.74145 -442.722)
		(stroke
			(width 0.085598)
			(type default)
		)
		(layer "F.Cu")
	)
	(gr_line
		(start 115.74145 -442.722)
		(end 116.371624 -442.722)
		(stroke
			(width 0.085598)
			(type default)
		)
		(layer "F.Cu")
	)
	(gr_line
		(start 130.214624 -158.369)
		(end 130.719576 -158.369)
		(stroke
			(width 0.085598)
			(type default)
		)
		(layer "F.Cu")
	)
	(gr_line
		(start 130.719576 -158.369)
		(end 130.774694 -158.313882)
		(stroke
			(width 0.085598)
			(type default)
		)
		(layer "F.Cu")
	)
	(gr_line
		(start 131.559808 -158.313882)
		(end 131.614926 -158.369)
		(stroke
			(width 0.085598)
			(type default)
		)
		(layer "F.Cu")
	)
	(gr_line
		(start 131.614926 -158.369)
		(end 132.119624 -158.369)
		(stroke
			(width 0.085598)
			(type default)
		)
		(layer "F.Cu")
	)
	(gr_line
		(start 140.97 -134.583424)
		(end 140.97 -135.088376)
		(stroke
			(width 0.085598)
			(type default)
		)
		(layer "F.Cu")
	)
	(gr_line
		(start 140.97 -134.583424)
		(end 141.025118 -134.528306)
		(stroke
			(width 0.085598)
			(type default)
		)
		(layer "F.Cu")
	)
	(gr_line
		(start 140.97 -133.688074)
		(end 141.025118 -133.743192)
		(stroke
			(width 0.085598)
			(type default)
		)
		(layer "F.Cu")
	)
	(gr_line
		(start 140.97 -133.183376)
		(end 140.97 -133.688074)
		(stroke
			(width 0.085598)
			(type default)
		)
		(layer "F.Cu")
	)
	(gr_line
		(start 189.765686 -445.47028)
		(end 190.136526 -445.84112)
		(stroke
			(width 0.087376)
			(type default)
		)
		(layer "F.Cu")
	)
	(gr_line
		(start 189.765686 -445.293242)
		(end 189.765686 -445.47028)
		(stroke
			(width 0.087376)
			(type default)
		)
		(layer "F.Cu")
	)
	(gr_line
		(start 190.136526 -445.84112)
		(end 190.313564 -445.84112)
		(stroke
			(width 0.087376)
			(type default)
		)
		(layer "F.Cu")
	)
	(gr_line
		(start 190.19901 -445.291464)
		(end 190.315342 -445.407796)
		(stroke
			(width 0.087376)
			(type default)
		)
		(layer "F.Cu")
	)
	(gr_line
		(start 190.687706 -446.392554)
		(end 191.058546 -446.76314)
		(stroke
			(width 0.087376)
			(type default)
		)
		(layer "F.Cu")
	)
	(gr_line
		(start 190.687706 -446.215262)
		(end 190.687706 -446.392554)
		(stroke
			(width 0.087376)
			(type default)
		)
		(layer "F.Cu")
	)
	(gr_line
		(start 191.058546 -446.76314)
		(end 191.235584 -446.76314)
		(stroke
			(width 0.087376)
			(type default)
		)
		(layer "F.Cu")
	)
	(gr_line
		(start 191.12103 -446.213484)
		(end 191.237362 -446.329816)
		(stroke
			(width 0.087376)
			(type default)
		)
		(layer "F.Cu")
	)
	(gr_line
		(start 191.60998 -447.314574)
		(end 191.980566 -447.685414)
		(stroke
			(width 0.087376)
			(type default)
		)
		(layer "F.Cu")
	)
	(gr_line
		(start 191.60998 -447.137536)
		(end 191.60998 -447.314574)
		(stroke
			(width 0.087376)
			(type default)
		)
		(layer "F.Cu")
	)
	(gr_line
		(start 191.980566 -447.685414)
		(end 192.157858 -447.685414)
		(stroke
			(width 0.087376)
			(type default)
		)
		(layer "F.Cu")
	)
	(gr_line
		(start 192.043304 -447.135758)
		(end 192.159636 -447.25209)
		(stroke
			(width 0.087376)
			(type default)
		)
		(layer "F.Cu")
	)
	(gr_line
		(start 201.255122 -50.140108)
		(end 201.345546 -50.049684)
		(stroke
			(width 0.085598)
			(type default)
		)
		(layer "F.Cu")
	)
	(gr_line
		(start 201.255122 -49.174146)
		(end 201.345546 -49.26457)
		(stroke
			(width 0.085598)
			(type default)
		)
		(layer "F.Cu")
	)
	(gr_line
		(start 202.76693 -460.00543)
		(end 203.0095 -460.248)
		(stroke
			(width 0.085598)
			(type default)
		)
		(layer "F.Cu")
	)
	(gr_line
		(start 202.76693 -459.22057)
		(end 203.0095 -458.978)
		(stroke
			(width 0.085598)
			(type default)
		)
		(layer "F.Cu")
	)
	(gr_line
		(start 202.76693 -50.04943)
		(end 203.0095 -50.292)
		(stroke
			(width 0.085598)
			(type default)
		)
		(layer "F.Cu")
	)
	(gr_line
		(start 202.76693 -49.26457)
		(end 203.0095 -49.022)
		(stroke
			(width 0.085598)
			(type default)
		)
		(layer "F.Cu")
	)
	(gr_line
		(start 203.8985 -460.248)
		(end 204.14107 -460.00543)
		(stroke
			(width 0.085598)
			(type default)
		)
		(layer "F.Cu")
	)
	(gr_line
		(start 203.8985 -458.978)
		(end 204.14107 -459.22057)
		(stroke
			(width 0.085598)
			(type default)
		)
		(layer "F.Cu")
	)
	(gr_line
		(start 203.8985 -50.292)
		(end 204.14107 -50.04943)
		(stroke
			(width 0.085598)
			(type default)
		)
		(layer "F.Cu")
	)
	(gr_line
		(start 203.8985 -49.022)
		(end 204.14107 -49.26457)
		(stroke
			(width 0.085598)
			(type default)
		)
		(layer "F.Cu")
	)
	(gr_line
		(start 204.439012 -356.23754)
		(end 204.564234 -356.362762)
		(stroke
			(width 0.087376)
			(type default)
		)
		(layer "F.Cu")
	)
	(gr_line
		(start 204.564234 -356.362762)
		(end 205.08849 -356.362762)
		(stroke
			(width 0.087376)
			(type default)
		)
		(layer "F.Cu")
	)
	(gr_line
		(start 204.744066 -355.929946)
		(end 204.908658 -355.929946)
		(stroke
			(width 0.087376)
			(type default)
		)
		(layer "F.Cu")
	)
	(gr_line
		(start 205.08849 -356.362762)
		(end 205.213712 -356.23754)
		(stroke
			(width 0.087376)
			(type default)
		)
		(layer "F.Cu")
	)
	(gr_line
		(start 205.24343 -460.00543)
		(end 205.867 -460.629)
		(stroke
			(width 0.085598)
			(type default)
		)
		(layer "F.Cu")
	)
	(gr_line
		(start 205.24343 -459.22057)
		(end 205.867 -458.597)
		(stroke
			(width 0.085598)
			(type default)
		)
		(layer "F.Cu")
	)
	(gr_line
		(start 205.24343 -50.04943)
		(end 205.867 -50.673)
		(stroke
			(width 0.085598)
			(type default)
		)
		(layer "F.Cu")
	)
	(gr_line
		(start 205.24343 -49.26457)
		(end 205.867 -48.641)
		(stroke
			(width 0.085598)
			(type default)
		)
		(layer "F.Cu")
	)
	(gr_line
		(start 205.743048 -356.23754)
		(end 205.86827 -356.362762)
		(stroke
			(width 0.087376)
			(type default)
		)
		(layer "F.Cu")
	)
	(gr_line
		(start 205.867 -460.629)
		(end 206.49057 -460.00543)
		(stroke
			(width 0.085598)
			(type default)
		)
		(layer "F.Cu")
	)
	(gr_line
		(start 205.867 -458.597)
		(end 206.49057 -459.22057)
		(stroke
			(width 0.085598)
			(type default)
		)
		(layer "F.Cu")
	)
	(gr_line
		(start 205.867 -50.673)
		(end 206.49057 -50.04943)
		(stroke
			(width 0.085598)
			(type default)
		)
		(layer "F.Cu")
	)
	(gr_line
		(start 205.867 -48.641)
		(end 206.49057 -49.26457)
		(stroke
			(width 0.085598)
			(type default)
		)
		(layer "F.Cu")
	)
	(gr_line
		(start 205.86827 -356.362762)
		(end 206.392526 -356.362762)
		(stroke
			(width 0.087376)
			(type default)
		)
		(layer "F.Cu")
	)
	(gr_line
		(start 206.048102 -355.929946)
		(end 206.212694 -355.929946)
		(stroke
			(width 0.087376)
			(type default)
		)
		(layer "F.Cu")
	)
	(gr_line
		(start 206.392526 -356.362762)
		(end 206.517748 -356.23754)
		(stroke
			(width 0.087376)
			(type default)
		)
		(layer "F.Cu")
	)
	(gr_line
		(start 206.481426 -254.713994)
		(end 206.606648 -254.839216)
		(stroke
			(width 0.087376)
			(type default)
		)
		(layer "F.Cu")
	)
	(gr_line
		(start 206.606648 -254.839216)
		(end 207.130904 -254.839216)
		(stroke
			(width 0.087376)
			(type default)
		)
		(layer "F.Cu")
	)
	(gr_line
		(start 206.78648 -254.4064)
		(end 206.951072 -254.4064)
		(stroke
			(width 0.087376)
			(type default)
		)
		(layer "F.Cu")
	)
	(gr_line
		(start 207.130904 -254.839216)
		(end 207.256126 -254.713994)
		(stroke
			(width 0.087376)
			(type default)
		)
		(layer "F.Cu")
	)
	(gr_line
		(start 207.397858 -459.325218)
		(end 208.4451 -459.325218)
		(stroke
			(width 0.085598)
			(type default)
		)
		(layer "F.Cu")
	)
	(gr_line
		(start 207.397858 -49.325022)
		(end 208.4451 -49.325022)
		(stroke
			(width 0.085598)
			(type default)
		)
		(layer "F.Cu")
	)
	(gr_line
		(start 207.398112 -459.975458)
		(end 208.4451 -459.975458)
		(stroke
			(width 0.085598)
			(type default)
		)
		(layer "F.Cu")
	)
	(gr_line
		(start 207.398112 -49.975262)
		(end 208.4451 -49.975262)
		(stroke
			(width 0.085598)
			(type default)
		)
		(layer "F.Cu")
	)
	(gr_line
		(start 207.785462 -254.713994)
		(end 207.910684 -254.839216)
		(stroke
			(width 0.087376)
			(type default)
		)
		(layer "F.Cu")
	)
	(gr_line
		(start 207.910684 -254.839216)
		(end 208.43494 -254.839216)
		(stroke
			(width 0.087376)
			(type default)
		)
		(layer "F.Cu")
	)
	(gr_line
		(start 208.090516 -254.4064)
		(end 208.255108 -254.4064)
		(stroke
			(width 0.087376)
			(type default)
		)
		(layer "F.Cu")
	)
	(gr_line
		(start 208.43494 -254.839216)
		(end 208.560162 -254.713994)
		(stroke
			(width 0.087376)
			(type default)
		)
		(layer "F.Cu")
	)
	(gr_line
		(start 209.062828 -356.23754)
		(end 209.18805 -356.362762)
		(stroke
			(width 0.087376)
			(type default)
		)
		(layer "F.Cu")
	)
	(gr_line
		(start 209.089498 -254.713994)
		(end 209.21472 -254.839216)
		(stroke
			(width 0.087376)
			(type default)
		)
		(layer "F.Cu")
	)
	(gr_line
		(start 209.18805 -356.362762)
		(end 209.712306 -356.362762)
		(stroke
			(width 0.087376)
			(type default)
		)
		(layer "F.Cu")
	)
	(gr_line
		(start 209.21472 -254.839216)
		(end 209.738976 -254.839216)
		(stroke
			(width 0.087376)
			(type default)
		)
		(layer "F.Cu")
	)
	(gr_line
		(start 209.367882 -355.929946)
		(end 209.532474 -355.929946)
		(stroke
			(width 0.087376)
			(type default)
		)
		(layer "F.Cu")
	)
	(gr_line
		(start 209.394552 -254.4064)
		(end 209.559144 -254.4064)
		(stroke
			(width 0.087376)
			(type default)
		)
		(layer "F.Cu")
	)
	(gr_line
		(start 209.712306 -356.362762)
		(end 209.837528 -356.23754)
		(stroke
			(width 0.087376)
			(type default)
		)
		(layer "F.Cu")
	)
	(gr_line
		(start 209.738976 -254.839216)
		(end 209.864198 -254.713994)
		(stroke
			(width 0.087376)
			(type default)
		)
		(layer "F.Cu")
	)
	(gr_line
		(start 210.366864 -356.23754)
		(end 210.492086 -356.362762)
		(stroke
			(width 0.087376)
			(type default)
		)
		(layer "F.Cu")
	)
	(gr_line
		(start 210.492086 -356.362762)
		(end 211.016342 -356.362762)
		(stroke
			(width 0.087376)
			(type default)
		)
		(layer "F.Cu")
	)
	(gr_line
		(start 210.614514 -60.530486)
		(end 210.730592 -60.414408)
		(stroke
			(width 0.087376)
			(type default)
		)
		(layer "F.Cu")
	)
	(gr_line
		(start 210.616292 -60.96381)
		(end 210.79333 -60.96381)
		(stroke
			(width 0.087376)
			(type default)
		)
		(layer "F.Cu")
	)
	(gr_line
		(start 210.671918 -355.929946)
		(end 210.83651 -355.929946)
		(stroke
			(width 0.087376)
			(type default)
		)
		(layer "F.Cu")
	)
	(gr_line
		(start 210.79333 -60.96381)
		(end 211.163916 -60.593224)
		(stroke
			(width 0.087376)
			(type default)
		)
		(layer "F.Cu")
	)
	(gr_line
		(start 211.016342 -356.362762)
		(end 211.141564 -356.23754)
		(stroke
			(width 0.087376)
			(type default)
		)
		(layer "F.Cu")
	)
	(gr_line
		(start 211.163916 -60.416186)
		(end 211.163916 -60.593224)
		(stroke
			(width 0.087376)
			(type default)
		)
		(layer "F.Cu")
	)
	(gr_line
		(start 211.536534 -59.608466)
		(end 211.652866 -59.492134)
		(stroke
			(width 0.087376)
			(type default)
		)
		(layer "F.Cu")
	)
	(gr_line
		(start 211.538312 -60.04179)
		(end 211.71535 -60.04179)
		(stroke
			(width 0.087376)
			(type default)
		)
		(layer "F.Cu")
	)
	(gr_line
		(start 211.6709 -356.23754)
		(end 211.796122 -356.362762)
		(stroke
			(width 0.087376)
			(type default)
		)
		(layer "F.Cu")
	)
	(gr_line
		(start 211.71535 -60.04179)
		(end 212.08619 -59.671204)
		(stroke
			(width 0.087376)
			(type default)
		)
		(layer "F.Cu")
	)
	(gr_line
		(start 211.796122 -356.362762)
		(end 212.320378 -356.362762)
		(stroke
			(width 0.087376)
			(type default)
		)
		(layer "F.Cu")
	)
	(gr_line
		(start 211.975954 -355.929946)
		(end 212.140546 -355.929946)
		(stroke
			(width 0.087376)
			(type default)
		)
		(layer "F.Cu")
	)
	(gr_line
		(start 211.989162 -254.713994)
		(end 212.114384 -254.839216)
		(stroke
			(width 0.087376)
			(type default)
		)
		(layer "F.Cu")
	)
	(gr_line
		(start 212.08619 -59.493912)
		(end 212.08619 -59.671204)
		(stroke
			(width 0.087376)
			(type default)
		)
		(layer "F.Cu")
	)
	(gr_line
		(start 212.114384 -254.839216)
		(end 212.63864 -254.839216)
		(stroke
			(width 0.087376)
			(type default)
		)
		(layer "F.Cu")
	)
	(gr_line
		(start 212.294216 -254.4064)
		(end 212.458808 -254.4064)
		(stroke
			(width 0.087376)
			(type default)
		)
		(layer "F.Cu")
	)
	(gr_line
		(start 212.320378 -356.362762)
		(end 212.4456 -356.23754)
		(stroke
			(width 0.087376)
			(type default)
		)
		(layer "F.Cu")
	)
	(gr_line
		(start 212.63864 -254.839216)
		(end 212.763862 -254.713994)
		(stroke
			(width 0.087376)
			(type default)
		)
		(layer "F.Cu")
	)
	(gr_line
		(start 213.293198 -254.713994)
		(end 213.41842 -254.839216)
		(stroke
			(width 0.087376)
			(type default)
		)
		(layer "F.Cu")
	)
	(gr_line
		(start 213.396576 -52.846478)
		(end 213.512908 -52.730146)
		(stroke
			(width 0.087376)
			(type default)
		)
		(layer "F.Cu")
	)
	(gr_line
		(start 213.398354 -53.279802)
		(end 213.575392 -53.279802)
		(stroke
			(width 0.087376)
			(type default)
		)
		(layer "F.Cu")
	)
	(gr_line
		(start 213.41842 -254.839216)
		(end 213.942676 -254.839216)
		(stroke
			(width 0.087376)
			(type default)
		)
		(layer "F.Cu")
	)
	(gr_line
		(start 213.428326 -258.744974)
		(end 213.553548 -258.870196)
		(stroke
			(width 0.087376)
			(type default)
		)
		(layer "F.Cu")
	)
	(gr_line
		(start 213.553548 -258.870196)
		(end 214.077804 -258.870196)
		(stroke
			(width 0.087376)
			(type default)
		)
		(layer "F.Cu")
	)
	(gr_line
		(start 213.575392 -53.279802)
		(end 213.946232 -52.909216)
		(stroke
			(width 0.087376)
			(type default)
		)
		(layer "F.Cu")
	)
	(gr_line
		(start 213.598252 -254.4064)
		(end 213.762844 -254.4064)
		(stroke
			(width 0.087376)
			(type default)
		)
		(layer "F.Cu")
	)
	(gr_line
		(start 213.73338 -258.43738)
		(end 213.897972 -258.43738)
		(stroke
			(width 0.087376)
			(type default)
		)
		(layer "F.Cu")
	)
	(gr_line
		(start 213.884002 -57.260998)
		(end 214.000334 -57.144666)
		(stroke
			(width 0.087376)
			(type default)
		)
		(layer "F.Cu")
	)
	(gr_line
		(start 213.88578 -57.694322)
		(end 214.062818 -57.694322)
		(stroke
			(width 0.087376)
			(type default)
		)
		(layer "F.Cu")
	)
	(gr_line
		(start 213.942676 -254.839216)
		(end 214.067898 -254.713994)
		(stroke
			(width 0.087376)
			(type default)
		)
		(layer "F.Cu")
	)
	(gr_line
		(start 213.946232 -52.731924)
		(end 213.946232 -52.909216)
		(stroke
			(width 0.087376)
			(type default)
		)
		(layer "F.Cu")
	)
	(gr_line
		(start 214.062818 -57.694322)
		(end 214.433658 -57.323736)
		(stroke
			(width 0.087376)
			(type default)
		)
		(layer "F.Cu")
	)
	(gr_line
		(start 214.077804 -258.870196)
		(end 214.203026 -258.744974)
		(stroke
			(width 0.087376)
			(type default)
		)
		(layer "F.Cu")
	)
	(gr_line
		(start 214.318596 -51.924458)
		(end 214.434928 -51.808126)
		(stroke
			(width 0.087376)
			(type default)
		)
		(layer "F.Cu")
	)
	(gr_line
		(start 214.320374 -52.357782)
		(end 214.497666 -52.357782)
		(stroke
			(width 0.087376)
			(type default)
		)
		(layer "F.Cu")
	)
	(gr_line
		(start 214.433658 -57.146444)
		(end 214.433658 -57.323736)
		(stroke
			(width 0.087376)
			(type default)
		)
		(layer "F.Cu")
	)
	(gr_line
		(start 214.497666 -52.357782)
		(end 214.868252 -51.986942)
		(stroke
			(width 0.087376)
			(type default)
		)
		(layer "F.Cu")
	)
	(gr_line
		(start 214.732362 -258.744974)
		(end 214.857584 -258.870196)
		(stroke
			(width 0.087376)
			(type default)
		)
		(layer "F.Cu")
	)
	(gr_line
		(start 214.806022 -56.338978)
		(end 214.922354 -56.222646)
		(stroke
			(width 0.087376)
			(type default)
		)
		(layer "F.Cu")
	)
	(gr_line
		(start 214.8078 -56.772302)
		(end 214.984838 -56.772302)
		(stroke
			(width 0.087376)
			(type default)
		)
		(layer "F.Cu")
	)
	(gr_line
		(start 214.857584 -258.870196)
		(end 215.38184 -258.870196)
		(stroke
			(width 0.087376)
			(type default)
		)
		(layer "F.Cu")
	)
	(gr_line
		(start 214.868252 -51.809904)
		(end 214.868252 -51.986942)
		(stroke
			(width 0.087376)
			(type default)
		)
		(layer "F.Cu")
	)
	(gr_line
		(start 214.984838 -56.772302)
		(end 215.355678 -56.401716)
		(stroke
			(width 0.087376)
			(type default)
		)
		(layer "F.Cu")
	)
	(gr_line
		(start 215.037416 -258.43738)
		(end 215.202008 -258.43738)
		(stroke
			(width 0.087376)
			(type default)
		)
		(layer "F.Cu")
	)
	(gr_line
		(start 215.355678 -56.224424)
		(end 215.355678 -56.401716)
		(stroke
			(width 0.087376)
			(type default)
		)
		(layer "F.Cu")
	)
	(gr_line
		(start 215.38184 -258.870196)
		(end 215.507062 -258.744974)
		(stroke
			(width 0.087376)
			(type default)
		)
		(layer "F.Cu")
	)
	(gr_line
		(start 215.480392 -356.23754)
		(end 215.605614 -356.362762)
		(stroke
			(width 0.087376)
			(type default)
		)
		(layer "F.Cu")
	)
	(gr_line
		(start 215.605614 -356.362762)
		(end 216.12987 -356.362762)
		(stroke
			(width 0.087376)
			(type default)
		)
		(layer "F.Cu")
	)
	(gr_line
		(start 215.728042 -55.416958)
		(end 215.844374 -55.300626)
		(stroke
			(width 0.087376)
			(type default)
		)
		(layer "F.Cu")
	)
	(gr_line
		(start 215.72982 -55.850282)
		(end 215.907112 -55.850282)
		(stroke
			(width 0.087376)
			(type default)
		)
		(layer "F.Cu")
	)
	(gr_line
		(start 215.785446 -355.929946)
		(end 215.950038 -355.929946)
		(stroke
			(width 0.087376)
			(type default)
		)
		(layer "F.Cu")
	)
	(gr_line
		(start 215.907112 -55.850282)
		(end 216.277698 -55.479442)
		(stroke
			(width 0.087376)
			(type default)
		)
		(layer "F.Cu")
	)
	(gr_line
		(start 216.10193 -492.72063)
		(end 216.3445 -492.9632)
		(stroke
			(width 0.085598)
			(type default)
		)
		(layer "F.Cu")
	)
	(gr_line
		(start 216.10193 -491.93577)
		(end 216.3445 -491.6932)
		(stroke
			(width 0.085598)
			(type default)
		)
		(layer "F.Cu")
	)
	(gr_line
		(start 216.12987 -356.362762)
		(end 216.255092 -356.23754)
		(stroke
			(width 0.087376)
			(type default)
		)
		(layer "F.Cu")
	)
	(gr_line
		(start 216.277698 -55.302404)
		(end 216.277698 -55.479442)
		(stroke
			(width 0.087376)
			(type default)
		)
		(layer "F.Cu")
	)
	(gr_line
		(start 216.35593 -391.55243)
		(end 216.5985 -391.795)
		(stroke
			(width 0.085598)
			(type default)
		)
		(layer "F.Cu")
	)
	(gr_line
		(start 216.35593 -390.76757)
		(end 216.5985 -390.525)
		(stroke
			(width 0.085598)
			(type default)
		)
		(layer "F.Cu")
	)
	(gr_line
		(start 216.35593 -288.55543)
		(end 216.5985 -288.798)
		(stroke
			(width 0.085598)
			(type default)
		)
		(layer "F.Cu")
	)
	(gr_line
		(start 216.35593 -287.77057)
		(end 216.5985 -287.528)
		(stroke
			(width 0.085598)
			(type default)
		)
		(layer "F.Cu")
	)
	(gr_line
		(start 216.35593 -185.55843)
		(end 216.5985 -185.801)
		(stroke
			(width 0.085598)
			(type default)
		)
		(layer "F.Cu")
	)
	(gr_line
		(start 216.35593 -184.77357)
		(end 216.5985 -184.531)
		(stroke
			(width 0.085598)
			(type default)
		)
		(layer "F.Cu")
	)
	(gr_line
		(start 216.35593 -82.56143)
		(end 216.5985 -82.804)
		(stroke
			(width 0.085598)
			(type default)
		)
		(layer "F.Cu")
	)
	(gr_line
		(start 216.35593 -81.77657)
		(end 216.5985 -81.534)
		(stroke
			(width 0.085598)
			(type default)
		)
		(layer "F.Cu")
	)
	(gr_line
		(start 216.612978 -254.713994)
		(end 216.7382 -254.839216)
		(stroke
			(width 0.087376)
			(type default)
		)
		(layer "F.Cu")
	)
	(gr_line
		(start 216.666064 -49.57699)
		(end 216.782396 -49.460658)
		(stroke
			(width 0.087376)
			(type default)
		)
		(layer "F.Cu")
	)
	(gr_line
		(start 216.667842 -50.010314)
		(end 216.84488 -50.010314)
		(stroke
			(width 0.087376)
			(type default)
		)
		(layer "F.Cu")
	)
	(gr_line
		(start 216.7382 -254.839216)
		(end 217.262456 -254.839216)
		(stroke
			(width 0.087376)
			(type default)
		)
		(layer "F.Cu")
	)
	(gr_line
		(start 216.784428 -356.23754)
		(end 216.90965 -356.362762)
		(stroke
			(width 0.087376)
			(type default)
		)
		(layer "F.Cu")
	)
	(gr_line
		(start 216.84488 -50.010314)
		(end 217.21572 -49.639474)
		(stroke
			(width 0.087376)
			(type default)
		)
		(layer "F.Cu")
	)
	(gr_line
		(start 216.90965 -356.362762)
		(end 217.433906 -356.362762)
		(stroke
			(width 0.087376)
			(type default)
		)
		(layer "F.Cu")
	)
	(gr_line
		(start 216.918032 -254.4064)
		(end 217.082624 -254.4064)
		(stroke
			(width 0.087376)
			(type default)
		)
		(layer "F.Cu")
	)
	(gr_line
		(start 217.089482 -355.929946)
		(end 217.254074 -355.929946)
		(stroke
			(width 0.087376)
			(type default)
		)
		(layer "F.Cu")
	)
	(gr_line
		(start 217.21572 -49.462436)
		(end 217.21572 -49.639474)
		(stroke
			(width 0.087376)
			(type default)
		)
		(layer "F.Cu")
	)
	(gr_line
		(start 217.2335 -492.9632)
		(end 217.47607 -492.72063)
		(stroke
			(width 0.085598)
			(type default)
		)
		(layer "F.Cu")
	)
	(gr_line
		(start 217.2335 -491.6932)
		(end 217.47607 -491.93577)
		(stroke
			(width 0.085598)
			(type default)
		)
		(layer "F.Cu")
	)
	(gr_line
		(start 217.262456 -254.839216)
		(end 217.387678 -254.713994)
		(stroke
			(width 0.087376)
			(type default)
		)
		(layer "F.Cu")
	)
	(gr_line
		(start 217.433906 -356.362762)
		(end 217.559128 -356.23754)
		(stroke
			(width 0.087376)
			(type default)
		)
		(layer "F.Cu")
	)
	(gr_line
		(start 217.4875 -391.795)
		(end 217.73007 -391.55243)
		(stroke
			(width 0.085598)
			(type default)
		)
		(layer "F.Cu")
	)
	(gr_line
		(start 217.4875 -390.525)
		(end 217.73007 -390.76757)
		(stroke
			(width 0.085598)
			(type default)
		)
		(layer "F.Cu")
	)
	(gr_line
		(start 217.4875 -288.798)
		(end 217.73007 -288.55543)
		(stroke
			(width 0.085598)
			(type default)
		)
		(layer "F.Cu")
	)
	(gr_line
		(start 217.4875 -287.528)
		(end 217.73007 -287.77057)
		(stroke
			(width 0.085598)
			(type default)
		)
		(layer "F.Cu")
	)
	(gr_line
		(start 217.4875 -185.801)
		(end 217.73007 -185.55843)
		(stroke
			(width 0.085598)
			(type default)
		)
		(layer "F.Cu")
	)
	(gr_line
		(start 217.4875 -184.531)
		(end 217.73007 -184.77357)
		(stroke
			(width 0.085598)
			(type default)
		)
		(layer "F.Cu")
	)
	(gr_line
		(start 217.4875 -82.804)
		(end 217.73007 -82.56143)
		(stroke
			(width 0.085598)
			(type default)
		)
		(layer "F.Cu")
	)
	(gr_line
		(start 217.4875 -81.534)
		(end 217.73007 -81.77657)
		(stroke
			(width 0.085598)
			(type default)
		)
		(layer "F.Cu")
	)
	(gr_line
		(start 217.588084 -48.65497)
		(end 217.704416 -48.538638)
		(stroke
			(width 0.087376)
			(type default)
		)
		(layer "F.Cu")
	)
	(gr_line
		(start 217.589862 -49.088294)
		(end 217.767154 -49.088294)
		(stroke
			(width 0.087376)
			(type default)
		)
		(layer "F.Cu")
	)
	(gr_line
		(start 217.767154 -49.088294)
		(end 218.13774 -48.717454)
		(stroke
			(width 0.087376)
			(type default)
		)
		(layer "F.Cu")
	)
	(gr_line
		(start 217.917014 -254.713994)
		(end 218.042236 -254.839216)
		(stroke
			(width 0.087376)
			(type default)
		)
		(layer "F.Cu")
	)
	(gr_line
		(start 218.042236 -254.839216)
		(end 218.566492 -254.839216)
		(stroke
			(width 0.087376)
			(type default)
		)
		(layer "F.Cu")
	)
	(gr_line
		(start 218.052142 -258.744974)
		(end 218.177364 -258.870196)
		(stroke
			(width 0.087376)
			(type default)
		)
		(layer "F.Cu")
	)
	(gr_line
		(start 218.13774 -48.540416)
		(end 218.13774 -48.717454)
		(stroke
			(width 0.087376)
			(type default)
		)
		(layer "F.Cu")
	)
	(gr_line
		(start 218.177364 -258.870196)
		(end 218.70162 -258.870196)
		(stroke
			(width 0.087376)
			(type default)
		)
		(layer "F.Cu")
	)
	(gr_line
		(start 218.222068 -254.4064)
		(end 218.38666 -254.4064)
		(stroke
			(width 0.087376)
			(type default)
		)
		(layer "F.Cu")
	)
	(gr_line
		(start 218.357196 -258.43738)
		(end 218.521788 -258.43738)
		(stroke
			(width 0.087376)
			(type default)
		)
		(layer "F.Cu")
	)
	(gr_line
		(start 218.449144 -492.663734)
		(end 219.009214 -493.223804)
		(stroke
			(width 0.085598)
			(type default)
		)
		(layer "F.Cu")
	)
	(gr_line
		(start 218.449144 -491.878874)
		(end 219.009214 -491.318804)
		(stroke
			(width 0.085598)
			(type default)
		)
		(layer "F.Cu")
	)
	(gr_line
		(start 218.510358 -47.732696)
		(end 218.62669 -47.616364)
		(stroke
			(width 0.087376)
			(type default)
		)
		(layer "F.Cu")
	)
	(gr_line
		(start 218.512136 -48.16602)
		(end 218.689174 -48.16602)
		(stroke
			(width 0.087376)
			(type default)
		)
		(layer "F.Cu")
	)
	(gr_line
		(start 218.566492 -254.839216)
		(end 218.691714 -254.713994)
		(stroke
			(width 0.087376)
			(type default)
		)
		(layer "F.Cu")
	)
	(gr_line
		(start 218.689174 -48.16602)
		(end 219.060014 -47.795434)
		(stroke
			(width 0.087376)
			(type default)
		)
		(layer "F.Cu")
	)
	(gr_line
		(start 218.70162 -258.870196)
		(end 218.826842 -258.744974)
		(stroke
			(width 0.087376)
			(type default)
		)
		(layer "F.Cu")
	)
	(gr_line
		(start 218.855544 -185.51779)
		(end 219.415614 -186.07786)
		(stroke
			(width 0.085598)
			(type default)
		)
		(layer "F.Cu")
	)
	(gr_line
		(start 218.855544 -184.73293)
		(end 219.415614 -184.17286)
		(stroke
			(width 0.085598)
			(type default)
		)
		(layer "F.Cu")
	)
	(gr_line
		(start 218.880944 -82.517742)
		(end 219.441014 -83.077812)
		(stroke
			(width 0.085598)
			(type default)
		)
		(layer "F.Cu")
	)
	(gr_line
		(start 218.880944 -81.732882)
		(end 219.441014 -81.172812)
		(stroke
			(width 0.085598)
			(type default)
		)
		(layer "F.Cu")
	)
	(gr_line
		(start 218.957144 -288.517838)
		(end 219.517214 -289.077908)
		(stroke
			(width 0.085598)
			(type default)
		)
		(layer "F.Cu")
	)
	(gr_line
		(start 218.957144 -287.732978)
		(end 219.517214 -287.172908)
		(stroke
			(width 0.085598)
			(type default)
		)
		(layer "F.Cu")
	)
	(gr_line
		(start 219.007944 -391.517886)
		(end 219.568014 -392.077956)
		(stroke
			(width 0.085598)
			(type default)
		)
		(layer "F.Cu")
	)
	(gr_line
		(start 219.007944 -390.733026)
		(end 219.568014 -390.172956)
		(stroke
			(width 0.085598)
			(type default)
		)
		(layer "F.Cu")
	)
	(gr_line
		(start 219.009214 -492.714788)
		(end 219.009214 -493.223804)
		(stroke
			(width 0.085598)
			(type default)
		)
		(layer "F.Cu")
	)
	(gr_line
		(start 219.009214 -492.714788)
		(end 219.072968 -492.651034)
		(stroke
			(width 0.085598)
			(type default)
		)
		(layer "F.Cu")
	)
	(gr_line
		(start 219.009214 -491.802166)
		(end 219.072968 -491.86592)
		(stroke
			(width 0.085598)
			(type default)
		)
		(layer "F.Cu")
	)
	(gr_line
		(start 219.009214 -491.318804)
		(end 219.009214 -491.802166)
		(stroke
			(width 0.085598)
			(type default)
		)
		(layer "F.Cu")
	)
	(gr_line
		(start 219.060014 -47.618142)
		(end 219.060014 -47.795434)
		(stroke
			(width 0.087376)
			(type default)
		)
		(layer "F.Cu")
	)
	(gr_line
		(start 219.22105 -254.713994)
		(end 219.346272 -254.839216)
		(stroke
			(width 0.087376)
			(type default)
		)
		(layer "F.Cu")
	)
	(gr_line
		(start 219.346272 -254.839216)
		(end 219.870528 -254.839216)
		(stroke
			(width 0.087376)
			(type default)
		)
		(layer "F.Cu")
	)
	(gr_line
		(start 219.356178 -258.744974)
		(end 219.4814 -258.870196)
		(stroke
			(width 0.087376)
			(type default)
		)
		(layer "F.Cu")
	)
	(gr_line
		(start 219.415614 -186.07786)
		(end 219.975684 -185.51779)
		(stroke
			(width 0.085598)
			(type default)
		)
		(layer "F.Cu")
	)
	(gr_line
		(start 219.415614 -184.17286)
		(end 219.975684 -184.73293)
		(stroke
			(width 0.085598)
			(type default)
		)
		(layer "F.Cu")
	)
	(gr_line
		(start 219.441014 -83.077812)
		(end 220.001084 -82.517742)
		(stroke
			(width 0.085598)
			(type default)
		)
		(layer "F.Cu")
	)
	(gr_line
		(start 219.441014 -81.172812)
		(end 220.001084 -81.732882)
		(stroke
			(width 0.085598)
			(type default)
		)
		(layer "F.Cu")
	)
	(gr_line
		(start 219.4814 -258.870196)
		(end 220.005656 -258.870196)
		(stroke
			(width 0.087376)
			(type default)
		)
		(layer "F.Cu")
	)
	(gr_line
		(start 219.517214 -289.077908)
		(end 220.077284 -288.517838)
		(stroke
			(width 0.085598)
			(type default)
		)
		(layer "F.Cu")
	)
	(gr_line
		(start 219.517214 -287.172908)
		(end 220.077284 -287.732978)
		(stroke
			(width 0.085598)
			(type default)
		)
		(layer "F.Cu")
	)
	(gr_line
		(start 219.526104 -254.4064)
		(end 219.690696 -254.4064)
		(stroke
			(width 0.087376)
			(type default)
		)
		(layer "F.Cu")
	)
	(gr_line
		(start 219.568014 -392.077956)
		(end 220.128084 -391.517886)
		(stroke
			(width 0.085598)
			(type default)
		)
		(layer "F.Cu")
	)
	(gr_line
		(start 219.568014 -390.172956)
		(end 220.128084 -390.733026)
		(stroke
			(width 0.085598)
			(type default)
		)
		(layer "F.Cu")
	)
	(gr_line
		(start 219.661232 -258.43738)
		(end 219.825824 -258.43738)
		(stroke
			(width 0.087376)
			(type default)
		)
		(layer "F.Cu")
	)
	(gr_line
		(start 219.870528 -254.839216)
		(end 219.99575 -254.713994)
		(stroke
			(width 0.087376)
			(type default)
		)
		(layer "F.Cu")
	)
	(gr_line
		(start 220.005656 -258.870196)
		(end 220.130878 -258.744974)
		(stroke
			(width 0.087376)
			(type default)
		)
		(layer "F.Cu")
	)
	(gr_line
		(start 220.104208 -356.23754)
		(end 220.22943 -356.362762)
		(stroke
			(width 0.087376)
			(type default)
		)
		(layer "F.Cu")
	)
	(gr_line
		(start 220.22943 -356.362762)
		(end 220.753686 -356.362762)
		(stroke
			(width 0.087376)
			(type default)
		)
		(layer "F.Cu")
	)
	(gr_line
		(start 220.330014 -489.796582)
		(end 220.51899 -489.607606)
		(stroke
			(width 0.087376)
			(type default)
		)
		(layer "F.Cu")
	)
	(gr_line
		(start 220.330014 -488.983782)
		(end 220.51899 -489.172758)
		(stroke
			(width 0.087376)
			(type default)
		)
		(layer "F.Cu")
	)
	(gr_line
		(start 220.330014 -484.99649)
		(end 220.51899 -484.807514)
		(stroke
			(width 0.087376)
			(type default)
		)
		(layer "F.Cu")
	)
	(gr_line
		(start 220.330014 -484.18369)
		(end 220.51899 -484.372666)
		(stroke
			(width 0.087376)
			(type default)
		)
		(layer "F.Cu")
	)
	(gr_line
		(start 220.330014 -480.196652)
		(end 220.51899 -480.007676)
		(stroke
			(width 0.087376)
			(type default)
		)
		(layer "F.Cu")
	)
	(gr_line
		(start 220.330014 -479.383852)
		(end 220.51899 -479.572828)
		(stroke
			(width 0.087376)
			(type default)
		)
		(layer "F.Cu")
	)
	(gr_line
		(start 220.330014 -467.396576)
		(end 220.51899 -467.2076)
		(stroke
			(width 0.087376)
			(type default)
		)
		(layer "F.Cu")
	)
	(gr_line
		(start 220.330014 -466.583776)
		(end 220.51899 -466.772752)
		(stroke
			(width 0.087376)
			(type default)
		)
		(layer "F.Cu")
	)
	(gr_line
		(start 220.330014 -386.796534)
		(end 220.51899 -386.607558)
		(stroke
			(width 0.087376)
			(type default)
		)
		(layer "F.Cu")
	)
	(gr_line
		(start 220.330014 -385.983734)
		(end 220.51899 -386.17271)
		(stroke
			(width 0.087376)
			(type default)
		)
		(layer "F.Cu")
	)
	(gr_line
		(start 220.330014 -381.996442)
		(end 220.51899 -381.807466)
		(stroke
			(width 0.087376)
			(type default)
		)
		(layer "F.Cu")
	)
	(gr_line
		(start 220.330014 -381.183642)
		(end 220.51899 -381.372618)
		(stroke
			(width 0.087376)
			(type default)
		)
		(layer "F.Cu")
	)
	(gr_line
		(start 220.330014 -377.196604)
		(end 220.51899 -377.007628)
		(stroke
			(width 0.087376)
			(type default)
		)
		(layer "F.Cu")
	)
	(gr_line
		(start 220.330014 -376.383804)
		(end 220.51899 -376.57278)
		(stroke
			(width 0.087376)
			(type default)
		)
		(layer "F.Cu")
	)
	(gr_line
		(start 220.330014 -364.396528)
		(end 220.51899 -364.207552)
		(stroke
			(width 0.087376)
			(type default)
		)
		(layer "F.Cu")
	)
	(gr_line
		(start 220.330014 -363.583728)
		(end 220.51899 -363.772704)
		(stroke
			(width 0.087376)
			(type default)
		)
		(layer "F.Cu")
	)
	(gr_line
		(start 220.330014 -283.796486)
		(end 220.51899 -283.60751)
		(stroke
			(width 0.087376)
			(type default)
		)
		(layer "F.Cu")
	)
	(gr_line
		(start 220.330014 -282.983686)
		(end 220.51899 -283.172662)
		(stroke
			(width 0.087376)
			(type default)
		)
		(layer "F.Cu")
	)
	(gr_line
		(start 220.330014 -278.996394)
		(end 220.51899 -278.807418)
		(stroke
			(width 0.087376)
			(type default)
		)
		(layer "F.Cu")
	)
	(gr_line
		(start 220.330014 -278.183594)
		(end 220.51899 -278.37257)
		(stroke
			(width 0.087376)
			(type default)
		)
		(layer "F.Cu")
	)
	(gr_line
		(start 220.330014 -274.196556)
		(end 220.51899 -274.00758)
		(stroke
			(width 0.087376)
			(type default)
		)
		(layer "F.Cu")
	)
	(gr_line
		(start 220.330014 -273.383756)
		(end 220.51899 -273.572732)
		(stroke
			(width 0.087376)
			(type default)
		)
		(layer "F.Cu")
	)
	(gr_line
		(start 220.330014 -261.39648)
		(end 220.51899 -261.207504)
		(stroke
			(width 0.087376)
			(type default)
		)
		(layer "F.Cu")
	)
	(gr_line
		(start 220.330014 -260.58368)
		(end 220.51899 -260.772656)
		(stroke
			(width 0.087376)
			(type default)
		)
		(layer "F.Cu")
	)
	(gr_line
		(start 220.330014 -180.796438)
		(end 220.51899 -180.607462)
		(stroke
			(width 0.087376)
			(type default)
		)
		(layer "F.Cu")
	)
	(gr_line
		(start 220.330014 -179.983638)
		(end 220.51899 -180.172614)
		(stroke
			(width 0.087376)
			(type default)
		)
		(layer "F.Cu")
	)
	(gr_line
		(start 220.330014 -175.996346)
		(end 220.51899 -175.80737)
		(stroke
			(width 0.087376)
			(type default)
		)
		(layer "F.Cu")
	)
	(gr_line
		(start 220.330014 -175.183546)
		(end 220.51899 -175.372522)
		(stroke
			(width 0.087376)
			(type default)
		)
		(layer "F.Cu")
	)
	(gr_line
		(start 220.330014 -171.196508)
		(end 220.51899 -171.007532)
		(stroke
			(width 0.087376)
			(type default)
		)
		(layer "F.Cu")
	)
	(gr_line
		(start 220.330014 -170.383708)
		(end 220.51899 -170.572684)
		(stroke
			(width 0.087376)
			(type default)
		)
		(layer "F.Cu")
	)
	(gr_line
		(start 220.330014 -158.396432)
		(end 220.51899 -158.207456)
		(stroke
			(width 0.087376)
			(type default)
		)
		(layer "F.Cu")
	)
	(gr_line
		(start 220.330014 -157.583632)
		(end 220.51899 -157.772608)
		(stroke
			(width 0.087376)
			(type default)
		)
		(layer "F.Cu")
	)
	(gr_line
		(start 220.330014 -77.79639)
		(end 220.51899 -77.607414)
		(stroke
			(width 0.087376)
			(type default)
		)
		(layer "F.Cu")
	)
	(gr_line
		(start 220.330014 -76.98359)
		(end 220.51899 -77.172566)
		(stroke
			(width 0.087376)
			(type default)
		)
		(layer "F.Cu")
	)
	(gr_line
		(start 220.330014 -72.996298)
		(end 220.51899 -72.807322)
		(stroke
			(width 0.087376)
			(type default)
		)
		(layer "F.Cu")
	)
	(gr_line
		(start 220.330014 -72.183498)
		(end 220.51899 -72.372474)
		(stroke
			(width 0.087376)
			(type default)
		)
		(layer "F.Cu")
	)
	(gr_line
		(start 220.330014 -68.19646)
		(end 220.51899 -68.007484)
		(stroke
			(width 0.087376)
			(type default)
		)
		(layer "F.Cu")
	)
	(gr_line
		(start 220.330014 -67.38366)
		(end 220.51899 -67.572636)
		(stroke
			(width 0.087376)
			(type default)
		)
		(layer "F.Cu")
	)
	(gr_line
		(start 220.330014 -55.396384)
		(end 220.51899 -55.207408)
		(stroke
			(width 0.087376)
			(type default)
		)
		(layer "F.Cu")
	)
	(gr_line
		(start 220.330014 -54.583584)
		(end 220.51899 -54.77256)
		(stroke
			(width 0.087376)
			(type default)
		)
		(layer "F.Cu")
	)
	(gr_line
		(start 220.409262 -355.929946)
		(end 220.573854 -355.929946)
		(stroke
			(width 0.087376)
			(type default)
		)
		(layer "F.Cu")
	)
	(gr_line
		(start 220.660214 -258.744974)
		(end 220.785436 -258.870196)
		(stroke
			(width 0.087376)
			(type default)
		)
		(layer "F.Cu")
	)
	(gr_line
		(start 220.753686 -356.362762)
		(end 220.878908 -356.23754)
		(stroke
			(width 0.087376)
			(type default)
		)
		(layer "F.Cu")
	)
	(gr_line
		(start 220.785436 -258.870196)
		(end 221.309692 -258.870196)
		(stroke
			(width 0.087376)
			(type default)
		)
		(layer "F.Cu")
	)
	(gr_line
		(start 220.965268 -258.43738)
		(end 221.12986 -258.43738)
		(stroke
			(width 0.087376)
			(type default)
		)
		(layer "F.Cu")
	)
	(gr_line
		(start 221.309692 -258.870196)
		(end 221.434914 -258.744974)
		(stroke
			(width 0.087376)
			(type default)
		)
		(layer "F.Cu")
	)
	(gr_line
		(start 221.408244 -356.23754)
		(end 221.533466 -356.362762)
		(stroke
			(width 0.087376)
			(type default)
		)
		(layer "F.Cu")
	)
	(gr_line
		(start 221.533466 -356.362762)
		(end 222.057722 -356.362762)
		(stroke
			(width 0.087376)
			(type default)
		)
		(layer "F.Cu")
	)
	(gr_line
		(start 221.713298 -355.929946)
		(end 221.87789 -355.929946)
		(stroke
			(width 0.087376)
			(type default)
		)
		(layer "F.Cu")
	)
	(gr_line
		(start 221.727014 -492.349028)
		(end 222.06839 -492.007652)
		(stroke
			(width 0.087376)
			(type default)
		)
		(layer "F.Cu")
	)
	(gr_line
		(start 221.727014 -491.231428)
		(end 222.06839 -491.572804)
		(stroke
			(width 0.087376)
			(type default)
		)
		(layer "F.Cu")
	)
	(gr_line
		(start 221.727014 -487.531156)
		(end 221.727014 -487.548936)
		(stroke
			(width 0.087376)
			(type default)
		)
		(layer "F.Cu")
	)
	(gr_line
		(start 221.727014 -487.531156)
		(end 222.0595 -487.19867)
		(stroke
			(width 0.087376)
			(type default)
		)
		(layer "F.Cu")
	)
	(gr_line
		(start 221.727014 -486.431336)
		(end 222.0595 -486.763822)
		(stroke
			(width 0.087376)
			(type default)
		)
		(layer "F.Cu")
	)
	(gr_line
		(start 221.727014 -482.748844)
		(end 222.06839 -482.407468)
		(stroke
			(width 0.087376)
			(type default)
		)
		(layer "F.Cu")
	)
	(gr_line
		(start 221.727014 -481.631244)
		(end 222.06839 -481.97262)
		(stroke
			(width 0.087376)
			(type default)
		)
		(layer "F.Cu")
	)
	(gr_line
		(start 221.727014 -469.949022)
		(end 222.06839 -469.607646)
		(stroke
			(width 0.087376)
			(type default)
		)
		(layer "F.Cu")
	)
	(gr_line
		(start 221.727014 -468.831422)
		(end 222.06839 -469.172798)
		(stroke
			(width 0.087376)
			(type default)
		)
		(layer "F.Cu")
	)
	(gr_line
		(start 221.727014 -389.34898)
		(end 222.06839 -389.007604)
		(stroke
			(width 0.087376)
			(type default)
		)
		(layer "F.Cu")
	)
	(gr_line
		(start 221.727014 -388.23138)
		(end 222.06839 -388.572756)
		(stroke
			(width 0.087376)
			(type default)
		)
		(layer "F.Cu")
	)
	(gr_line
		(start 221.727014 -384.548888)
		(end 222.06839 -384.207512)
		(stroke
			(width 0.087376)
			(type default)
		)
		(layer "F.Cu")
	)
	(gr_line
		(start 221.727014 -383.431288)
		(end 222.06839 -383.772664)
		(stroke
			(width 0.087376)
			(type default)
		)
		(layer "F.Cu")
	)
	(gr_line
		(start 221.727014 -379.748796)
		(end 222.06839 -379.40742)
		(stroke
			(width 0.087376)
			(type default)
		)
		(layer "F.Cu")
	)
	(gr_line
		(start 221.727014 -378.631196)
		(end 222.06839 -378.972572)
		(stroke
			(width 0.087376)
			(type default)
		)
		(layer "F.Cu")
	)
	(gr_line
		(start 221.727014 -366.948974)
		(end 222.06839 -366.607598)
		(stroke
			(width 0.087376)
			(type default)
		)
		(layer "F.Cu")
	)
	(gr_line
		(start 221.727014 -365.831374)
		(end 222.06839 -366.17275)
		(stroke
			(width 0.087376)
			(type default)
		)
		(layer "F.Cu")
	)
	(gr_line
		(start 221.727014 -286.348932)
		(end 222.06839 -286.007556)
		(stroke
			(width 0.087376)
			(type default)
		)
		(layer "F.Cu")
	)
	(gr_line
		(start 221.727014 -285.231332)
		(end 222.06839 -285.572708)
		(stroke
			(width 0.087376)
			(type default)
		)
		(layer "F.Cu")
	)
	(gr_line
		(start 221.727014 -281.54884)
		(end 222.06839 -281.207464)
		(stroke
			(width 0.087376)
			(type default)
		)
		(layer "F.Cu")
	)
	(gr_line
		(start 221.727014 -280.43124)
		(end 222.06839 -280.772616)
		(stroke
			(width 0.087376)
			(type default)
		)
		(layer "F.Cu")
	)
	(gr_line
		(start 221.727014 -276.748748)
		(end 222.06839 -276.407372)
		(stroke
			(width 0.087376)
			(type default)
		)
		(layer "F.Cu")
	)
	(gr_line
		(start 221.727014 -275.631148)
		(end 222.06839 -275.972524)
		(stroke
			(width 0.087376)
			(type default)
		)
		(layer "F.Cu")
	)
	(gr_line
		(start 221.727014 -263.948926)
		(end 222.06839 -263.60755)
		(stroke
			(width 0.087376)
			(type default)
		)
		(layer "F.Cu")
	)
	(gr_line
		(start 221.727014 -262.831326)
		(end 222.06839 -263.172702)
		(stroke
			(width 0.087376)
			(type default)
		)
		(layer "F.Cu")
	)
	(gr_line
		(start 221.727014 -183.348884)
		(end 222.06839 -183.007508)
		(stroke
			(width 0.087376)
			(type default)
		)
		(layer "F.Cu")
	)
	(gr_line
		(start 221.727014 -182.231284)
		(end 222.06839 -182.57266)
		(stroke
			(width 0.087376)
			(type default)
		)
		(layer "F.Cu")
	)
	(gr_line
		(start 221.727014 -178.548792)
		(end 222.06839 -178.207416)
		(stroke
			(width 0.087376)
			(type default)
		)
		(layer "F.Cu")
	)
	(gr_line
		(start 221.727014 -177.431192)
		(end 222.06839 -177.772568)
		(stroke
			(width 0.087376)
			(type default)
		)
		(layer "F.Cu")
	)
	(gr_line
		(start 221.727014 -173.7487)
		(end 222.06839 -173.407324)
		(stroke
			(width 0.087376)
			(type default)
		)
		(layer "F.Cu")
	)
	(gr_line
		(start 221.727014 -172.6311)
		(end 222.06839 -172.972476)
		(stroke
			(width 0.087376)
			(type default)
		)
		(layer "F.Cu")
	)
	(gr_line
		(start 221.727014 -160.948878)
		(end 222.06839 -160.607502)
		(stroke
			(width 0.087376)
			(type default)
		)
		(layer "F.Cu")
	)
	(gr_line
		(start 221.727014 -159.831278)
		(end 222.06839 -160.172654)
		(stroke
			(width 0.087376)
			(type default)
		)
		(layer "F.Cu")
	)
	(gr_line
		(start 221.727014 -80.348836)
		(end 222.06839 -80.00746)
		(stroke
			(width 0.087376)
			(type default)
		)
		(layer "F.Cu")
	)
	(gr_line
		(start 221.727014 -79.231236)
		(end 222.06839 -79.572612)
		(stroke
			(width 0.087376)
			(type default)
		)
		(layer "F.Cu")
	)
	(gr_line
		(start 221.727014 -75.548744)
		(end 222.06839 -75.207368)
		(stroke
			(width 0.087376)
			(type default)
		)
		(layer "F.Cu")
	)
	(gr_line
		(start 221.727014 -74.431144)
		(end 222.06839 -74.77252)
		(stroke
			(width 0.087376)
			(type default)
		)
		(layer "F.Cu")
	)
	(gr_line
		(start 221.727014 -70.748652)
		(end 222.06839 -70.407276)
		(stroke
			(width 0.087376)
			(type default)
		)
		(layer "F.Cu")
	)
	(gr_line
		(start 221.727014 -69.631052)
		(end 222.06839 -69.972428)
		(stroke
			(width 0.087376)
			(type default)
		)
		(layer "F.Cu")
	)
	(gr_line
		(start 221.727014 -57.94883)
		(end 222.06839 -57.607454)
		(stroke
			(width 0.087376)
			(type default)
		)
		(layer "F.Cu")
	)
	(gr_line
		(start 221.727014 -56.83123)
		(end 222.06839 -57.172606)
		(stroke
			(width 0.087376)
			(type default)
		)
		(layer "F.Cu")
	)
	(gr_line
		(start 222.057722 -356.362762)
		(end 222.182944 -356.23754)
		(stroke
			(width 0.087376)
			(type default)
		)
		(layer "F.Cu")
	)
	(gr_line
		(start 222.437452 -47.24654)
		(end 222.562674 -47.371762)
		(stroke
			(width 0.087376)
			(type default)
		)
		(layer "F.Cu")
	)
	(gr_line
		(start 222.562674 -47.371762)
		(end 223.08693 -47.371762)
		(stroke
			(width 0.087376)
			(type default)
		)
		(layer "F.Cu")
	)
	(gr_line
		(start 222.71228 -356.23754)
		(end 222.837502 -356.362762)
		(stroke
			(width 0.087376)
			(type default)
		)
		(layer "F.Cu")
	)
	(gr_line
		(start 222.742506 -46.938946)
		(end 222.907098 -46.938946)
		(stroke
			(width 0.087376)
			(type default)
		)
		(layer "F.Cu")
	)
	(gr_line
		(start 222.823024 -55.207662)
		(end 223.005396 -55.390034)
		(stroke
			(width 0.087376)
			(type default)
		)
		(layer "F.Cu")
	)
	(gr_line
		(start 222.823024 -54.77256)
		(end 223.00565 -54.589934)
		(stroke
			(width 0.087376)
			(type default)
		)
		(layer "F.Cu")
	)
	(gr_line
		(start 222.828612 -57.601612)
		(end 223.016826 -57.789826)
		(stroke
			(width 0.087376)
			(type default)
		)
		(layer "F.Cu")
	)
	(gr_line
		(start 222.828612 -57.166764)
		(end 223.005396 -56.98998)
		(stroke
			(width 0.087376)
			(type default)
		)
		(layer "F.Cu")
	)
	(gr_line
		(start 222.837502 -356.362762)
		(end 223.361758 -356.362762)
		(stroke
			(width 0.087376)
			(type default)
		)
		(layer "F.Cu")
	)
	(gr_line
		(start 222.84309 -155.78709)
		(end 223.046036 -155.990036)
		(stroke
			(width 0.087376)
			(type default)
		)
		(layer "F.Cu")
	)
	(gr_line
		(start 222.84309 -155.352242)
		(end 223.005396 -155.189936)
		(stroke
			(width 0.087376)
			(type default)
		)
		(layer "F.Cu")
	)
	(gr_line
		(start 222.85071 -464.807554)
		(end 223.033336 -464.99018)
		(stroke
			(width 0.087376)
			(type default)
		)
		(layer "F.Cu")
	)
	(gr_line
		(start 222.85071 -464.372452)
		(end 223.033082 -464.19008)
		(stroke
			(width 0.087376)
			(type default)
		)
		(layer "F.Cu")
	)
	(gr_line
		(start 222.886524 -487.224324)
		(end 223.052386 -487.390186)
		(stroke
			(width 0.087376)
			(type default)
		)
		(layer "F.Cu")
	)
	(gr_line
		(start 222.886524 -486.789476)
		(end 223.085914 -486.590086)
		(stroke
			(width 0.087376)
			(type default)
		)
		(layer "F.Cu")
	)
	(gr_line
		(start 222.950024 -467.207854)
		(end 223.132396 -467.390226)
		(stroke
			(width 0.087376)
			(type default)
		)
		(layer "F.Cu")
	)
	(gr_line
		(start 222.950024 -466.772752)
		(end 223.13265 -466.590126)
		(stroke
			(width 0.087376)
			(type default)
		)
		(layer "F.Cu")
	)
	(gr_line
		(start 222.950024 -377.007628)
		(end 223.132396 -377.19)
		(stroke
			(width 0.087376)
			(type default)
		)
		(layer "F.Cu")
	)
	(gr_line
		(start 222.950024 -376.572526)
		(end 223.132396 -376.390154)
		(stroke
			(width 0.087376)
			(type default)
		)
		(layer "F.Cu")
	)
	(gr_line
		(start 222.950024 -364.207806)
		(end 223.132396 -364.390178)
		(stroke
			(width 0.087376)
			(type default)
		)
		(layer "F.Cu")
	)
	(gr_line
		(start 222.950024 -363.772704)
		(end 223.13265 -363.590078)
		(stroke
			(width 0.087376)
			(type default)
		)
		(layer "F.Cu")
	)
	(gr_line
		(start 222.950024 -263.60755)
		(end 223.132396 -263.789922)
		(stroke
			(width 0.087376)
			(type default)
		)
		(layer "F.Cu")
	)
	(gr_line
		(start 222.950024 -263.172448)
		(end 223.132396 -262.990076)
		(stroke
			(width 0.087376)
			(type default)
		)
		(layer "F.Cu")
	)
	(gr_line
		(start 222.950024 -261.207758)
		(end 223.132396 -261.39013)
		(stroke
			(width 0.087376)
			(type default)
		)
		(layer "F.Cu")
	)
	(gr_line
		(start 222.950024 -260.772656)
		(end 223.13265 -260.59003)
		(stroke
			(width 0.087376)
			(type default)
		)
		(layer "F.Cu")
	)
	(gr_line
		(start 222.950024 -258.807458)
		(end 223.13265 -258.990084)
		(stroke
			(width 0.087376)
			(type default)
		)
		(layer "F.Cu")
	)
	(gr_line
		(start 222.950024 -258.372356)
		(end 223.132396 -258.189984)
		(stroke
			(width 0.087376)
			(type default)
		)
		(layer "F.Cu")
	)
	(gr_line
		(start 222.950024 -160.607502)
		(end 223.132396 -160.789874)
		(stroke
			(width 0.087376)
			(type default)
		)
		(layer "F.Cu")
	)
	(gr_line
		(start 222.950024 -160.1724)
		(end 223.132396 -159.990028)
		(stroke
			(width 0.087376)
			(type default)
		)
		(layer "F.Cu")
	)
	(gr_line
		(start 222.950024 -72.807576)
		(end 223.132396 -72.989948)
		(stroke
			(width 0.087376)
			(type default)
		)
		(layer "F.Cu")
	)
	(gr_line
		(start 222.950024 -72.372474)
		(end 223.13265 -72.189848)
		(stroke
			(width 0.087376)
			(type default)
		)
		(layer "F.Cu")
	)
	(gr_line
		(start 222.950024 -52.807362)
		(end 223.13265 -52.989988)
		(stroke
			(width 0.087376)
			(type default)
		)
		(layer "F.Cu")
	)
	(gr_line
		(start 222.950024 -52.37226)
		(end 223.132396 -52.189888)
		(stroke
			(width 0.087376)
			(type default)
		)
		(layer "F.Cu")
	)
	(gr_line
		(start 222.953072 -386.61086)
		(end 223.132396 -386.790184)
		(stroke
			(width 0.087376)
			(type default)
		)
		(layer "F.Cu")
	)
	(gr_line
		(start 222.953072 -386.176012)
		(end 223.139 -385.990084)
		(stroke
			(width 0.087376)
			(type default)
		)
		(layer "F.Cu")
	)
	(gr_line
		(start 222.953072 -381.810768)
		(end 223.132396 -381.990092)
		(stroke
			(width 0.087376)
			(type default)
		)
		(layer "F.Cu")
	)
	(gr_line
		(start 222.953072 -381.37592)
		(end 223.139 -381.189992)
		(stroke
			(width 0.087376)
			(type default)
		)
		(layer "F.Cu")
	)
	(gr_line
		(start 222.953072 -283.610812)
		(end 223.132396 -283.790136)
		(stroke
			(width 0.087376)
			(type default)
		)
		(layer "F.Cu")
	)
	(gr_line
		(start 222.953072 -283.175964)
		(end 223.139 -282.990036)
		(stroke
			(width 0.087376)
			(type default)
		)
		(layer "F.Cu")
	)
	(gr_line
		(start 222.953072 -281.210766)
		(end 223.132396 -281.39009)
		(stroke
			(width 0.087376)
			(type default)
		)
		(layer "F.Cu")
	)
	(gr_line
		(start 222.953072 -280.775918)
		(end 223.139 -280.58999)
		(stroke
			(width 0.087376)
			(type default)
		)
		(layer "F.Cu")
	)
	(gr_line
		(start 222.953072 -278.81072)
		(end 223.132396 -278.990044)
		(stroke
			(width 0.087376)
			(type default)
		)
		(layer "F.Cu")
	)
	(gr_line
		(start 222.953072 -278.375872)
		(end 223.139 -278.189944)
		(stroke
			(width 0.087376)
			(type default)
		)
		(layer "F.Cu")
	)
	(gr_line
		(start 222.953072 -158.210758)
		(end 223.132396 -158.390082)
		(stroke
			(width 0.087376)
			(type default)
		)
		(layer "F.Cu")
	)
	(gr_line
		(start 222.953072 -157.77591)
		(end 223.139 -157.589982)
		(stroke
			(width 0.087376)
			(type default)
		)
		(layer "F.Cu")
	)
	(gr_line
		(start 222.953072 -77.610716)
		(end 223.132396 -77.79004)
		(stroke
			(width 0.087376)
			(type default)
		)
		(layer "F.Cu")
	)
	(gr_line
		(start 222.953072 -77.175868)
		(end 223.139 -76.98994)
		(stroke
			(width 0.087376)
			(type default)
		)
		(layer "F.Cu")
	)
	(gr_line
		(start 222.953072 -75.21067)
		(end 223.132396 -75.389994)
		(stroke
			(width 0.087376)
			(type default)
		)
		(layer "F.Cu")
	)
	(gr_line
		(start 222.953072 -74.775822)
		(end 223.139 -74.589894)
		(stroke
			(width 0.087376)
			(type default)
		)
		(layer "F.Cu")
	)
	(gr_line
		(start 222.953326 -484.804466)
		(end 223.139 -484.99014)
		(stroke
			(width 0.087376)
			(type default)
		)
		(layer "F.Cu")
	)
	(gr_line
		(start 222.953326 -484.369364)
		(end 223.13265 -484.19004)
		(stroke
			(width 0.087376)
			(type default)
		)
		(layer "F.Cu")
	)
	(gr_line
		(start 222.953326 -480.010978)
		(end 223.132396 -480.190048)
		(stroke
			(width 0.087376)
			(type default)
		)
		(layer "F.Cu")
	)
	(gr_line
		(start 222.953326 -479.575876)
		(end 223.139 -479.390202)
		(stroke
			(width 0.087376)
			(type default)
		)
		(layer "F.Cu")
	)
	(gr_line
		(start 222.953326 -389.010906)
		(end 223.132396 -389.189976)
		(stroke
			(width 0.087376)
			(type default)
		)
		(layer "F.Cu")
	)
	(gr_line
		(start 222.953326 -388.575804)
		(end 223.139 -388.39013)
		(stroke
			(width 0.087376)
			(type default)
		)
		(layer "F.Cu")
	)
	(gr_line
		(start 222.953326 -366.6109)
		(end 223.132396 -366.78997)
		(stroke
			(width 0.087376)
			(type default)
		)
		(layer "F.Cu")
	)
	(gr_line
		(start 222.953326 -366.175798)
		(end 223.139 -365.990124)
		(stroke
			(width 0.087376)
			(type default)
		)
		(layer "F.Cu")
	)
	(gr_line
		(start 222.953326 -361.810808)
		(end 223.13265 -361.990132)
		(stroke
			(width 0.087376)
			(type default)
		)
		(layer "F.Cu")
	)
	(gr_line
		(start 222.953326 -361.375706)
		(end 223.139 -361.190032)
		(stroke
			(width 0.087376)
			(type default)
		)
		(layer "F.Cu")
	)
	(gr_line
		(start 222.953326 -286.010858)
		(end 223.132396 -286.189928)
		(stroke
			(width 0.087376)
			(type default)
		)
		(layer "F.Cu")
	)
	(gr_line
		(start 222.953326 -285.575756)
		(end 223.139 -285.390082)
		(stroke
			(width 0.087376)
			(type default)
		)
		(layer "F.Cu")
	)
	(gr_line
		(start 222.953326 -274.004278)
		(end 223.139 -274.189952)
		(stroke
			(width 0.087376)
			(type default)
		)
		(layer "F.Cu")
	)
	(gr_line
		(start 222.953326 -273.569176)
		(end 223.132396 -273.390106)
		(stroke
			(width 0.087376)
			(type default)
		)
		(layer "F.Cu")
	)
	(gr_line
		(start 222.953326 -183.01081)
		(end 223.132396 -183.18988)
		(stroke
			(width 0.087376)
			(type default)
		)
		(layer "F.Cu")
	)
	(gr_line
		(start 222.953326 -182.575708)
		(end 223.139 -182.390034)
		(stroke
			(width 0.087376)
			(type default)
		)
		(layer "F.Cu")
	)
	(gr_line
		(start 222.953326 -173.404276)
		(end 223.139 -173.58995)
		(stroke
			(width 0.087376)
			(type default)
		)
		(layer "F.Cu")
	)
	(gr_line
		(start 222.953326 -172.969174)
		(end 223.13265 -172.78985)
		(stroke
			(width 0.087376)
			(type default)
		)
		(layer "F.Cu")
	)
	(gr_line
		(start 222.953326 -171.00423)
		(end 223.139 -171.189904)
		(stroke
			(width 0.087376)
			(type default)
		)
		(layer "F.Cu")
	)
	(gr_line
		(start 222.953326 -170.569128)
		(end 223.132396 -170.390058)
		(stroke
			(width 0.087376)
			(type default)
		)
		(layer "F.Cu")
	)
	(gr_line
		(start 222.953326 -80.010762)
		(end 223.132396 -80.189832)
		(stroke
			(width 0.087376)
			(type default)
		)
		(layer "F.Cu")
	)
	(gr_line
		(start 222.953326 -79.57566)
		(end 223.139 -79.389986)
		(stroke
			(width 0.087376)
			(type default)
		)
		(layer "F.Cu")
	)
	(gr_line
		(start 222.953326 -68.004182)
		(end 223.139 -68.189856)
		(stroke
			(width 0.087376)
			(type default)
		)
		(layer "F.Cu")
	)
	(gr_line
		(start 222.953326 -67.56908)
		(end 223.132396 -67.39001)
		(stroke
			(width 0.087376)
			(type default)
		)
		(layer "F.Cu")
	)
	(gr_line
		(start 222.956374 -489.607606)
		(end 223.139 -489.790232)
		(stroke
			(width 0.087376)
			(type default)
		)
		(layer "F.Cu")
	)
	(gr_line
		(start 222.956374 -489.172758)
		(end 223.139 -488.990132)
		(stroke
			(width 0.087376)
			(type default)
		)
		(layer "F.Cu")
	)
	(gr_line
		(start 222.956374 -482.407468)
		(end 223.139 -482.590094)
		(stroke
			(width 0.087376)
			(type default)
		)
		(layer "F.Cu")
	)
	(gr_line
		(start 222.956374 -481.97262)
		(end 223.139 -481.789994)
		(stroke
			(width 0.087376)
			(type default)
		)
		(layer "F.Cu")
	)
	(gr_line
		(start 222.956374 -384.207512)
		(end 223.139 -384.390138)
		(stroke
			(width 0.087376)
			(type default)
		)
		(layer "F.Cu")
	)
	(gr_line
		(start 222.956374 -383.772664)
		(end 223.139 -383.590038)
		(stroke
			(width 0.087376)
			(type default)
		)
		(layer "F.Cu")
	)
	(gr_line
		(start 222.956374 -379.40742)
		(end 223.139 -379.590046)
		(stroke
			(width 0.087376)
			(type default)
		)
		(layer "F.Cu")
	)
	(gr_line
		(start 222.956374 -378.972572)
		(end 223.139 -378.789946)
		(stroke
			(width 0.087376)
			(type default)
		)
		(layer "F.Cu")
	)
	(gr_line
		(start 222.956374 -276.407372)
		(end 223.139 -276.589998)
		(stroke
			(width 0.087376)
			(type default)
		)
		(layer "F.Cu")
	)
	(gr_line
		(start 222.956374 -275.972524)
		(end 223.139 -275.789898)
		(stroke
			(width 0.087376)
			(type default)
		)
		(layer "F.Cu")
	)
	(gr_line
		(start 222.956374 -180.607462)
		(end 223.139 -180.790088)
		(stroke
			(width 0.087376)
			(type default)
		)
		(layer "F.Cu")
	)
	(gr_line
		(start 222.956374 -180.172614)
		(end 223.139 -179.989988)
		(stroke
			(width 0.087376)
			(type default)
		)
		(layer "F.Cu")
	)
	(gr_line
		(start 222.956374 -178.207416)
		(end 223.139 -178.390042)
		(stroke
			(width 0.087376)
			(type default)
		)
		(layer "F.Cu")
	)
	(gr_line
		(start 222.956374 -177.772568)
		(end 223.139 -177.589942)
		(stroke
			(width 0.087376)
			(type default)
		)
		(layer "F.Cu")
	)
	(gr_line
		(start 222.956374 -175.80737)
		(end 223.139 -175.989996)
		(stroke
			(width 0.087376)
			(type default)
		)
		(layer "F.Cu")
	)
	(gr_line
		(start 222.956374 -175.372522)
		(end 223.139 -175.189896)
		(stroke
			(width 0.087376)
			(type default)
		)
		(layer "F.Cu")
	)
	(gr_line
		(start 222.956628 -492.007652)
		(end 223.139 -492.190024)
		(stroke
			(width 0.087376)
			(type default)
		)
		(layer "F.Cu")
	)
	(gr_line
		(start 222.956628 -491.57255)
		(end 223.139 -491.390178)
		(stroke
			(width 0.087376)
			(type default)
		)
		(layer "F.Cu")
	)
	(gr_line
		(start 222.961708 -469.595708)
		(end 223.156018 -469.790018)
		(stroke
			(width 0.087376)
			(type default)
		)
		(layer "F.Cu")
	)
	(gr_line
		(start 222.961708 -469.16086)
		(end 223.132396 -468.990172)
		(stroke
			(width 0.087376)
			(type default)
		)
		(layer "F.Cu")
	)
	(gr_line
		(start 222.97898 -494.582704)
		(end 222.986346 -494.59007)
		(stroke
			(width 0.085598)
			(type default)
		)
		(layer "F.Cu")
	)
	(gr_line
		(start 222.97898 -493.79759)
		(end 222.986346 -493.790224)
		(stroke
			(width 0.085598)
			(type default)
		)
		(layer "F.Cu")
	)
	(gr_line
		(start 222.97898 -391.582656)
		(end 222.986346 -391.590022)
		(stroke
			(width 0.085598)
			(type default)
		)
		(layer "F.Cu")
	)
	(gr_line
		(start 222.97898 -390.797542)
		(end 222.986346 -390.790176)
		(stroke
			(width 0.085598)
			(type default)
		)
		(layer "F.Cu")
	)
	(gr_line
		(start 222.97898 -288.582608)
		(end 222.986346 -288.589974)
		(stroke
			(width 0.085598)
			(type default)
		)
		(layer "F.Cu")
	)
	(gr_line
		(start 222.97898 -287.797494)
		(end 222.986346 -287.790128)
		(stroke
			(width 0.085598)
			(type default)
		)
		(layer "F.Cu")
	)
	(gr_line
		(start 222.97898 -185.58256)
		(end 222.986346 -185.589926)
		(stroke
			(width 0.085598)
			(type default)
		)
		(layer "F.Cu")
	)
	(gr_line
		(start 222.97898 -184.797446)
		(end 222.986346 -184.79008)
		(stroke
			(width 0.085598)
			(type default)
		)
		(layer "F.Cu")
	)
	(gr_line
		(start 222.97898 -82.582512)
		(end 222.986346 -82.589878)
		(stroke
			(width 0.085598)
			(type default)
		)
		(layer "F.Cu")
	)
	(gr_line
		(start 222.97898 -81.797398)
		(end 222.986346 -81.790032)
		(stroke
			(width 0.085598)
			(type default)
		)
		(layer "F.Cu")
	)
	(gr_line
		(start 222.986346 -494.59007)
		(end 224.199958 -494.59007)
		(stroke
			(width 0.085598)
			(type default)
		)
		(layer "F.Cu")
	)
	(gr_line
		(start 222.986346 -493.790224)
		(end 224.199958 -493.790224)
		(stroke
			(width 0.085598)
			(type default)
		)
		(layer "F.Cu")
	)
	(gr_line
		(start 222.986346 -391.590022)
		(end 224.199958 -391.590022)
		(stroke
			(width 0.085598)
			(type default)
		)
		(layer "F.Cu")
	)
	(gr_line
		(start 222.986346 -390.790176)
		(end 224.199958 -390.790176)
		(stroke
			(width 0.085598)
			(type default)
		)
		(layer "F.Cu")
	)
	(gr_line
		(start 222.986346 -288.589974)
		(end 224.199958 -288.589974)
		(stroke
			(width 0.085598)
			(type default)
		)
		(layer "F.Cu")
	)
	(gr_line
		(start 222.986346 -287.790128)
		(end 224.199958 -287.790128)
		(stroke
			(width 0.085598)
			(type default)
		)
		(layer "F.Cu")
	)
	(gr_line
		(start 222.986346 -185.589926)
		(end 224.199958 -185.589926)
		(stroke
			(width 0.085598)
			(type default)
		)
		(layer "F.Cu")
	)
	(gr_line
		(start 222.986346 -184.79008)
		(end 224.199958 -184.79008)
		(stroke
			(width 0.085598)
			(type default)
		)
		(layer "F.Cu")
	)
	(gr_line
		(start 222.986346 -82.589878)
		(end 224.199958 -82.589878)
		(stroke
			(width 0.085598)
			(type default)
		)
		(layer "F.Cu")
	)
	(gr_line
		(start 222.986346 -81.790032)
		(end 224.199958 -81.790032)
		(stroke
			(width 0.085598)
			(type default)
		)
		(layer "F.Cu")
	)
	(gr_line
		(start 222.993712 -150.11654)
		(end 223.118934 -150.241762)
		(stroke
			(width 0.087376)
			(type default)
		)
		(layer "F.Cu")
	)
	(gr_line
		(start 223.005396 -155.189936)
		(end 224.199958 -155.189936)
		(stroke
			(width 0.087376)
			(type default)
		)
		(layer "F.Cu")
	)
	(gr_line
		(start 223.005396 -56.98998)
		(end 224.199958 -56.98998)
		(stroke
			(width 0.087376)
			(type default)
		)
		(layer "F.Cu")
	)
	(gr_line
		(start 223.005396 -55.390034)
		(end 224.199958 -55.390034)
		(stroke
			(width 0.087376)
			(type default)
		)
		(layer "F.Cu")
	)
	(gr_line
		(start 223.00565 -54.589934)
		(end 224.199958 -54.589934)
		(stroke
			(width 0.087376)
			(type default)
		)
		(layer "F.Cu")
	)
	(gr_line
		(start 223.016826 -57.789826)
		(end 224.199958 -57.789826)
		(stroke
			(width 0.087376)
			(type default)
		)
		(layer "F.Cu")
	)
	(gr_line
		(start 223.017334 -355.929946)
		(end 223.181926 -355.929946)
		(stroke
			(width 0.087376)
			(type default)
		)
		(layer "F.Cu")
	)
	(gr_line
		(start 223.019874 -70.470776)
		(end 223.139 -70.589902)
		(stroke
			(width 0.087376)
			(type default)
		)
		(layer "F.Cu")
	)
	(gr_line
		(start 223.019874 -70.035928)
		(end 223.266 -69.789802)
		(stroke
			(width 0.087376)
			(type default)
		)
		(layer "F.Cu")
	)
	(gr_line
		(start 223.033082 -464.19008)
		(end 224.199958 -464.19008)
		(stroke
			(width 0.087376)
			(type default)
		)
		(layer "F.Cu")
	)
	(gr_line
		(start 223.033336 -464.99018)
		(end 224.199958 -464.99018)
		(stroke
			(width 0.087376)
			(type default)
		)
		(layer "F.Cu")
	)
	(gr_line
		(start 223.046036 -155.990036)
		(end 224.199958 -155.990036)
		(stroke
			(width 0.087376)
			(type default)
		)
		(layer "F.Cu")
	)
	(gr_line
		(start 223.052386 -487.390186)
		(end 224.199958 -487.390186)
		(stroke
			(width 0.087376)
			(type default)
		)
		(layer "F.Cu")
	)
	(gr_line
		(start 223.085914 -486.590086)
		(end 224.199958 -486.590086)
		(stroke
			(width 0.087376)
			(type default)
		)
		(layer "F.Cu")
	)
	(gr_line
		(start 223.08693 -47.371762)
		(end 223.212152 -47.24654)
		(stroke
			(width 0.087376)
			(type default)
		)
		(layer "F.Cu")
	)
	(gr_line
		(start 223.118934 -150.241762)
		(end 223.64319 -150.241762)
		(stroke
			(width 0.087376)
			(type default)
		)
		(layer "F.Cu")
	)
	(gr_line
		(start 223.132396 -480.190048)
		(end 224.199958 -480.190048)
		(stroke
			(width 0.087376)
			(type default)
		)
		(layer "F.Cu")
	)
	(gr_line
		(start 223.132396 -468.990172)
		(end 224.199958 -468.990172)
		(stroke
			(width 0.087376)
			(type default)
		)
		(layer "F.Cu")
	)
	(gr_line
		(start 223.132396 -467.390226)
		(end 224.199958 -467.390226)
		(stroke
			(width 0.087376)
			(type default)
		)
		(layer "F.Cu")
	)
	(gr_line
		(start 223.132396 -389.189976)
		(end 224.199958 -389.189976)
		(stroke
			(width 0.087376)
			(type default)
		)
		(layer "F.Cu")
	)
	(gr_line
		(start 223.132396 -386.790184)
		(end 224.199958 -386.790184)
		(stroke
			(width 0.087376)
			(type default)
		)
		(layer "F.Cu")
	)
	(gr_line
		(start 223.132396 -381.990092)
		(end 224.199958 -381.990092)
		(stroke
			(width 0.087376)
			(type default)
		)
		(layer "F.Cu")
	)
	(gr_line
		(start 223.132396 -377.19)
		(end 224.199958 -377.19)
		(stroke
			(width 0.087376)
			(type default)
		)
		(layer "F.Cu")
	)
	(gr_line
		(start 223.132396 -376.390154)
		(end 224.199958 -376.390154)
		(stroke
			(width 0.087376)
			(type default)
		)
		(layer "F.Cu")
	)
	(gr_line
		(start 223.132396 -366.78997)
		(end 224.199958 -366.78997)
		(stroke
			(width 0.087376)
			(type default)
		)
		(layer "F.Cu")
	)
	(gr_line
		(start 223.132396 -364.390178)
		(end 224.199958 -364.390178)
		(stroke
			(width 0.087376)
			(type default)
		)
		(layer "F.Cu")
	)
	(gr_line
		(start 223.132396 -286.189928)
		(end 224.199958 -286.189928)
		(stroke
			(width 0.087376)
			(type default)
		)
		(layer "F.Cu")
	)
	(gr_line
		(start 223.132396 -283.790136)
		(end 224.199958 -283.790136)
		(stroke
			(width 0.087376)
			(type default)
		)
		(layer "F.Cu")
	)
	(gr_line
		(start 223.132396 -281.39009)
		(end 224.199958 -281.39009)
		(stroke
			(width 0.087376)
			(type default)
		)
		(layer "F.Cu")
	)
	(gr_line
		(start 223.132396 -278.990044)
		(end 224.199958 -278.990044)
		(stroke
			(width 0.087376)
			(type default)
		)
		(layer "F.Cu")
	)
	(gr_line
		(start 223.132396 -273.390106)
		(end 224.199958 -273.390106)
		(stroke
			(width 0.087376)
			(type default)
		)
		(layer "F.Cu")
	)
	(gr_line
		(start 223.132396 -263.789922)
		(end 224.199958 -263.789922)
		(stroke
			(width 0.087376)
			(type default)
		)
		(layer "F.Cu")
	)
	(gr_line
		(start 223.132396 -262.990076)
		(end 224.199958 -262.990076)
		(stroke
			(width 0.087376)
			(type default)
		)
		(layer "F.Cu")
	)
	(gr_line
		(start 223.132396 -261.39013)
		(end 224.199958 -261.39013)
		(stroke
			(width 0.087376)
			(type default)
		)
		(layer "F.Cu")
	)
	(gr_line
		(start 223.132396 -258.189984)
		(end 224.199958 -258.189984)
		(stroke
			(width 0.087376)
			(type default)
		)
		(layer "F.Cu")
	)
	(gr_line
		(start 223.132396 -183.18988)
		(end 224.199958 -183.18988)
		(stroke
			(width 0.087376)
			(type default)
		)
		(layer "F.Cu")
	)
	(gr_line
		(start 223.132396 -170.390058)
		(end 224.199958 -170.390058)
		(stroke
			(width 0.087376)
			(type default)
		)
		(layer "F.Cu")
	)
	(gr_line
		(start 223.132396 -160.789874)
		(end 224.199958 -160.789874)
		(stroke
			(width 0.087376)
			(type default)
		)
		(layer "F.Cu")
	)
	(gr_line
		(start 223.132396 -159.990028)
		(end 224.199958 -159.990028)
		(stroke
			(width 0.087376)
			(type default)
		)
		(layer "F.Cu")
	)
	(gr_line
		(start 223.132396 -158.390082)
		(end 224.199958 -158.390082)
		(stroke
			(width 0.087376)
			(type default)
		)
		(layer "F.Cu")
	)
	(gr_line
		(start 223.132396 -80.189832)
		(end 224.199958 -80.189832)
		(stroke
			(width 0.087376)
			(type default)
		)
		(layer "F.Cu")
	)
	(gr_line
		(start 223.132396 -77.79004)
		(end 224.199958 -77.79004)
		(stroke
			(width 0.087376)
			(type default)
		)
		(layer "F.Cu")
	)
	(gr_line
		(start 223.132396 -75.389994)
		(end 224.199958 -75.389994)
		(stroke
			(width 0.087376)
			(type default)
		)
		(layer "F.Cu")
	)
	(gr_line
		(start 223.132396 -72.989948)
		(end 224.199958 -72.989948)
		(stroke
			(width 0.087376)
			(type default)
		)
		(layer "F.Cu")
	)
	(gr_line
		(start 223.132396 -67.39001)
		(end 224.199958 -67.39001)
		(stroke
			(width 0.087376)
			(type default)
		)
		(layer "F.Cu")
	)
	(gr_line
		(start 223.132396 -52.189888)
		(end 224.199958 -52.189888)
		(stroke
			(width 0.087376)
			(type default)
		)
		(layer "F.Cu")
	)
	(gr_line
		(start 223.13265 -484.19004)
		(end 224.199958 -484.19004)
		(stroke
			(width 0.087376)
			(type default)
		)
		(layer "F.Cu")
	)
	(gr_line
		(start 223.13265 -466.590126)
		(end 224.199958 -466.590126)
		(stroke
			(width 0.087376)
			(type default)
		)
		(layer "F.Cu")
	)
	(gr_line
		(start 223.13265 -363.590078)
		(end 224.199958 -363.590078)
		(stroke
			(width 0.087376)
			(type default)
		)
		(layer "F.Cu")
	)
	(gr_line
		(start 223.13265 -361.990132)
		(end 224.199958 -361.990132)
		(stroke
			(width 0.087376)
			(type default)
		)
		(layer "F.Cu")
	)
	(gr_line
		(start 223.13265 -260.59003)
		(end 224.199958 -260.59003)
		(stroke
			(width 0.087376)
			(type default)
		)
		(layer "F.Cu")
	)
	(gr_line
		(start 223.13265 -258.990084)
		(end 224.199958 -258.990084)
		(stroke
			(width 0.087376)
			(type default)
		)
		(layer "F.Cu")
	)
	(gr_line
		(start 223.13265 -172.78985)
		(end 224.199958 -172.78985)
		(stroke
			(width 0.087376)
			(type default)
		)
		(layer "F.Cu")
	)
	(gr_line
		(start 223.13265 -72.189848)
		(end 224.199958 -72.189848)
		(stroke
			(width 0.087376)
			(type default)
		)
		(layer "F.Cu")
	)
	(gr_line
		(start 223.13265 -52.989988)
		(end 224.199958 -52.989988)
		(stroke
			(width 0.087376)
			(type default)
		)
		(layer "F.Cu")
	)
	(gr_line
		(start 223.139 -492.190024)
		(end 224.199958 -492.190024)
		(stroke
			(width 0.087376)
			(type default)
		)
		(layer "F.Cu")
	)
	(gr_line
		(start 223.139 -491.390178)
		(end 224.199958 -491.390178)
		(stroke
			(width 0.087376)
			(type default)
		)
		(layer "F.Cu")
	)
	(gr_line
		(start 223.139 -489.790232)
		(end 224.199958 -489.790232)
		(stroke
			(width 0.087376)
			(type default)
		)
		(layer "F.Cu")
	)
	(gr_line
		(start 223.139 -488.990132)
		(end 224.199958 -488.990132)
		(stroke
			(width 0.087376)
			(type default)
		)
		(layer "F.Cu")
	)
	(gr_line
		(start 223.139 -484.99014)
		(end 224.199958 -484.99014)
		(stroke
			(width 0.087376)
			(type default)
		)
		(layer "F.Cu")
	)
	(gr_line
		(start 223.139 -482.590094)
		(end 224.199958 -482.590094)
		(stroke
			(width 0.087376)
			(type default)
		)
		(layer "F.Cu")
	)
	(gr_line
		(start 223.139 -481.789994)
		(end 224.199958 -481.789994)
		(stroke
			(width 0.087376)
			(type default)
		)
		(layer "F.Cu")
	)
	(gr_line
		(start 223.139 -479.390202)
		(end 224.199958 -479.390202)
		(stroke
			(width 0.087376)
			(type default)
		)
		(layer "F.Cu")
	)
	(gr_line
		(start 223.139 -388.39013)
		(end 224.199958 -388.39013)
		(stroke
			(width 0.087376)
			(type default)
		)
		(layer "F.Cu")
	)
	(gr_line
		(start 223.139 -385.990084)
		(end 224.199958 -385.990084)
		(stroke
			(width 0.087376)
			(type default)
		)
		(layer "F.Cu")
	)
	(gr_line
		(start 223.139 -384.390138)
		(end 224.199958 -384.390138)
		(stroke
			(width 0.087376)
			(type default)
		)
		(layer "F.Cu")
	)
	(gr_line
		(start 223.139 -383.590038)
		(end 224.199958 -383.590038)
		(stroke
			(width 0.087376)
			(type default)
		)
		(layer "F.Cu")
	)
	(gr_line
		(start 223.139 -381.189992)
		(end 224.199958 -381.189992)
		(stroke
			(width 0.087376)
			(type default)
		)
		(layer "F.Cu")
	)
	(gr_line
		(start 223.139 -379.590046)
		(end 224.199958 -379.590046)
		(stroke
			(width 0.087376)
			(type default)
		)
		(layer "F.Cu")
	)
	(gr_line
		(start 223.139 -378.789946)
		(end 224.199958 -378.789946)
		(stroke
			(width 0.087376)
			(type default)
		)
		(layer "F.Cu")
	)
	(gr_line
		(start 223.139 -365.990124)
		(end 224.199958 -365.990124)
		(stroke
			(width 0.087376)
			(type default)
		)
		(layer "F.Cu")
	)
	(gr_line
		(start 223.139 -361.190032)
		(end 224.199958 -361.190032)
		(stroke
			(width 0.087376)
			(type default)
		)
		(layer "F.Cu")
	)
	(gr_line
		(start 223.139 -285.390082)
		(end 224.199958 -285.390082)
		(stroke
			(width 0.087376)
			(type default)
		)
		(layer "F.Cu")
	)
	(gr_line
		(start 223.139 -282.990036)
		(end 224.199958 -282.990036)
		(stroke
			(width 0.087376)
			(type default)
		)
		(layer "F.Cu")
	)
	(gr_line
		(start 223.139 -280.58999)
		(end 224.199958 -280.58999)
		(stroke
			(width 0.087376)
			(type default)
		)
		(layer "F.Cu")
	)
	(gr_line
		(start 223.139 -278.189944)
		(end 224.199958 -278.189944)
		(stroke
			(width 0.087376)
			(type default)
		)
		(layer "F.Cu")
	)
	(gr_line
		(start 223.139 -276.589998)
		(end 224.199958 -276.589998)
		(stroke
			(width 0.087376)
			(type default)
		)
		(layer "F.Cu")
	)
	(gr_line
		(start 223.139 -275.789898)
		(end 224.199958 -275.789898)
		(stroke
			(width 0.087376)
			(type default)
		)
		(layer "F.Cu")
	)
	(gr_line
		(start 223.139 -274.189952)
		(end 224.199958 -274.189952)
		(stroke
			(width 0.087376)
			(type default)
		)
		(layer "F.Cu")
	)
	(gr_line
		(start 223.139 -182.390034)
		(end 224.199958 -182.390034)
		(stroke
			(width 0.087376)
			(type default)
		)
		(layer "F.Cu")
	)
	(gr_line
		(start 223.139 -180.790088)
		(end 224.199958 -180.790088)
		(stroke
			(width 0.087376)
			(type default)
		)
		(layer "F.Cu")
	)
	(gr_line
		(start 223.139 -179.989988)
		(end 224.199958 -179.989988)
		(stroke
			(width 0.087376)
			(type default)
		)
		(layer "F.Cu")
	)
	(gr_line
		(start 223.139 -178.390042)
		(end 224.199958 -178.390042)
		(stroke
			(width 0.087376)
			(type default)
		)
		(layer "F.Cu")
	)
	(gr_line
		(start 223.139 -177.589942)
		(end 224.199958 -177.589942)
		(stroke
			(width 0.087376)
			(type default)
		)
		(layer "F.Cu")
	)
	(gr_line
		(start 223.139 -175.989996)
		(end 224.199958 -175.989996)
		(stroke
			(width 0.087376)
			(type default)
		)
		(layer "F.Cu")
	)
	(gr_line
		(start 223.139 -175.189896)
		(end 224.199958 -175.189896)
		(stroke
			(width 0.087376)
			(type default)
		)
		(layer "F.Cu")
	)
	(gr_line
		(start 223.139 -173.58995)
		(end 224.199958 -173.58995)
		(stroke
			(width 0.087376)
			(type default)
		)
		(layer "F.Cu")
	)
	(gr_line
		(start 223.139 -171.189904)
		(end 224.199958 -171.189904)
		(stroke
			(width 0.087376)
			(type default)
		)
		(layer "F.Cu")
	)
	(gr_line
		(start 223.139 -157.589982)
		(end 224.199958 -157.589982)
		(stroke
			(width 0.087376)
			(type default)
		)
		(layer "F.Cu")
	)
	(gr_line
		(start 223.139 -79.389986)
		(end 224.199958 -79.389986)
		(stroke
			(width 0.087376)
			(type default)
		)
		(layer "F.Cu")
	)
	(gr_line
		(start 223.139 -76.98994)
		(end 224.199958 -76.98994)
		(stroke
			(width 0.087376)
			(type default)
		)
		(layer "F.Cu")
	)
	(gr_line
		(start 223.139 -74.589894)
		(end 224.199958 -74.589894)
		(stroke
			(width 0.087376)
			(type default)
		)
		(layer "F.Cu")
	)
	(gr_line
		(start 223.139 -70.589902)
		(end 224.199958 -70.589902)
		(stroke
			(width 0.087376)
			(type default)
		)
		(layer "F.Cu")
	)
	(gr_line
		(start 223.139 -68.189856)
		(end 224.199958 -68.189856)
		(stroke
			(width 0.087376)
			(type default)
		)
		(layer "F.Cu")
	)
	(gr_line
		(start 223.156018 -469.790018)
		(end 224.199958 -469.790018)
		(stroke
			(width 0.087376)
			(type default)
		)
		(layer "F.Cu")
	)
	(gr_line
		(start 223.266 -69.789802)
		(end 224.199958 -69.789802)
		(stroke
			(width 0.087376)
			(type default)
		)
		(layer "F.Cu")
	)
	(gr_line
		(start 223.298766 -149.808946)
		(end 223.463358 -149.808946)
		(stroke
			(width 0.087376)
			(type default)
		)
		(layer "F.Cu")
	)
	(gr_line
		(start 223.361758 -356.362762)
		(end 223.48698 -356.23754)
		(stroke
			(width 0.087376)
			(type default)
		)
		(layer "F.Cu")
	)
	(gr_line
		(start 223.64319 -150.241762)
		(end 223.768412 -150.11654)
		(stroke
			(width 0.087376)
			(type default)
		)
		(layer "F.Cu")
	)
	(gr_line
		(start 223.741488 -47.24654)
		(end 223.86671 -47.371762)
		(stroke
			(width 0.087376)
			(type default)
		)
		(layer "F.Cu")
	)
	(gr_line
		(start 223.86671 -47.371762)
		(end 224.390966 -47.371762)
		(stroke
			(width 0.087376)
			(type default)
		)
		(layer "F.Cu")
	)
	(gr_line
		(start 224.046542 -46.938946)
		(end 224.211134 -46.938946)
		(stroke
			(width 0.087376)
			(type default)
		)
		(layer "F.Cu")
	)
	(gr_line
		(start 224.297748 -150.11654)
		(end 224.42297 -150.241762)
		(stroke
			(width 0.087376)
			(type default)
		)
		(layer "F.Cu")
	)
	(gr_line
		(start 224.390966 -47.371762)
		(end 224.516188 -47.24654)
		(stroke
			(width 0.087376)
			(type default)
		)
		(layer "F.Cu")
	)
	(gr_line
		(start 224.42297 -150.241762)
		(end 224.947226 -150.241762)
		(stroke
			(width 0.087376)
			(type default)
		)
		(layer "F.Cu")
	)
	(gr_line
		(start 224.602802 -149.808946)
		(end 224.767394 -149.808946)
		(stroke
			(width 0.087376)
			(type default)
		)
		(layer "F.Cu")
	)
	(gr_line
		(start 224.947226 -150.241762)
		(end 225.072448 -150.11654)
		(stroke
			(width 0.087376)
			(type default)
		)
		(layer "F.Cu")
	)
	(gr_line
		(start 227.389944 -473.390214)
		(end 228.479604 -473.390214)
		(stroke
			(width 0.087376)
			(type default)
		)
		(layer "F.Cu")
	)
	(gr_line
		(start 227.389944 -472.590114)
		(end 228.473 -472.590114)
		(stroke
			(width 0.087376)
			(type default)
		)
		(layer "F.Cu")
	)
	(gr_line
		(start 227.389944 -370.390166)
		(end 228.479604 -370.390166)
		(stroke
			(width 0.087376)
			(type default)
		)
		(layer "F.Cu")
	)
	(gr_line
		(start 227.389944 -369.590066)
		(end 228.473 -369.590066)
		(stroke
			(width 0.087376)
			(type default)
		)
		(layer "F.Cu")
	)
	(gr_line
		(start 227.389944 -267.390118)
		(end 228.479604 -267.390118)
		(stroke
			(width 0.087376)
			(type default)
		)
		(layer "F.Cu")
	)
	(gr_line
		(start 227.389944 -266.590018)
		(end 228.473 -266.590018)
		(stroke
			(width 0.087376)
			(type default)
		)
		(layer "F.Cu")
	)
	(gr_line
		(start 227.389944 -164.39007)
		(end 228.479604 -164.39007)
		(stroke
			(width 0.087376)
			(type default)
		)
		(layer "F.Cu")
	)
	(gr_line
		(start 227.389944 -163.58997)
		(end 228.473 -163.58997)
		(stroke
			(width 0.087376)
			(type default)
		)
		(layer "F.Cu")
	)
	(gr_line
		(start 227.389944 -61.390022)
		(end 228.479604 -61.390022)
		(stroke
			(width 0.087376)
			(type default)
		)
		(layer "F.Cu")
	)
	(gr_line
		(start 227.389944 -60.589922)
		(end 228.473 -60.589922)
		(stroke
			(width 0.087376)
			(type default)
		)
		(layer "F.Cu")
	)
	(gr_line
		(start 228.473 -472.590114)
		(end 228.658928 -472.776042)
		(stroke
			(width 0.087376)
			(type default)
		)
		(layer "F.Cu")
	)
	(gr_line
		(start 228.473 -369.590066)
		(end 228.658928 -369.775994)
		(stroke
			(width 0.087376)
			(type default)
		)
		(layer "F.Cu")
	)
	(gr_line
		(start 228.473 -266.590018)
		(end 228.658928 -266.775946)
		(stroke
			(width 0.087376)
			(type default)
		)
		(layer "F.Cu")
	)
	(gr_line
		(start 228.473 -163.58997)
		(end 228.658928 -163.775898)
		(stroke
			(width 0.087376)
			(type default)
		)
		(layer "F.Cu")
	)
	(gr_line
		(start 228.473 -60.589922)
		(end 228.658928 -60.77585)
		(stroke
			(width 0.087376)
			(type default)
		)
		(layer "F.Cu")
	)
	(gr_line
		(start 228.479604 -473.390214)
		(end 228.658928 -473.21089)
		(stroke
			(width 0.087376)
			(type default)
		)
		(layer "F.Cu")
	)
	(gr_line
		(start 228.479604 -370.390166)
		(end 228.658928 -370.210842)
		(stroke
			(width 0.087376)
			(type default)
		)
		(layer "F.Cu")
	)
	(gr_line
		(start 228.479604 -267.390118)
		(end 228.658928 -267.210794)
		(stroke
			(width 0.087376)
			(type default)
		)
		(layer "F.Cu")
	)
	(gr_line
		(start 228.479604 -164.39007)
		(end 228.658928 -164.210746)
		(stroke
			(width 0.087376)
			(type default)
		)
		(layer "F.Cu")
	)
	(gr_line
		(start 228.479604 -61.390022)
		(end 228.658928 -61.210698)
		(stroke
			(width 0.087376)
			(type default)
		)
		(layer "F.Cu")
	)
	(gr_line
		(start 229.907084 -471.790268)
		(end 230.09606 -471.979244)
		(stroke
			(width 0.087376)
			(type default)
		)
		(layer "F.Cu")
	)
	(gr_line
		(start 229.907084 -368.79022)
		(end 230.09606 -368.979196)
		(stroke
			(width 0.087376)
			(type default)
		)
		(layer "F.Cu")
	)
	(gr_line
		(start 229.907084 -265.790172)
		(end 230.09606 -265.979148)
		(stroke
			(width 0.087376)
			(type default)
		)
		(layer "F.Cu")
	)
	(gr_line
		(start 229.907084 -162.790124)
		(end 230.09606 -162.9791)
		(stroke
			(width 0.087376)
			(type default)
		)
		(layer "F.Cu")
	)
	(gr_line
		(start 229.907084 -59.790076)
		(end 230.09606 -59.979052)
		(stroke
			(width 0.087376)
			(type default)
		)
		(layer "F.Cu")
	)
	(gr_line
		(start 230.293164 -151.861012)
		(end 230.664004 -152.231598)
		(stroke
			(width 0.087376)
			(type default)
		)
		(layer "F.Cu")
	)
	(gr_line
		(start 230.293164 -151.68372)
		(end 230.293164 -151.861012)
		(stroke
			(width 0.087376)
			(type default)
		)
		(layer "F.Cu")
	)
	(gr_line
		(start 230.344218 -48.406812)
		(end 230.715058 -48.777398)
		(stroke
			(width 0.087376)
			(type default)
		)
		(layer "F.Cu")
	)
	(gr_line
		(start 230.344218 -48.22952)
		(end 230.344218 -48.406812)
		(stroke
			(width 0.087376)
			(type default)
		)
		(layer "F.Cu")
	)
	(gr_line
		(start 230.530908 -471.979244)
		(end 230.719884 -471.790268)
		(stroke
			(width 0.087376)
			(type default)
		)
		(layer "F.Cu")
	)
	(gr_line
		(start 230.530908 -368.979196)
		(end 230.719884 -368.79022)
		(stroke
			(width 0.087376)
			(type default)
		)
		(layer "F.Cu")
	)
	(gr_line
		(start 230.530908 -265.979148)
		(end 230.719884 -265.790172)
		(stroke
			(width 0.087376)
			(type default)
		)
		(layer "F.Cu")
	)
	(gr_line
		(start 230.530908 -162.9791)
		(end 230.719884 -162.790124)
		(stroke
			(width 0.087376)
			(type default)
		)
		(layer "F.Cu")
	)
	(gr_line
		(start 230.530908 -59.979052)
		(end 230.719884 -59.790076)
		(stroke
			(width 0.087376)
			(type default)
		)
		(layer "F.Cu")
	)
	(gr_line
		(start 230.664004 -152.231598)
		(end 230.841042 -152.231598)
		(stroke
			(width 0.087376)
			(type default)
		)
		(layer "F.Cu")
	)
	(gr_line
		(start 230.715058 -48.777398)
		(end 230.892096 -48.777398)
		(stroke
			(width 0.087376)
			(type default)
		)
		(layer "F.Cu")
	)
	(gr_line
		(start 230.726488 -151.681942)
		(end 230.84282 -151.798274)
		(stroke
			(width 0.087376)
			(type default)
		)
		(layer "F.Cu")
	)
	(gr_line
		(start 230.777542 -48.227742)
		(end 230.893874 -48.344074)
		(stroke
			(width 0.087376)
			(type default)
		)
		(layer "F.Cu")
	)
	(gr_line
		(start 231.081072 -254.858012)
		(end 231.451658 -255.228852)
		(stroke
			(width 0.087376)
			(type default)
		)
		(layer "F.Cu")
	)
	(gr_line
		(start 231.081072 -254.680974)
		(end 231.081072 -254.858012)
		(stroke
			(width 0.087376)
			(type default)
		)
		(layer "F.Cu")
	)
	(gr_line
		(start 231.451658 -255.228852)
		(end 231.62895 -255.228852)
		(stroke
			(width 0.087376)
			(type default)
		)
		(layer "F.Cu")
	)
	(gr_line
		(start 231.514396 -254.679196)
		(end 231.630728 -254.795528)
		(stroke
			(width 0.087376)
			(type default)
		)
		(layer "F.Cu")
	)
	(gr_line
		(start 232.003092 -255.780032)
		(end 232.373932 -256.150872)
		(stroke
			(width 0.087376)
			(type default)
		)
		(layer "F.Cu")
	)
	(gr_line
		(start 232.003092 -255.602994)
		(end 232.003092 -255.780032)
		(stroke
			(width 0.087376)
			(type default)
		)
		(layer "F.Cu")
	)
	(gr_line
		(start 232.373932 -256.150872)
		(end 232.55097 -256.150872)
		(stroke
			(width 0.087376)
			(type default)
		)
		(layer "F.Cu")
	)
	(gr_line
		(start 232.436416 -255.601216)
		(end 232.552748 -255.717548)
		(stroke
			(width 0.087376)
			(type default)
		)
		(layer "F.Cu")
	)
	(gr_line
		(start 232.640632 -461.344772)
		(end 233.011472 -461.715612)
		(stroke
			(width 0.087376)
			(type default)
		)
		(layer "F.Cu")
	)
	(gr_line
		(start 232.640632 -461.167734)
		(end 232.640632 -461.344772)
		(stroke
			(width 0.087376)
			(type default)
		)
		(layer "F.Cu")
	)
	(gr_line
		(start 232.640632 -154.208226)
		(end 233.011472 -154.579066)
		(stroke
			(width 0.087376)
			(type default)
		)
		(layer "F.Cu")
	)
	(gr_line
		(start 232.640632 -154.031188)
		(end 232.640632 -154.208226)
		(stroke
			(width 0.087376)
			(type default)
		)
		(layer "F.Cu")
	)
	(gr_line
		(start 232.691686 -50.754026)
		(end 233.062526 -51.124866)
		(stroke
			(width 0.087376)
			(type default)
		)
		(layer "F.Cu")
	)
	(gr_line
		(start 232.691686 -50.576988)
		(end 232.691686 -50.754026)
		(stroke
			(width 0.087376)
			(type default)
		)
		(layer "F.Cu")
	)
	(gr_line
		(start 232.925112 -256.702306)
		(end 233.295952 -257.072892)
		(stroke
			(width 0.087376)
			(type default)
		)
		(layer "F.Cu")
	)
	(gr_line
		(start 232.925112 -256.525014)
		(end 232.925112 -256.702306)
		(stroke
			(width 0.087376)
			(type default)
		)
		(layer "F.Cu")
	)
	(gr_line
		(start 233.011472 -461.715612)
		(end 233.18851 -461.715612)
		(stroke
			(width 0.087376)
			(type default)
		)
		(layer "F.Cu")
	)
	(gr_line
		(start 233.011472 -154.579066)
		(end 233.18851 -154.579066)
		(stroke
			(width 0.087376)
			(type default)
		)
		(layer "F.Cu")
	)
	(gr_line
		(start 233.062526 -51.124866)
		(end 233.239564 -51.124866)
		(stroke
			(width 0.087376)
			(type default)
		)
		(layer "F.Cu")
	)
	(gr_line
		(start 233.073956 -461.165956)
		(end 233.190288 -461.282288)
		(stroke
			(width 0.087376)
			(type default)
		)
		(layer "F.Cu")
	)
	(gr_line
		(start 233.073956 -154.02941)
		(end 233.190288 -154.145742)
		(stroke
			(width 0.087376)
			(type default)
		)
		(layer "F.Cu")
	)
	(gr_line
		(start 233.12501 -50.57521)
		(end 233.241342 -50.691542)
		(stroke
			(width 0.087376)
			(type default)
		)
		(layer "F.Cu")
	)
	(gr_line
		(start 233.295952 -257.072892)
		(end 233.47299 -257.072892)
		(stroke
			(width 0.087376)
			(type default)
		)
		(layer "F.Cu")
	)
	(gr_line
		(start 233.358436 -256.523236)
		(end 233.474768 -256.639568)
		(stroke
			(width 0.087376)
			(type default)
		)
		(layer "F.Cu")
	)
	(gr_line
		(start 233.386884 -473.392246)
		(end 233.57586 -473.20327)
		(stroke
			(width 0.087376)
			(type default)
		)
		(layer "F.Cu")
	)
	(gr_line
		(start 233.386884 -472.579446)
		(end 233.57586 -472.768422)
		(stroke
			(width 0.087376)
			(type default)
		)
		(layer "F.Cu")
	)
	(gr_line
		(start 233.386884 -370.392198)
		(end 233.57586 -370.203222)
		(stroke
			(width 0.087376)
			(type default)
		)
		(layer "F.Cu")
	)
	(gr_line
		(start 233.386884 -369.579398)
		(end 233.57586 -369.768374)
		(stroke
			(width 0.087376)
			(type default)
		)
		(layer "F.Cu")
	)
	(gr_line
		(start 233.386884 -267.39215)
		(end 233.57586 -267.203174)
		(stroke
			(width 0.087376)
			(type default)
		)
		(layer "F.Cu")
	)
	(gr_line
		(start 233.386884 -266.57935)
		(end 233.57586 -266.768326)
		(stroke
			(width 0.087376)
			(type default)
		)
		(layer "F.Cu")
	)
	(gr_line
		(start 233.386884 -164.392102)
		(end 233.57586 -164.203126)
		(stroke
			(width 0.087376)
			(type default)
		)
		(layer "F.Cu")
	)
	(gr_line
		(start 233.386884 -163.579302)
		(end 233.57586 -163.768278)
		(stroke
			(width 0.087376)
			(type default)
		)
		(layer "F.Cu")
	)
	(gr_line
		(start 233.386884 -61.392054)
		(end 233.57586 -61.203078)
		(stroke
			(width 0.087376)
			(type default)
		)
		(layer "F.Cu")
	)
	(gr_line
		(start 233.386884 -60.579254)
		(end 233.57586 -60.76823)
		(stroke
			(width 0.087376)
			(type default)
		)
		(layer "F.Cu")
	)
	(gr_line
		(start 233.562652 -462.267046)
		(end 233.933492 -462.637632)
		(stroke
			(width 0.087376)
			(type default)
		)
		(layer "F.Cu")
	)
	(gr_line
		(start 233.562652 -462.089754)
		(end 233.562652 -462.267046)
		(stroke
			(width 0.087376)
			(type default)
		)
		(layer "F.Cu")
	)
	(gr_line
		(start 233.562652 -155.1305)
		(end 233.933492 -155.501086)
		(stroke
			(width 0.087376)
			(type default)
		)
		(layer "F.Cu")
	)
	(gr_line
		(start 233.562652 -154.953208)
		(end 233.562652 -155.1305)
		(stroke
			(width 0.087376)
			(type default)
		)
		(layer "F.Cu")
	)
	(gr_line
		(start 233.613706 -51.6763)
		(end 233.984546 -52.046886)
		(stroke
			(width 0.087376)
			(type default)
		)
		(layer "F.Cu")
	)
	(gr_line
		(start 233.613706 -51.499008)
		(end 233.613706 -51.6763)
		(stroke
			(width 0.087376)
			(type default)
		)
		(layer "F.Cu")
	)
	(gr_line
		(start 233.933492 -462.637632)
		(end 234.11053 -462.637632)
		(stroke
			(width 0.087376)
			(type default)
		)
		(layer "F.Cu")
	)
	(gr_line
		(start 233.933492 -155.501086)
		(end 234.11053 -155.501086)
		(stroke
			(width 0.087376)
			(type default)
		)
		(layer "F.Cu")
	)
	(gr_line
		(start 233.984546 -52.046886)
		(end 234.161584 -52.046886)
		(stroke
			(width 0.087376)
			(type default)
		)
		(layer "F.Cu")
	)
	(gr_line
		(start 233.995976 -462.087976)
		(end 234.112308 -462.204308)
		(stroke
			(width 0.087376)
			(type default)
		)
		(layer "F.Cu")
	)
	(gr_line
		(start 233.995976 -154.95143)
		(end 234.112308 -155.067762)
		(stroke
			(width 0.087376)
			(type default)
		)
		(layer "F.Cu")
	)
	(gr_line
		(start 234.04703 -51.49723)
		(end 234.163362 -51.613562)
		(stroke
			(width 0.087376)
			(type default)
		)
		(layer "F.Cu")
	)
	(gr_line
		(start 234.484926 -463.189066)
		(end 234.855512 -463.559906)
		(stroke
			(width 0.087376)
			(type default)
		)
		(layer "F.Cu")
	)
	(gr_line
		(start 234.484926 -463.012028)
		(end 234.484926 -463.189066)
		(stroke
			(width 0.087376)
			(type default)
		)
		(layer "F.Cu")
	)
	(gr_line
		(start 234.484926 -156.05252)
		(end 234.855512 -156.42336)
		(stroke
			(width 0.087376)
			(type default)
		)
		(layer "F.Cu")
	)
	(gr_line
		(start 234.484926 -155.875482)
		(end 234.484926 -156.05252)
		(stroke
			(width 0.087376)
			(type default)
		)
		(layer "F.Cu")
	)
	(gr_line
		(start 234.53598 -52.59832)
		(end 234.906566 -52.96916)
		(stroke
			(width 0.087376)
			(type default)
		)
		(layer "F.Cu")
	)
	(gr_line
		(start 234.53598 -52.421282)
		(end 234.53598 -52.59832)
		(stroke
			(width 0.087376)
			(type default)
		)
		(layer "F.Cu")
	)
	(gr_line
		(start 234.855512 -463.559906)
		(end 235.032804 -463.559906)
		(stroke
			(width 0.087376)
			(type default)
		)
		(layer "F.Cu")
	)
	(gr_line
		(start 234.855512 -156.42336)
		(end 235.032804 -156.42336)
		(stroke
			(width 0.087376)
			(type default)
		)
		(layer "F.Cu")
	)
	(gr_line
		(start 234.906566 -52.96916)
		(end 235.083858 -52.96916)
		(stroke
			(width 0.087376)
			(type default)
		)
		(layer "F.Cu")
	)
	(gr_line
		(start 234.91825 -463.01025)
		(end 235.034582 -463.126582)
		(stroke
			(width 0.087376)
			(type default)
		)
		(layer "F.Cu")
	)
	(gr_line
		(start 234.91825 -155.873704)
		(end 235.034582 -155.990036)
		(stroke
			(width 0.087376)
			(type default)
		)
		(layer "F.Cu")
	)
	(gr_line
		(start 234.969304 -52.419504)
		(end 235.085636 -52.535836)
		(stroke
			(width 0.087376)
			(type default)
		)
		(layer "F.Cu")
	)
	(gr_line
		(start 235.279184 -471.585036)
		(end 235.404406 -471.710258)
		(stroke
			(width 0.087376)
			(type default)
		)
		(layer "F.Cu")
	)
	(gr_line
		(start 235.279184 -471.06078)
		(end 235.279184 -471.585036)
		(stroke
			(width 0.087376)
			(type default)
		)
		(layer "F.Cu")
	)
	(gr_line
		(start 235.279184 -471.06078)
		(end 235.404406 -470.935558)
		(stroke
			(width 0.087376)
			(type default)
		)
		(layer "F.Cu")
	)
	(gr_line
		(start 235.279184 -470.281)
		(end 235.404406 -470.406222)
		(stroke
			(width 0.087376)
			(type default)
		)
		(layer "F.Cu")
	)
	(gr_line
		(start 235.279184 -469.756744)
		(end 235.279184 -470.281)
		(stroke
			(width 0.087376)
			(type default)
		)
		(layer "F.Cu")
	)
	(gr_line
		(start 235.279184 -469.756744)
		(end 235.404406 -469.631522)
		(stroke
			(width 0.087376)
			(type default)
		)
		(layer "F.Cu")
	)
	(gr_line
		(start 235.279184 -468.976964)
		(end 235.404406 -469.102186)
		(stroke
			(width 0.087376)
			(type default)
		)
		(layer "F.Cu")
	)
	(gr_line
		(start 235.279184 -468.452708)
		(end 235.279184 -468.976964)
		(stroke
			(width 0.087376)
			(type default)
		)
		(layer "F.Cu")
	)
	(gr_line
		(start 235.279184 -468.452708)
		(end 235.404406 -468.327486)
		(stroke
			(width 0.087376)
			(type default)
		)
		(layer "F.Cu")
	)
	(gr_line
		(start 235.279184 -264.227818)
		(end 235.404406 -264.35304)
		(stroke
			(width 0.087376)
			(type default)
		)
		(layer "F.Cu")
	)
	(gr_line
		(start 235.279184 -263.703562)
		(end 235.279184 -264.227818)
		(stroke
			(width 0.087376)
			(type default)
		)
		(layer "F.Cu")
	)
	(gr_line
		(start 235.279184 -263.703562)
		(end 235.404406 -263.57834)
		(stroke
			(width 0.087376)
			(type default)
		)
		(layer "F.Cu")
	)
	(gr_line
		(start 235.279184 -262.923782)
		(end 235.404406 -263.049004)
		(stroke
			(width 0.087376)
			(type default)
		)
		(layer "F.Cu")
	)
	(gr_line
		(start 235.279184 -262.399526)
		(end 235.279184 -262.923782)
		(stroke
			(width 0.087376)
			(type default)
		)
		(layer "F.Cu")
	)
	(gr_line
		(start 235.279184 -262.399526)
		(end 235.404406 -262.274304)
		(stroke
			(width 0.087376)
			(type default)
		)
		(layer "F.Cu")
	)
	(gr_line
		(start 235.279184 -261.619746)
		(end 235.404406 -261.744968)
		(stroke
			(width 0.087376)
			(type default)
		)
		(layer "F.Cu")
	)
	(gr_line
		(start 235.279184 -261.09549)
		(end 235.279184 -261.619746)
		(stroke
			(width 0.087376)
			(type default)
		)
		(layer "F.Cu")
	)
	(gr_line
		(start 235.279184 -261.09549)
		(end 235.404406 -260.970268)
		(stroke
			(width 0.087376)
			(type default)
		)
		(layer "F.Cu")
	)
	(gr_line
		(start 235.279184 -162.263836)
		(end 235.404406 -162.389058)
		(stroke
			(width 0.087376)
			(type default)
		)
		(layer "F.Cu")
	)
	(gr_line
		(start 235.279184 -161.73958)
		(end 235.279184 -162.263836)
		(stroke
			(width 0.087376)
			(type default)
		)
		(layer "F.Cu")
	)
	(gr_line
		(start 235.279184 -161.73958)
		(end 235.404406 -161.614358)
		(stroke
			(width 0.087376)
			(type default)
		)
		(layer "F.Cu")
	)
	(gr_line
		(start 235.279184 -160.9598)
		(end 235.404406 -161.085022)
		(stroke
			(width 0.087376)
			(type default)
		)
		(layer "F.Cu")
	)
	(gr_line
		(start 235.279184 -160.435544)
		(end 235.279184 -160.9598)
		(stroke
			(width 0.087376)
			(type default)
		)
		(layer "F.Cu")
	)
	(gr_line
		(start 235.279184 -160.435544)
		(end 235.404406 -160.310322)
		(stroke
			(width 0.087376)
			(type default)
		)
		(layer "F.Cu")
	)
	(gr_line
		(start 235.279184 -159.655764)
		(end 235.404406 -159.780986)
		(stroke
			(width 0.087376)
			(type default)
		)
		(layer "F.Cu")
	)
	(gr_line
		(start 235.279184 -159.131508)
		(end 235.279184 -159.655764)
		(stroke
			(width 0.087376)
			(type default)
		)
		(layer "F.Cu")
	)
	(gr_line
		(start 235.279184 -159.131508)
		(end 235.404406 -159.006286)
		(stroke
			(width 0.087376)
			(type default)
		)
		(layer "F.Cu")
	)
	(gr_line
		(start 235.330238 -59.53379)
		(end 235.45546 -59.659012)
		(stroke
			(width 0.087376)
			(type default)
		)
		(layer "F.Cu")
	)
	(gr_line
		(start 235.330238 -59.009534)
		(end 235.330238 -59.53379)
		(stroke
			(width 0.087376)
			(type default)
		)
		(layer "F.Cu")
	)
	(gr_line
		(start 235.330238 -59.009534)
		(end 235.45546 -58.884312)
		(stroke
			(width 0.087376)
			(type default)
		)
		(layer "F.Cu")
	)
	(gr_line
		(start 235.330238 -58.229754)
		(end 235.45546 -58.354976)
		(stroke
			(width 0.087376)
			(type default)
		)
		(layer "F.Cu")
	)
	(gr_line
		(start 235.330238 -57.705498)
		(end 235.330238 -58.229754)
		(stroke
			(width 0.087376)
			(type default)
		)
		(layer "F.Cu")
	)
	(gr_line
		(start 235.330238 -57.705498)
		(end 235.45546 -57.580276)
		(stroke
			(width 0.087376)
			(type default)
		)
		(layer "F.Cu")
	)
	(gr_line
		(start 235.330238 -56.925718)
		(end 235.45546 -57.05094)
		(stroke
			(width 0.087376)
			(type default)
		)
		(layer "F.Cu")
	)
	(gr_line
		(start 235.330238 -56.401462)
		(end 235.330238 -56.925718)
		(stroke
			(width 0.087376)
			(type default)
		)
		(layer "F.Cu")
	)
	(gr_line
		(start 235.330238 -56.401462)
		(end 235.45546 -56.27624)
		(stroke
			(width 0.087376)
			(type default)
		)
		(layer "F.Cu")
	)
	(gr_line
		(start 235.712 -471.240612)
		(end 235.712 -471.405204)
		(stroke
			(width 0.087376)
			(type default)
		)
		(layer "F.Cu")
	)
	(gr_line
		(start 235.712 -469.936576)
		(end 235.712 -470.101168)
		(stroke
			(width 0.087376)
			(type default)
		)
		(layer "F.Cu")
	)
	(gr_line
		(start 235.712 -468.63254)
		(end 235.712 -468.797132)
		(stroke
			(width 0.087376)
			(type default)
		)
		(layer "F.Cu")
	)
	(gr_line
		(start 235.712 -263.883394)
		(end 235.712 -264.047986)
		(stroke
			(width 0.087376)
			(type default)
		)
		(layer "F.Cu")
	)
	(gr_line
		(start 235.712 -262.579358)
		(end 235.712 -262.74395)
		(stroke
			(width 0.087376)
			(type default)
		)
		(layer "F.Cu")
	)
	(gr_line
		(start 235.712 -261.275322)
		(end 235.712 -261.439914)
		(stroke
			(width 0.087376)
			(type default)
		)
		(layer "F.Cu")
	)
	(gr_line
		(start 235.712 -161.919412)
		(end 235.712 -162.084004)
		(stroke
			(width 0.087376)
			(type default)
		)
		(layer "F.Cu")
	)
	(gr_line
		(start 235.712 -160.615376)
		(end 235.712 -160.779968)
		(stroke
			(width 0.087376)
			(type default)
		)
		(layer "F.Cu")
	)
	(gr_line
		(start 235.712 -159.31134)
		(end 235.712 -159.475932)
		(stroke
			(width 0.087376)
			(type default)
		)
		(layer "F.Cu")
	)
	(gr_line
		(start 235.763054 -59.189366)
		(end 235.763054 -59.353958)
		(stroke
			(width 0.087376)
			(type default)
		)
		(layer "F.Cu")
	)
	(gr_line
		(start 235.763054 -57.88533)
		(end 235.763054 -58.049922)
		(stroke
			(width 0.087376)
			(type default)
		)
		(layer "F.Cu")
	)
	(gr_line
		(start 235.763054 -56.581294)
		(end 235.763054 -56.745886)
		(stroke
			(width 0.087376)
			(type default)
		)
		(layer "F.Cu")
	)
	(gr_line
		(start 240.94567 -423.556684)
		(end 241.187986 -423.799)
		(stroke
			(width 0.085598)
			(type default)
		)
		(layer "F.Cu")
	)
	(gr_line
		(start 240.94567 -422.77157)
		(end 241.18824 -422.529)
		(stroke
			(width 0.085598)
			(type default)
		)
		(layer "F.Cu")
	)
	(gr_line
		(start 241.187986 -423.799)
		(end 241.6175 -423.799)
		(stroke
			(width 0.085598)
			(type default)
		)
		(layer "F.Cu")
	)
	(gr_line
		(start 241.18824 -422.529)
		(end 241.6175 -422.529)
		(stroke
			(width 0.085598)
			(type default)
		)
		(layer "F.Cu")
	)
	(gr_line
		(start 242.5065 -423.799)
		(end 243.5225 -423.799)
		(stroke
			(width 0.085598)
			(type default)
		)
		(layer "F.Cu")
	)
	(gr_line
		(start 242.5065 -422.529)
		(end 243.5225 -422.529)
		(stroke
			(width 0.085598)
			(type default)
		)
		(layer "F.Cu")
	)
	(gr_line
		(start 243.5225 -423.799)
		(end 243.586 -423.7355)
		(stroke
			(width 0.085598)
			(type default)
		)
		(layer "F.Cu")
	)
	(gr_line
		(start 243.5225 -422.529)
		(end 243.586 -422.5925)
		(stroke
			(width 0.085598)
			(type default)
		)
		(layer "F.Cu")
	)
	(gr_line
		(start 243.586 -423.7355)
		(end 243.76507 -423.55643)
		(stroke
			(width 0.085598)
			(type default)
		)
		(layer "F.Cu")
	)
	(gr_line
		(start 243.586 -422.5925)
		(end 243.76507 -422.77157)
		(stroke
			(width 0.085598)
			(type default)
		)
		(layer "F.Cu")
	)
	(gr_line
		(start 245.37543 -423.55643)
		(end 246.253 -424.434)
		(stroke
			(width 0.085598)
			(type default)
		)
		(layer "F.Cu")
	)
	(gr_line
		(start 245.37543 -422.77157)
		(end 246.253 -421.894)
		(stroke
			(width 0.085598)
			(type default)
		)
		(layer "F.Cu")
	)
	(gr_line
		(start 246.253 -424.434)
		(end 247.13057 -423.55643)
		(stroke
			(width 0.085598)
			(type default)
		)
		(layer "F.Cu")
	)
	(gr_line
		(start 246.253 -421.894)
		(end 247.13057 -422.77157)
		(stroke
			(width 0.085598)
			(type default)
		)
		(layer "F.Cu")
	)
	(gr_line
		(start 248.737882 -423.55643)
		(end 248.793 -423.611548)
		(stroke
			(width 0.085598)
			(type default)
		)
		(layer "F.Cu")
	)
	(gr_line
		(start 248.737882 -422.771316)
		(end 248.793 -422.716198)
		(stroke
			(width 0.085598)
			(type default)
		)
		(layer "F.Cu")
	)
	(gr_line
		(start 248.793 -423.611548)
		(end 248.793 -424.1165)
		(stroke
			(width 0.085598)
			(type default)
		)
		(layer "F.Cu")
	)
	(gr_line
		(start 248.793 -422.2115)
		(end 248.793 -422.716198)
		(stroke
			(width 0.085598)
			(type default)
		)
		(layer "F.Cu")
	)
	(gr_poly
		(pts
			(arc
				(start 0.999998 -488.391962)
				(mid 5.500116 -492.903779)
				(end 10.000234 -488.391962)
			)
			(xy 10.000234 -487.800142) (xy 7.500366 -487.800142)
			(arc
				(start 7.500366 -488.395772)
				(mid 5.500116 -490.404167)
				(end 3.499866 -488.395772)
			)
			(xy 3.499866 -487.800142) (xy 0.999998 -487.800142)
		)
		(stroke
			(width 0)
			(type solid)
		)
		(fill yes)
		(layer "B.Cu")
		(net "GND")
	)
	(gr_poly
		(pts
			(arc
				(start 3.999992 -71.491856)
				(mid 8.50011 -76.003673)
				(end 13.000228 -71.491856)
			)
			(xy 13.000228 -70.900036) (xy 10.50036 -70.900036)
			(arc
				(start 10.50036 -71.495666)
				(mid 8.50011 -73.504061)
				(end 6.49986 -71.495666)
			)
			(xy 6.49986 -70.900036) (xy 3.999992 -70.900036)
		)
		(stroke
			(width 0)
			(type solid)
		)
		(fill yes)
		(layer "B.Cu")
		(net "GND")
	)
	(gr_poly
		(pts
			(arc
				(start 29.499814 -4.49199)
				(mid 33.999932 -9.003807)
				(end 38.50005 -4.49199)
			)
			(xy 38.50005 -3.90017) (xy 36.000182 -3.90017)
			(arc
				(start 36.000182 -4.4958)
				(mid 33.999932 -6.504195)
				(end 31.999682 -4.4958)
			)
			(xy 31.999682 -3.90017) (xy 29.499814 -3.90017)
		)
		(stroke
			(width 0)
			(type solid)
		)
		(fill yes)
		(layer "B.Cu")
		(net "GND")
	)
	(gr_poly
		(pts
			(arc
				(start 65.499996 -483.489508)
				(mid 70.000114 -488.001325)
				(end 74.500232 -483.489508)
			)
			(xy 74.500232 -482.897688) (xy 72.000364 -482.897688)
			(arc
				(start 72.000364 -483.493318)
				(mid 70.000114 -485.501713)
				(end 67.999864 -483.493318)
			)
			(xy 67.999864 -482.897688) (xy 65.499996 -482.897688)
		)
		(stroke
			(width 0)
			(type solid)
		)
		(fill yes)
		(layer "B.Cu")
		(net "GND")
	)
	(gr_poly
		(pts
			(arc
				(start 65.499996 -276.489414)
				(mid 70.000114 -281.001231)
				(end 74.500232 -276.489414)
			)
			(xy 74.500232 -275.897594) (xy 72.000364 -275.897594)
			(arc
				(start 72.000364 -276.493224)
				(mid 70.000114 -278.501619)
				(end 67.999864 -276.493224)
			)
			(xy 67.999864 -275.897594) (xy 65.499996 -275.897594)
		)
		(stroke
			(width 0)
			(type solid)
		)
		(fill yes)
		(layer "B.Cu")
		(net "GND")
	)
	(gr_poly
		(pts
			(arc
				(start 65.499996 -173.989492)
				(mid 70.000114 -178.501309)
				(end 74.500232 -173.989492)
			)
			(xy 74.500232 -173.397672) (xy 72.000364 -173.397672)
			(arc
				(start 72.000364 -173.993302)
				(mid 70.000114 -176.001697)
				(end 67.999864 -173.993302)
			)
			(xy 67.999864 -173.397672) (xy 65.499996 -173.397672)
		)
		(stroke
			(width 0)
			(type solid)
		)
		(fill yes)
		(layer "B.Cu")
		(net "GND")
	)
	(gr_poly
		(pts
			(arc
				(start 65.499996 -70.991984)
				(mid 70.000114 -75.503801)
				(end 74.500232 -70.991984)
			)
			(xy 74.500232 -70.400164) (xy 72.000364 -70.400164)
			(arc
				(start 72.000364 -70.995794)
				(mid 70.000114 -73.004189)
				(end 67.999864 -70.995794)
			)
			(xy 67.999864 -70.400164) (xy 65.499996 -70.400164)
		)
		(stroke
			(width 0)
			(type solid)
		)
		(fill yes)
		(layer "B.Cu")
		(net "GND")
	)
	(gr_poly
		(pts
			(arc
				(start 248.999756 -483.489508)
				(mid 253.499874 -488.001325)
				(end 257.999992 -483.489508)
			)
			(xy 257.999992 -482.897688) (xy 255.500124 -482.897688)
			(arc
				(start 255.500124 -483.493318)
				(mid 253.499874 -485.501713)
				(end 251.499624 -483.493318)
			)
			(xy 251.499624 -482.897688) (xy 248.999756 -482.897688)
		)
		(stroke
			(width 0)
			(type solid)
		)
		(fill yes)
		(layer "B.Cu")
		(net "GND")
	)
	(gr_poly
		(pts
			(arc
				(start 248.999756 -274.98929)
				(mid 253.499874 -279.501107)
				(end 257.999992 -274.98929)
			)
			(xy 257.999992 -274.39747) (xy 255.500124 -274.39747)
			(arc
				(start 255.500124 -274.9931)
				(mid 253.499874 -277.001495)
				(end 251.499624 -274.9931)
			)
			(xy 251.499624 -274.39747) (xy 248.999756 -274.39747)
		)
		(stroke
			(width 0)
			(type solid)
		)
		(fill yes)
		(layer "B.Cu")
		(net "GND")
	)
	(gr_poly
		(pts
			(arc
				(start 248.999756 -174.489364)
				(mid 253.499874 -179.001181)
				(end 257.999992 -174.489364)
			)
			(xy 257.999992 -173.897544) (xy 255.500124 -173.897544)
			(arc
				(start 255.500124 -174.493174)
				(mid 253.499874 -176.501569)
				(end 251.499624 -174.493174)
			)
			(xy 251.499624 -173.897544) (xy 248.999756 -173.897544)
		)
		(stroke
			(width 0)
			(type solid)
		)
		(fill yes)
		(layer "B.Cu")
		(net "GND")
	)
	(gr_poly
		(pts
			(arc
				(start 248.999756 -41.489376)
				(mid 253.499874 -46.001193)
				(end 257.999992 -41.489376)
			)
			(xy 257.999992 -40.897556) (xy 255.500124 -40.897556)
			(arc
				(start 255.500124 -41.493186)
				(mid 253.499874 -43.501581)
				(end 251.499624 -41.493186)
			)
			(xy 251.499624 -40.897556) (xy 248.999756 -40.897556)
		)
		(stroke
			(width 0)
			(type solid)
		)
		(fill yes)
		(layer "B.Cu")
		(net "GND")
	)
	(gr_line
		(start 1.868932 -450.342)
		(end 3.552444 -450.342)
		(stroke
			(width 0.085598)
			(type default)
		)
		(layer "B.Cu")
	)
	(gr_line
		(start 1.868932 -449.5419)
		(end 3.5941 -449.5419)
		(stroke
			(width 0.085598)
			(type default)
		)
		(layer "B.Cu")
	)
	(gr_line
		(start 1.868932 -447.941954)
		(end 3.657854 -447.941954)
		(stroke
			(width 0.087376)
			(type default)
		)
		(layer "B.Cu")
	)
	(gr_line
		(start 1.868932 -447.141854)
		(end 3.658108 -447.141854)
		(stroke
			(width 0.087376)
			(type default)
		)
		(layer "B.Cu")
	)
	(gr_line
		(start 1.868932 -445.541908)
		(end 3.657854 -445.541908)
		(stroke
			(width 0.087376)
			(type default)
		)
		(layer "B.Cu")
	)
	(gr_line
		(start 1.868932 -444.741808)
		(end 3.658108 -444.741808)
		(stroke
			(width 0.087376)
			(type default)
		)
		(layer "B.Cu")
	)
	(gr_line
		(start 1.868932 -442.342016)
		(end 3.658108 -442.342016)
		(stroke
			(width 0.087376)
			(type default)
		)
		(layer "B.Cu")
	)
	(gr_line
		(start 1.868932 -441.541916)
		(end 3.657854 -441.541916)
		(stroke
			(width 0.087376)
			(type default)
		)
		(layer "B.Cu")
	)
	(gr_line
		(start 1.868932 -439.14187)
		(end 3.657854 -439.14187)
		(stroke
			(width 0.087376)
			(type default)
		)
		(layer "B.Cu")
	)
	(gr_line
		(start 1.868932 -438.342024)
		(end 3.657854 -438.342024)
		(stroke
			(width 0.087376)
			(type default)
		)
		(layer "B.Cu")
	)
	(gr_line
		(start 1.868932 -435.941978)
		(end 3.658108 -435.941978)
		(stroke
			(width 0.087376)
			(type default)
		)
		(layer "B.Cu")
	)
	(gr_line
		(start 1.868932 -435.141878)
		(end 3.657854 -435.141878)
		(stroke
			(width 0.087376)
			(type default)
		)
		(layer "B.Cu")
	)
	(gr_line
		(start 1.868932 -430.341786)
		(end 3.657854 -430.341786)
		(stroke
			(width 0.087376)
			(type default)
		)
		(layer "B.Cu")
	)
	(gr_line
		(start 1.868932 -429.54194)
		(end 3.657854 -429.54194)
		(stroke
			(width 0.087376)
			(type default)
		)
		(layer "B.Cu")
	)
	(gr_line
		(start 1.868932 -427.141894)
		(end 3.658108 -427.141894)
		(stroke
			(width 0.087376)
			(type default)
		)
		(layer "B.Cu")
	)
	(gr_line
		(start 1.868932 -426.341794)
		(end 3.657854 -426.341794)
		(stroke
			(width 0.087376)
			(type default)
		)
		(layer "B.Cu")
	)
	(gr_line
		(start 1.868932 -423.942002)
		(end 3.658108 -423.942002)
		(stroke
			(width 0.087376)
			(type default)
		)
		(layer "B.Cu")
	)
	(gr_line
		(start 1.868932 -423.141902)
		(end 3.657854 -423.141902)
		(stroke
			(width 0.087376)
			(type default)
		)
		(layer "B.Cu")
	)
	(gr_line
		(start 1.868932 -417.541964)
		(end 3.657854 -417.541964)
		(stroke
			(width 0.087376)
			(type default)
		)
		(layer "B.Cu")
	)
	(gr_line
		(start 1.868932 -416.741864)
		(end 3.658108 -416.741864)
		(stroke
			(width 0.087376)
			(type default)
		)
		(layer "B.Cu")
	)
	(gr_line
		(start 1.868932 -414.341818)
		(end 3.657854 -414.341818)
		(stroke
			(width 0.087376)
			(type default)
		)
		(layer "B.Cu")
	)
	(gr_line
		(start 1.868932 -413.541972)
		(end 3.657854 -413.541972)
		(stroke
			(width 0.087376)
			(type default)
		)
		(layer "B.Cu")
	)
	(gr_line
		(start 1.868932 -411.141926)
		(end 3.657854 -411.141926)
		(stroke
			(width 0.087376)
			(type default)
		)
		(layer "B.Cu")
	)
	(gr_line
		(start 1.868932 -410.341826)
		(end 3.658108 -410.341826)
		(stroke
			(width 0.087376)
			(type default)
		)
		(layer "B.Cu")
	)
	(gr_line
		(start 1.868932 -407.94178)
		(end 3.657854 -407.94178)
		(stroke
			(width 0.087376)
			(type default)
		)
		(layer "B.Cu")
	)
	(gr_line
		(start 1.868932 -407.141934)
		(end 3.657854 -407.141934)
		(stroke
			(width 0.087376)
			(type default)
		)
		(layer "B.Cu")
	)
	(gr_line
		(start 1.868932 -404.741888)
		(end 3.657854 -404.741888)
		(stroke
			(width 0.087376)
			(type default)
		)
		(layer "B.Cu")
	)
	(gr_line
		(start 1.868932 -403.941788)
		(end 3.658108 -403.941788)
		(stroke
			(width 0.087376)
			(type default)
		)
		(layer "B.Cu")
	)
	(gr_line
		(start 1.868932 -399.14195)
		(end 3.657854 -399.14195)
		(stroke
			(width 0.087376)
			(type default)
		)
		(layer "B.Cu")
	)
	(gr_line
		(start 1.868932 -398.34185)
		(end 3.658108 -398.34185)
		(stroke
			(width 0.087376)
			(type default)
		)
		(layer "B.Cu")
	)
	(gr_line
		(start 1.868932 -395.941804)
		(end 3.657854 -395.941804)
		(stroke
			(width 0.087376)
			(type default)
		)
		(layer "B.Cu")
	)
	(gr_line
		(start 1.868932 -395.141958)
		(end 3.657854 -395.141958)
		(stroke
			(width 0.087376)
			(type default)
		)
		(layer "B.Cu")
	)
	(gr_line
		(start 1.868932 -392.741912)
		(end 3.657854 -392.741912)
		(stroke
			(width 0.087376)
			(type default)
		)
		(layer "B.Cu")
	)
	(gr_line
		(start 1.868932 -391.941812)
		(end 3.658108 -391.941812)
		(stroke
			(width 0.087376)
			(type default)
		)
		(layer "B.Cu")
	)
	(gr_line
		(start 1.868932 -389.54202)
		(end 3.657854 -389.54202)
		(stroke
			(width 0.087376)
			(type default)
		)
		(layer "B.Cu")
	)
	(gr_line
		(start 1.868932 -388.74192)
		(end 3.658108 -388.74192)
		(stroke
			(width 0.087376)
			(type default)
		)
		(layer "B.Cu")
	)
	(gr_line
		(start 1.868932 -385.541774)
		(end 3.657854 -385.541774)
		(stroke
			(width 0.087376)
			(type default)
		)
		(layer "B.Cu")
	)
	(gr_line
		(start 1.868932 -384.741928)
		(end 3.808222 -384.741928)
		(stroke
			(width 0.087376)
			(type default)
		)
		(layer "B.Cu")
	)
	(gr_line
		(start 1.868932 -358.742234)
		(end 3.657854 -358.742234)
		(stroke
			(width 0.087376)
			(type default)
		)
		(layer "B.Cu")
	)
	(gr_line
		(start 1.868932 -357.942134)
		(end 3.658108 -357.942134)
		(stroke
			(width 0.087376)
			(type default)
		)
		(layer "B.Cu")
	)
	(gr_line
		(start 1.868932 -355.542088)
		(end 3.657854 -355.542088)
		(stroke
			(width 0.087376)
			(type default)
		)
		(layer "B.Cu")
	)
	(gr_line
		(start 1.868932 -354.741988)
		(end 3.658108 -354.741988)
		(stroke
			(width 0.087376)
			(type default)
		)
		(layer "B.Cu")
	)
	(gr_line
		(start 1.868932 -352.342196)
		(end 3.657854 -352.342196)
		(stroke
			(width 0.087376)
			(type default)
		)
		(layer "B.Cu")
	)
	(gr_line
		(start 1.868932 -351.542096)
		(end 3.658108 -351.542096)
		(stroke
			(width 0.087376)
			(type default)
		)
		(layer "B.Cu")
	)
	(gr_line
		(start 1.868932 -349.14205)
		(end 3.658108 -349.14205)
		(stroke
			(width 0.087376)
			(type default)
		)
		(layer "B.Cu")
	)
	(gr_line
		(start 1.868932 -348.342204)
		(end 3.658108 -348.342204)
		(stroke
			(width 0.087376)
			(type default)
		)
		(layer "B.Cu")
	)
	(gr_line
		(start 1.868932 -345.942158)
		(end 3.657854 -345.942158)
		(stroke
			(width 0.087376)
			(type default)
		)
		(layer "B.Cu")
	)
	(gr_line
		(start 1.868932 -345.142058)
		(end 3.651758 -345.142058)
		(stroke
			(width 0.087376)
			(type default)
		)
		(layer "B.Cu")
	)
	(gr_line
		(start 1.868932 -342.742012)
		(end 3.658108 -342.742012)
		(stroke
			(width 0.087376)
			(type default)
		)
		(layer "B.Cu")
	)
	(gr_line
		(start 1.868932 -341.942166)
		(end 3.658108 -341.942166)
		(stroke
			(width 0.087376)
			(type default)
		)
		(layer "B.Cu")
	)
	(gr_line
		(start 1.868932 -339.54212)
		(end 3.657854 -339.54212)
		(stroke
			(width 0.087376)
			(type default)
		)
		(layer "B.Cu")
	)
	(gr_line
		(start 1.868932 -338.74202)
		(end 3.658108 -338.74202)
		(stroke
			(width 0.087376)
			(type default)
		)
		(layer "B.Cu")
	)
	(gr_line
		(start 1.868932 -336.342228)
		(end 3.657854 -336.342228)
		(stroke
			(width 0.087376)
			(type default)
		)
		(layer "B.Cu")
	)
	(gr_line
		(start 1.868932 -335.542128)
		(end 3.658108 -335.542128)
		(stroke
			(width 0.087376)
			(type default)
		)
		(layer "B.Cu")
	)
	(gr_line
		(start 1.868932 -330.742036)
		(end 3.658108 -330.742036)
		(stroke
			(width 0.087376)
			(type default)
		)
		(layer "B.Cu")
	)
	(gr_line
		(start 1.868932 -329.94219)
		(end 3.658108 -329.94219)
		(stroke
			(width 0.087376)
			(type default)
		)
		(layer "B.Cu")
	)
	(gr_line
		(start 1.868932 -327.542144)
		(end 3.657854 -327.542144)
		(stroke
			(width 0.087376)
			(type default)
		)
		(layer "B.Cu")
	)
	(gr_line
		(start 1.868932 -326.742044)
		(end 3.658108 -326.742044)
		(stroke
			(width 0.087376)
			(type default)
		)
		(layer "B.Cu")
	)
	(gr_line
		(start 1.868932 -324.341998)
		(end 3.658108 -324.341998)
		(stroke
			(width 0.087376)
			(type default)
		)
		(layer "B.Cu")
	)
	(gr_line
		(start 1.868932 -323.542152)
		(end 3.658108 -323.542152)
		(stroke
			(width 0.087376)
			(type default)
		)
		(layer "B.Cu")
	)
	(gr_line
		(start 1.868932 -321.142106)
		(end 3.657854 -321.142106)
		(stroke
			(width 0.087376)
			(type default)
		)
		(layer "B.Cu")
	)
	(gr_line
		(start 1.868932 -320.342006)
		(end 3.658108 -320.342006)
		(stroke
			(width 0.087376)
			(type default)
		)
		(layer "B.Cu")
	)
	(gr_line
		(start 1.868932 -317.942214)
		(end 3.657854 -317.942214)
		(stroke
			(width 0.087376)
			(type default)
		)
		(layer "B.Cu")
	)
	(gr_line
		(start 1.868932 -317.142114)
		(end 3.658108 -317.142114)
		(stroke
			(width 0.087376)
			(type default)
		)
		(layer "B.Cu")
	)
	(gr_line
		(start 1.868932 -309.94223)
		(end 3.657854 -309.94223)
		(stroke
			(width 0.087376)
			(type default)
		)
		(layer "B.Cu")
	)
	(gr_line
		(start 1.868932 -309.14213)
		(end 3.658108 -309.14213)
		(stroke
			(width 0.087376)
			(type default)
		)
		(layer "B.Cu")
	)
	(gr_line
		(start 1.868932 -306.742084)
		(end 3.657854 -306.742084)
		(stroke
			(width 0.087376)
			(type default)
		)
		(layer "B.Cu")
	)
	(gr_line
		(start 1.868932 -305.941984)
		(end 3.658108 -305.941984)
		(stroke
			(width 0.087376)
			(type default)
		)
		(layer "B.Cu")
	)
	(gr_line
		(start 1.868932 -303.542192)
		(end 3.657854 -303.542192)
		(stroke
			(width 0.087376)
			(type default)
		)
		(layer "B.Cu")
	)
	(gr_line
		(start 1.868932 -302.742092)
		(end 3.658108 -302.742092)
		(stroke
			(width 0.087376)
			(type default)
		)
		(layer "B.Cu")
	)
	(gr_line
		(start 1.868932 -300.342046)
		(end 3.658108 -300.342046)
		(stroke
			(width 0.087376)
			(type default)
		)
		(layer "B.Cu")
	)
	(gr_line
		(start 1.868932 -299.5422)
		(end 3.658108 -299.5422)
		(stroke
			(width 0.087376)
			(type default)
		)
		(layer "B.Cu")
	)
	(gr_line
		(start 1.868932 -297.142154)
		(end 3.657854 -297.142154)
		(stroke
			(width 0.087376)
			(type default)
		)
		(layer "B.Cu")
	)
	(gr_line
		(start 1.868932 -296.342054)
		(end 3.658108 -296.342054)
		(stroke
			(width 0.087376)
			(type default)
		)
		(layer "B.Cu")
	)
	(gr_line
		(start 1.868932 -293.942008)
		(end 3.658108 -293.942008)
		(stroke
			(width 0.087376)
			(type default)
		)
		(layer "B.Cu")
	)
	(gr_line
		(start 1.868932 -293.142162)
		(end 3.658108 -293.142162)
		(stroke
			(width 0.087376)
			(type default)
		)
		(layer "B.Cu")
	)
	(gr_line
		(start 1.868932 -290.742116)
		(end 3.657854 -290.742116)
		(stroke
			(width 0.087376)
			(type default)
		)
		(layer "B.Cu")
	)
	(gr_line
		(start 1.868932 -289.942016)
		(end 3.658108 -289.942016)
		(stroke
			(width 0.087376)
			(type default)
		)
		(layer "B.Cu")
	)
	(gr_line
		(start 1.868932 -284.342078)
		(end 3.658108 -284.342078)
		(stroke
			(width 0.087376)
			(type default)
		)
		(layer "B.Cu")
	)
	(gr_line
		(start 1.868932 -283.542232)
		(end 3.658108 -283.542232)
		(stroke
			(width 0.087376)
			(type default)
		)
		(layer "B.Cu")
	)
	(gr_line
		(start 1.868932 -281.142186)
		(end 3.657854 -281.142186)
		(stroke
			(width 0.087376)
			(type default)
		)
		(layer "B.Cu")
	)
	(gr_line
		(start 1.868932 -280.342086)
		(end 3.658108 -280.342086)
		(stroke
			(width 0.087376)
			(type default)
		)
		(layer "B.Cu")
	)
	(gr_line
		(start 1.868932 -232.742232)
		(end 3.657854 -232.742232)
		(stroke
			(width 0.087376)
			(type default)
		)
		(layer "B.Cu")
	)
	(gr_line
		(start 1.868932 -231.942132)
		(end 3.658108 -231.942132)
		(stroke
			(width 0.087376)
			(type default)
		)
		(layer "B.Cu")
	)
	(gr_line
		(start 1.868932 -229.542086)
		(end 3.657854 -229.542086)
		(stroke
			(width 0.087376)
			(type default)
		)
		(layer "B.Cu")
	)
	(gr_line
		(start 1.868932 -228.741986)
		(end 3.658108 -228.741986)
		(stroke
			(width 0.087376)
			(type default)
		)
		(layer "B.Cu")
	)
	(gr_line
		(start 1.868932 -223.142048)
		(end 3.658108 -223.142048)
		(stroke
			(width 0.087376)
			(type default)
		)
		(layer "B.Cu")
	)
	(gr_line
		(start 1.868932 -222.342202)
		(end 3.658108 -222.342202)
		(stroke
			(width 0.087376)
			(type default)
		)
		(layer "B.Cu")
	)
	(gr_line
		(start 1.868932 -219.942156)
		(end 3.778504 -219.942156)
		(stroke
			(width 0.087376)
			(type default)
		)
		(layer "B.Cu")
	)
	(gr_line
		(start 1.868932 -219.142056)
		(end 3.661918 -219.142056)
		(stroke
			(width 0.087376)
			(type default)
		)
		(layer "B.Cu")
	)
	(gr_line
		(start 1.868932 -216.74201)
		(end 3.78333 -216.74201)
		(stroke
			(width 0.087376)
			(type default)
		)
		(layer "B.Cu")
	)
	(gr_line
		(start 1.868932 -215.942164)
		(end 3.658108 -215.942164)
		(stroke
			(width 0.087376)
			(type default)
		)
		(layer "B.Cu")
	)
	(gr_line
		(start 1.868932 -213.542118)
		(end 3.744722 -213.542118)
		(stroke
			(width 0.087376)
			(type default)
		)
		(layer "B.Cu")
	)
	(gr_line
		(start 1.868932 -212.742018)
		(end 3.658108 -212.742018)
		(stroke
			(width 0.087376)
			(type default)
		)
		(layer "B.Cu")
	)
	(gr_line
		(start 1.868932 -210.342226)
		(end 3.657854 -210.342226)
		(stroke
			(width 0.087376)
			(type default)
		)
		(layer "B.Cu")
	)
	(gr_line
		(start 1.868932 -209.542126)
		(end 3.658108 -209.542126)
		(stroke
			(width 0.087376)
			(type default)
		)
		(layer "B.Cu")
	)
	(gr_line
		(start 1.868932 -207.14208)
		(end 3.658108 -207.14208)
		(stroke
			(width 0.087376)
			(type default)
		)
		(layer "B.Cu")
	)
	(gr_line
		(start 1.868932 -206.342234)
		(end 3.658108 -206.342234)
		(stroke
			(width 0.087376)
			(type default)
		)
		(layer "B.Cu")
	)
	(gr_line
		(start 1.868932 -203.942188)
		(end 3.657854 -203.942188)
		(stroke
			(width 0.087376)
			(type default)
		)
		(layer "B.Cu")
	)
	(gr_line
		(start 1.868932 -203.142088)
		(end 3.658108 -203.142088)
		(stroke
			(width 0.087376)
			(type default)
		)
		(layer "B.Cu")
	)
	(gr_line
		(start 1.868932 -200.742042)
		(end 3.658108 -200.742042)
		(stroke
			(width 0.087376)
			(type default)
		)
		(layer "B.Cu")
	)
	(gr_line
		(start 1.868932 -199.942196)
		(end 3.658108 -199.942196)
		(stroke
			(width 0.087376)
			(type default)
		)
		(layer "B.Cu")
	)
	(gr_line
		(start 1.868932 -195.142104)
		(end 3.657854 -195.142104)
		(stroke
			(width 0.087376)
			(type default)
		)
		(layer "B.Cu")
	)
	(gr_line
		(start 1.868932 -194.342004)
		(end 3.658108 -194.342004)
		(stroke
			(width 0.087376)
			(type default)
		)
		(layer "B.Cu")
	)
	(gr_line
		(start 1.868932 -191.942212)
		(end 3.657854 -191.942212)
		(stroke
			(width 0.087376)
			(type default)
		)
		(layer "B.Cu")
	)
	(gr_line
		(start 1.868932 -191.142112)
		(end 3.658108 -191.142112)
		(stroke
			(width 0.087376)
			(type default)
		)
		(layer "B.Cu")
	)
	(gr_line
		(start 1.868932 -183.942228)
		(end 3.657854 -183.942228)
		(stroke
			(width 0.087376)
			(type default)
		)
		(layer "B.Cu")
	)
	(gr_line
		(start 1.868932 -183.142128)
		(end 3.658108 -183.142128)
		(stroke
			(width 0.087376)
			(type default)
		)
		(layer "B.Cu")
	)
	(gr_line
		(start 1.868932 -180.742082)
		(end 3.657854 -180.742082)
		(stroke
			(width 0.087376)
			(type default)
		)
		(layer "B.Cu")
	)
	(gr_line
		(start 1.868932 -179.941982)
		(end 3.658108 -179.941982)
		(stroke
			(width 0.087376)
			(type default)
		)
		(layer "B.Cu")
	)
	(gr_line
		(start 1.868932 -177.54219)
		(end 3.657854 -177.54219)
		(stroke
			(width 0.087376)
			(type default)
		)
		(layer "B.Cu")
	)
	(gr_line
		(start 1.868932 -176.74209)
		(end 3.658108 -176.74209)
		(stroke
			(width 0.087376)
			(type default)
		)
		(layer "B.Cu")
	)
	(gr_line
		(start 1.868932 -174.342044)
		(end 3.658108 -174.342044)
		(stroke
			(width 0.087376)
			(type default)
		)
		(layer "B.Cu")
	)
	(gr_line
		(start 1.868932 -173.542198)
		(end 3.658108 -173.542198)
		(stroke
			(width 0.087376)
			(type default)
		)
		(layer "B.Cu")
	)
	(gr_line
		(start 1.868932 -171.142152)
		(end 3.657854 -171.142152)
		(stroke
			(width 0.087376)
			(type default)
		)
		(layer "B.Cu")
	)
	(gr_line
		(start 1.868932 -170.342052)
		(end 3.658108 -170.342052)
		(stroke
			(width 0.087376)
			(type default)
		)
		(layer "B.Cu")
	)
	(gr_line
		(start 1.868932 -167.942006)
		(end 3.658108 -167.942006)
		(stroke
			(width 0.087376)
			(type default)
		)
		(layer "B.Cu")
	)
	(gr_line
		(start 1.868932 -167.14216)
		(end 3.658108 -167.14216)
		(stroke
			(width 0.087376)
			(type default)
		)
		(layer "B.Cu")
	)
	(gr_line
		(start 1.868932 -164.742114)
		(end 3.657854 -164.742114)
		(stroke
			(width 0.087376)
			(type default)
		)
		(layer "B.Cu")
	)
	(gr_line
		(start 1.868932 -163.942014)
		(end 3.658108 -163.942014)
		(stroke
			(width 0.087376)
			(type default)
		)
		(layer "B.Cu")
	)
	(gr_line
		(start 1.868932 -161.542222)
		(end 3.657854 -161.542222)
		(stroke
			(width 0.087376)
			(type default)
		)
		(layer "B.Cu")
	)
	(gr_line
		(start 1.868932 -160.742122)
		(end 3.658108 -160.742122)
		(stroke
			(width 0.087376)
			(type default)
		)
		(layer "B.Cu")
	)
	(gr_line
		(start 1.868932 -158.342076)
		(end 3.658108 -158.342076)
		(stroke
			(width 0.087376)
			(type default)
		)
		(layer "B.Cu")
	)
	(gr_line
		(start 1.868932 -157.54223)
		(end 3.658108 -157.54223)
		(stroke
			(width 0.087376)
			(type default)
		)
		(layer "B.Cu")
	)
	(gr_line
		(start 1.868932 -155.142184)
		(end 3.657854 -155.142184)
		(stroke
			(width 0.087376)
			(type default)
		)
		(layer "B.Cu")
	)
	(gr_line
		(start 1.868932 -154.342084)
		(end 3.658108 -154.342084)
		(stroke
			(width 0.087376)
			(type default)
		)
		(layer "B.Cu")
	)
	(gr_line
		(start 3.552444 -450.342)
		(end 3.580892 -450.313552)
		(stroke
			(width 0.085598)
			(type default)
		)
		(layer "B.Cu")
	)
	(gr_line
		(start 3.651758 -345.142058)
		(end 3.899154 -345.389454)
		(stroke
			(width 0.087376)
			(type default)
		)
		(layer "B.Cu")
	)
	(gr_line
		(start 3.657854 -447.941954)
		(end 3.84048 -447.759328)
		(stroke
			(width 0.087376)
			(type default)
		)
		(layer "B.Cu")
	)
	(gr_line
		(start 3.657854 -445.541908)
		(end 3.84048 -445.359282)
		(stroke
			(width 0.087376)
			(type default)
		)
		(layer "B.Cu")
	)
	(gr_line
		(start 3.657854 -441.541916)
		(end 3.84048 -441.724542)
		(stroke
			(width 0.087376)
			(type default)
		)
		(layer "B.Cu")
	)
	(gr_line
		(start 3.657854 -439.14187)
		(end 3.840226 -438.959498)
		(stroke
			(width 0.087376)
			(type default)
		)
		(layer "B.Cu")
	)
	(gr_line
		(start 3.657854 -438.342024)
		(end 3.840226 -438.524396)
		(stroke
			(width 0.087376)
			(type default)
		)
		(layer "B.Cu")
	)
	(gr_line
		(start 3.657854 -435.141878)
		(end 3.84048 -435.324504)
		(stroke
			(width 0.087376)
			(type default)
		)
		(layer "B.Cu")
	)
	(gr_line
		(start 3.657854 -430.341786)
		(end 3.840226 -430.159414)
		(stroke
			(width 0.087376)
			(type default)
		)
		(layer "B.Cu")
	)
	(gr_line
		(start 3.657854 -429.54194)
		(end 3.840226 -429.724312)
		(stroke
			(width 0.087376)
			(type default)
		)
		(layer "B.Cu")
	)
	(gr_line
		(start 3.657854 -426.341794)
		(end 3.84048 -426.52442)
		(stroke
			(width 0.087376)
			(type default)
		)
		(layer "B.Cu")
	)
	(gr_line
		(start 3.657854 -423.141902)
		(end 3.84048 -423.324528)
		(stroke
			(width 0.087376)
			(type default)
		)
		(layer "B.Cu")
	)
	(gr_line
		(start 3.657854 -417.541964)
		(end 3.84048 -417.359338)
		(stroke
			(width 0.087376)
			(type default)
		)
		(layer "B.Cu")
	)
	(gr_line
		(start 3.657854 -414.341818)
		(end 3.840226 -414.159446)
		(stroke
			(width 0.087376)
			(type default)
		)
		(layer "B.Cu")
	)
	(gr_line
		(start 3.657854 -413.541972)
		(end 3.840226 -413.724344)
		(stroke
			(width 0.087376)
			(type default)
		)
		(layer "B.Cu")
	)
	(gr_line
		(start 3.657854 -411.141926)
		(end 3.84048 -410.9593)
		(stroke
			(width 0.087376)
			(type default)
		)
		(layer "B.Cu")
	)
	(gr_line
		(start 3.657854 -407.94178)
		(end 3.840226 -407.759408)
		(stroke
			(width 0.087376)
			(type default)
		)
		(layer "B.Cu")
	)
	(gr_line
		(start 3.657854 -407.141934)
		(end 3.840226 -407.324306)
		(stroke
			(width 0.087376)
			(type default)
		)
		(layer "B.Cu")
	)
	(gr_line
		(start 3.657854 -404.741888)
		(end 3.84048 -404.559262)
		(stroke
			(width 0.087376)
			(type default)
		)
		(layer "B.Cu")
	)
	(gr_line
		(start 3.657854 -399.14195)
		(end 3.84048 -398.959324)
		(stroke
			(width 0.087376)
			(type default)
		)
		(layer "B.Cu")
	)
	(gr_line
		(start 3.657854 -395.941804)
		(end 3.840226 -395.759432)
		(stroke
			(width 0.087376)
			(type default)
		)
		(layer "B.Cu")
	)
	(gr_line
		(start 3.657854 -395.141958)
		(end 3.840226 -395.32433)
		(stroke
			(width 0.087376)
			(type default)
		)
		(layer "B.Cu")
	)
	(gr_line
		(start 3.657854 -392.741912)
		(end 3.84048 -392.559286)
		(stroke
			(width 0.087376)
			(type default)
		)
		(layer "B.Cu")
	)
	(gr_line
		(start 3.657854 -389.54202)
		(end 3.84048 -389.359394)
		(stroke
			(width 0.087376)
			(type default)
		)
		(layer "B.Cu")
	)
	(gr_line
		(start 3.657854 -385.541774)
		(end 3.80111 -385.398518)
		(stroke
			(width 0.087376)
			(type default)
		)
		(layer "B.Cu")
	)
	(gr_line
		(start 3.657854 -358.742234)
		(end 3.84048 -358.559608)
		(stroke
			(width 0.087376)
			(type default)
		)
		(layer "B.Cu")
	)
	(gr_line
		(start 3.657854 -355.542088)
		(end 3.84048 -355.359462)
		(stroke
			(width 0.087376)
			(type default)
		)
		(layer "B.Cu")
	)
	(gr_line
		(start 3.657854 -352.342196)
		(end 3.84048 -352.15957)
		(stroke
			(width 0.087376)
			(type default)
		)
		(layer "B.Cu")
	)
	(gr_line
		(start 3.657854 -345.942158)
		(end 4.002024 -345.697048)
		(stroke
			(width 0.087376)
			(type default)
		)
		(layer "B.Cu")
	)
	(gr_line
		(start 3.657854 -339.54212)
		(end 3.84048 -339.359494)
		(stroke
			(width 0.087376)
			(type default)
		)
		(layer "B.Cu")
	)
	(gr_line
		(start 3.657854 -336.342228)
		(end 3.84048 -336.159602)
		(stroke
			(width 0.087376)
			(type default)
		)
		(layer "B.Cu")
	)
	(gr_line
		(start 3.657854 -327.542144)
		(end 3.84048 -327.359518)
		(stroke
			(width 0.087376)
			(type default)
		)
		(layer "B.Cu")
	)
	(gr_line
		(start 3.657854 -321.142106)
		(end 3.84048 -320.95948)
		(stroke
			(width 0.087376)
			(type default)
		)
		(layer "B.Cu")
	)
	(gr_line
		(start 3.657854 -317.942214)
		(end 3.84048 -317.759588)
		(stroke
			(width 0.087376)
			(type default)
		)
		(layer "B.Cu")
	)
	(gr_line
		(start 3.657854 -309.94223)
		(end 3.84048 -309.759604)
		(stroke
			(width 0.087376)
			(type default)
		)
		(layer "B.Cu")
	)
	(gr_line
		(start 3.657854 -306.742084)
		(end 3.84048 -306.559458)
		(stroke
			(width 0.087376)
			(type default)
		)
		(layer "B.Cu")
	)
	(gr_line
		(start 3.657854 -303.542192)
		(end 3.84048 -303.359566)
		(stroke
			(width 0.087376)
			(type default)
		)
		(layer "B.Cu")
	)
	(gr_line
		(start 3.657854 -297.142154)
		(end 3.84048 -296.959528)
		(stroke
			(width 0.087376)
			(type default)
		)
		(layer "B.Cu")
	)
	(gr_line
		(start 3.657854 -290.742116)
		(end 3.84048 -290.55949)
		(stroke
			(width 0.087376)
			(type default)
		)
		(layer "B.Cu")
	)
	(gr_line
		(start 3.657854 -281.142186)
		(end 3.84048 -280.95956)
		(stroke
			(width 0.087376)
			(type default)
		)
		(layer "B.Cu")
	)
	(gr_line
		(start 3.657854 -232.742232)
		(end 3.84048 -232.559606)
		(stroke
			(width 0.087376)
			(type default)
		)
		(layer "B.Cu")
	)
	(gr_line
		(start 3.657854 -229.542086)
		(end 3.84048 -229.35946)
		(stroke
			(width 0.087376)
			(type default)
		)
		(layer "B.Cu")
	)
	(gr_line
		(start 3.657854 -210.342226)
		(end 3.84048 -210.1596)
		(stroke
			(width 0.087376)
			(type default)
		)
		(layer "B.Cu")
	)
	(gr_line
		(start 3.657854 -203.942188)
		(end 3.84048 -203.759562)
		(stroke
			(width 0.087376)
			(type default)
		)
		(layer "B.Cu")
	)
	(gr_line
		(start 3.657854 -195.142104)
		(end 3.84048 -194.959478)
		(stroke
			(width 0.087376)
			(type default)
		)
		(layer "B.Cu")
	)
	(gr_line
		(start 3.657854 -191.942212)
		(end 3.84048 -191.759586)
		(stroke
			(width 0.087376)
			(type default)
		)
		(layer "B.Cu")
	)
	(gr_line
		(start 3.657854 -183.942228)
		(end 3.84048 -183.759602)
		(stroke
			(width 0.087376)
			(type default)
		)
		(layer "B.Cu")
	)
	(gr_line
		(start 3.657854 -180.742082)
		(end 3.84048 -180.559456)
		(stroke
			(width 0.087376)
			(type default)
		)
		(layer "B.Cu")
	)
	(gr_line
		(start 3.657854 -177.54219)
		(end 3.84048 -177.359564)
		(stroke
			(width 0.087376)
			(type default)
		)
		(layer "B.Cu")
	)
	(gr_line
		(start 3.657854 -171.142152)
		(end 3.84048 -170.959526)
		(stroke
			(width 0.087376)
			(type default)
		)
		(layer "B.Cu")
	)
	(gr_line
		(start 3.657854 -164.742114)
		(end 3.84048 -164.559488)
		(stroke
			(width 0.087376)
			(type default)
		)
		(layer "B.Cu")
	)
	(gr_line
		(start 3.657854 -161.542222)
		(end 3.84048 -161.359596)
		(stroke
			(width 0.087376)
			(type default)
		)
		(layer "B.Cu")
	)
	(gr_line
		(start 3.657854 -155.142184)
		(end 3.84048 -154.959558)
		(stroke
			(width 0.087376)
			(type default)
		)
		(layer "B.Cu")
	)
	(gr_line
		(start 3.658108 -447.141854)
		(end 3.84048 -447.324226)
		(stroke
			(width 0.087376)
			(type default)
		)
		(layer "B.Cu")
	)
	(gr_line
		(start 3.658108 -444.741808)
		(end 3.84048 -444.92418)
		(stroke
			(width 0.087376)
			(type default)
		)
		(layer "B.Cu")
	)
	(gr_line
		(start 3.658108 -442.342016)
		(end 3.84048 -442.159644)
		(stroke
			(width 0.087376)
			(type default)
		)
		(layer "B.Cu")
	)
	(gr_line
		(start 3.658108 -435.941978)
		(end 3.84048 -435.759606)
		(stroke
			(width 0.087376)
			(type default)
		)
		(layer "B.Cu")
	)
	(gr_line
		(start 3.658108 -427.141894)
		(end 3.84048 -426.959522)
		(stroke
			(width 0.087376)
			(type default)
		)
		(layer "B.Cu")
	)
	(gr_line
		(start 3.658108 -423.942002)
		(end 3.84048 -423.75963)
		(stroke
			(width 0.087376)
			(type default)
		)
		(layer "B.Cu")
	)
	(gr_line
		(start 3.658108 -416.741864)
		(end 3.84048 -416.924236)
		(stroke
			(width 0.087376)
			(type default)
		)
		(layer "B.Cu")
	)
	(gr_line
		(start 3.658108 -410.341826)
		(end 3.84048 -410.524198)
		(stroke
			(width 0.087376)
			(type default)
		)
		(layer "B.Cu")
	)
	(gr_line
		(start 3.658108 -403.941788)
		(end 3.84048 -404.12416)
		(stroke
			(width 0.087376)
			(type default)
		)
		(layer "B.Cu")
	)
	(gr_line
		(start 3.658108 -398.34185)
		(end 3.84048 -398.524222)
		(stroke
			(width 0.087376)
			(type default)
		)
		(layer "B.Cu")
	)
	(gr_line
		(start 3.658108 -391.941812)
		(end 3.84048 -392.124184)
		(stroke
			(width 0.087376)
			(type default)
		)
		(layer "B.Cu")
	)
	(gr_line
		(start 3.658108 -388.74192)
		(end 3.84048 -388.924292)
		(stroke
			(width 0.087376)
			(type default)
		)
		(layer "B.Cu")
	)
	(gr_line
		(start 3.658108 -357.942134)
		(end 3.84048 -358.124506)
		(stroke
			(width 0.087376)
			(type default)
		)
		(layer "B.Cu")
	)
	(gr_line
		(start 3.658108 -354.741988)
		(end 3.84048 -354.92436)
		(stroke
			(width 0.087376)
			(type default)
		)
		(layer "B.Cu")
	)
	(gr_line
		(start 3.658108 -351.542096)
		(end 3.84048 -351.724468)
		(stroke
			(width 0.087376)
			(type default)
		)
		(layer "B.Cu")
	)
	(gr_line
		(start 3.658108 -349.14205)
		(end 3.84048 -348.959678)
		(stroke
			(width 0.087376)
			(type default)
		)
		(layer "B.Cu")
	)
	(gr_line
		(start 3.658108 -348.342204)
		(end 3.84048 -348.524576)
		(stroke
			(width 0.087376)
			(type default)
		)
		(layer "B.Cu")
	)
	(gr_line
		(start 3.658108 -342.742012)
		(end 4.007104 -342.497156)
		(stroke
			(width 0.087376)
			(type default)
		)
		(layer "B.Cu")
	)
	(gr_line
		(start 3.658108 -341.942166)
		(end 3.905504 -342.189562)
		(stroke
			(width 0.087376)
			(type default)
		)
		(layer "B.Cu")
	)
	(gr_line
		(start 3.658108 -338.74202)
		(end 3.84048 -338.924392)
		(stroke
			(width 0.087376)
			(type default)
		)
		(layer "B.Cu")
	)
	(gr_line
		(start 3.658108 -335.542128)
		(end 3.84048 -335.7245)
		(stroke
			(width 0.087376)
			(type default)
		)
		(layer "B.Cu")
	)
	(gr_line
		(start 3.658108 -330.742036)
		(end 3.84048 -330.559664)
		(stroke
			(width 0.087376)
			(type default)
		)
		(layer "B.Cu")
	)
	(gr_line
		(start 3.658108 -329.94219)
		(end 3.84048 -330.124562)
		(stroke
			(width 0.087376)
			(type default)
		)
		(layer "B.Cu")
	)
	(gr_line
		(start 3.658108 -326.742044)
		(end 3.84048 -326.924416)
		(stroke
			(width 0.087376)
			(type default)
		)
		(layer "B.Cu")
	)
	(gr_line
		(start 3.658108 -324.341998)
		(end 3.84048 -324.159626)
		(stroke
			(width 0.087376)
			(type default)
		)
		(layer "B.Cu")
	)
	(gr_line
		(start 3.658108 -323.542152)
		(end 3.84048 -323.724524)
		(stroke
			(width 0.087376)
			(type default)
		)
		(layer "B.Cu")
	)
	(gr_line
		(start 3.658108 -320.342006)
		(end 3.84048 -320.524378)
		(stroke
			(width 0.087376)
			(type default)
		)
		(layer "B.Cu")
	)
	(gr_line
		(start 3.658108 -317.142114)
		(end 3.84048 -317.324486)
		(stroke
			(width 0.087376)
			(type default)
		)
		(layer "B.Cu")
	)
	(gr_line
		(start 3.658108 -309.14213)
		(end 3.84048 -309.324502)
		(stroke
			(width 0.087376)
			(type default)
		)
		(layer "B.Cu")
	)
	(gr_line
		(start 3.658108 -305.941984)
		(end 3.84048 -306.124356)
		(stroke
			(width 0.087376)
			(type default)
		)
		(layer "B.Cu")
	)
	(gr_line
		(start 3.658108 -302.742092)
		(end 3.84048 -302.924464)
		(stroke
			(width 0.087376)
			(type default)
		)
		(layer "B.Cu")
	)
	(gr_line
		(start 3.658108 -300.342046)
		(end 3.84048 -300.159674)
		(stroke
			(width 0.087376)
			(type default)
		)
		(layer "B.Cu")
	)
	(gr_line
		(start 3.658108 -299.5422)
		(end 3.84048 -299.724572)
		(stroke
			(width 0.087376)
			(type default)
		)
		(layer "B.Cu")
	)
	(gr_line
		(start 3.658108 -296.342054)
		(end 3.84048 -296.524426)
		(stroke
			(width 0.087376)
			(type default)
		)
		(layer "B.Cu")
	)
	(gr_line
		(start 3.658108 -293.942008)
		(end 3.84048 -293.759636)
		(stroke
			(width 0.087376)
			(type default)
		)
		(layer "B.Cu")
	)
	(gr_line
		(start 3.658108 -293.142162)
		(end 3.84048 -293.324534)
		(stroke
			(width 0.087376)
			(type default)
		)
		(layer "B.Cu")
	)
	(gr_line
		(start 3.658108 -289.942016)
		(end 3.84048 -290.124388)
		(stroke
			(width 0.087376)
			(type default)
		)
		(layer "B.Cu")
	)
	(gr_line
		(start 3.658108 -284.342078)
		(end 3.84048 -284.159706)
		(stroke
			(width 0.087376)
			(type default)
		)
		(layer "B.Cu")
	)
	(gr_line
		(start 3.658108 -283.542232)
		(end 3.84048 -283.724604)
		(stroke
			(width 0.087376)
			(type default)
		)
		(layer "B.Cu")
	)
	(gr_line
		(start 3.658108 -280.342086)
		(end 3.84048 -280.524458)
		(stroke
			(width 0.087376)
			(type default)
		)
		(layer "B.Cu")
	)
	(gr_line
		(start 3.658108 -231.942132)
		(end 3.84048 -232.124504)
		(stroke
			(width 0.087376)
			(type default)
		)
		(layer "B.Cu")
	)
	(gr_line
		(start 3.658108 -228.741986)
		(end 3.84048 -228.924358)
		(stroke
			(width 0.087376)
			(type default)
		)
		(layer "B.Cu")
	)
	(gr_line
		(start 3.658108 -223.142048)
		(end 3.84048 -222.959676)
		(stroke
			(width 0.087376)
			(type default)
		)
		(layer "B.Cu")
	)
	(gr_line
		(start 3.658108 -222.342202)
		(end 3.84048 -222.524574)
		(stroke
			(width 0.087376)
			(type default)
		)
		(layer "B.Cu")
	)
	(gr_line
		(start 3.658108 -215.942164)
		(end 4.02971 -216.18702)
		(stroke
			(width 0.087376)
			(type default)
		)
		(layer "B.Cu")
	)
	(gr_line
		(start 3.658108 -212.742018)
		(end 4.002024 -212.986874)
		(stroke
			(width 0.087376)
			(type default)
		)
		(layer "B.Cu")
	)
	(gr_line
		(start 3.658108 -209.542126)
		(end 3.84048 -209.724498)
		(stroke
			(width 0.087376)
			(type default)
		)
		(layer "B.Cu")
	)
	(gr_line
		(start 3.658108 -207.14208)
		(end 3.84048 -206.959708)
		(stroke
			(width 0.087376)
			(type default)
		)
		(layer "B.Cu")
	)
	(gr_line
		(start 3.658108 -206.342234)
		(end 3.84048 -206.524606)
		(stroke
			(width 0.087376)
			(type default)
		)
		(layer "B.Cu")
	)
	(gr_line
		(start 3.658108 -203.142088)
		(end 3.84048 -203.32446)
		(stroke
			(width 0.087376)
			(type default)
		)
		(layer "B.Cu")
	)
	(gr_line
		(start 3.658108 -200.742042)
		(end 3.84048 -200.55967)
		(stroke
			(width 0.087376)
			(type default)
		)
		(layer "B.Cu")
	)
	(gr_line
		(start 3.658108 -199.942196)
		(end 3.84048 -200.124568)
		(stroke
			(width 0.087376)
			(type default)
		)
		(layer "B.Cu")
	)
	(gr_line
		(start 3.658108 -194.342004)
		(end 3.84048 -194.524376)
		(stroke
			(width 0.087376)
			(type default)
		)
		(layer "B.Cu")
	)
	(gr_line
		(start 3.658108 -191.142112)
		(end 3.84048 -191.324484)
		(stroke
			(width 0.087376)
			(type default)
		)
		(layer "B.Cu")
	)
	(gr_line
		(start 3.658108 -183.142128)
		(end 3.84048 -183.3245)
		(stroke
			(width 0.087376)
			(type default)
		)
		(layer "B.Cu")
	)
	(gr_line
		(start 3.658108 -179.941982)
		(end 3.84048 -180.124354)
		(stroke
			(width 0.087376)
			(type default)
		)
		(layer "B.Cu")
	)
	(gr_line
		(start 3.658108 -176.74209)
		(end 3.84048 -176.924462)
		(stroke
			(width 0.087376)
			(type default)
		)
		(layer "B.Cu")
	)
	(gr_line
		(start 3.658108 -174.342044)
		(end 3.84048 -174.159672)
		(stroke
			(width 0.087376)
			(type default)
		)
		(layer "B.Cu")
	)
	(gr_line
		(start 3.658108 -173.542198)
		(end 3.84048 -173.72457)
		(stroke
			(width 0.087376)
			(type default)
		)
		(layer "B.Cu")
	)
	(gr_line
		(start 3.658108 -170.342052)
		(end 3.84048 -170.524424)
		(stroke
			(width 0.087376)
			(type default)
		)
		(layer "B.Cu")
	)
	(gr_line
		(start 3.658108 -167.942006)
		(end 3.84048 -167.759634)
		(stroke
			(width 0.087376)
			(type default)
		)
		(layer "B.Cu")
	)
	(gr_line
		(start 3.658108 -167.14216)
		(end 3.84048 -167.324532)
		(stroke
			(width 0.087376)
			(type default)
		)
		(layer "B.Cu")
	)
	(gr_line
		(start 3.658108 -163.942014)
		(end 3.84048 -164.124386)
		(stroke
			(width 0.087376)
			(type default)
		)
		(layer "B.Cu")
	)
	(gr_line
		(start 3.658108 -160.742122)
		(end 3.84048 -160.924494)
		(stroke
			(width 0.087376)
			(type default)
		)
		(layer "B.Cu")
	)
	(gr_line
		(start 3.658108 -158.342076)
		(end 3.84048 -158.159704)
		(stroke
			(width 0.087376)
			(type default)
		)
		(layer "B.Cu")
	)
	(gr_line
		(start 3.658108 -157.54223)
		(end 3.84048 -157.724602)
		(stroke
			(width 0.087376)
			(type default)
		)
		(layer "B.Cu")
	)
	(gr_line
		(start 3.658108 -154.342084)
		(end 3.84048 -154.524456)
		(stroke
			(width 0.087376)
			(type default)
		)
		(layer "B.Cu")
	)
	(gr_line
		(start 3.661918 -219.142056)
		(end 4.010152 -219.38742)
		(stroke
			(width 0.087376)
			(type default)
		)
		(layer "B.Cu")
	)
	(gr_line
		(start 3.744722 -213.542118)
		(end 3.99034 -213.2965)
		(stroke
			(width 0.087376)
			(type default)
		)
		(layer "B.Cu")
	)
	(gr_line
		(start 3.778504 -219.942156)
		(end 4.023614 -219.697046)
		(stroke
			(width 0.087376)
			(type default)
		)
		(layer "B.Cu")
	)
	(gr_line
		(start 3.78333 -216.74201)
		(end 4.028186 -216.497154)
		(stroke
			(width 0.087376)
			(type default)
		)
		(layer "B.Cu")
	)
	(gr_line
		(start 3.80111 -385.208018)
		(end 3.80111 -385.398518)
		(stroke
			(width 0.087376)
			(type default)
		)
		(layer "B.Cu")
	)
	(gr_line
		(start 3.80111 -385.208018)
		(end 3.82016 -385.188968)
		(stroke
			(width 0.087376)
			(type default)
		)
		(layer "B.Cu")
	)
	(gr_line
		(start 3.808222 -384.741928)
		(end 3.82016 -384.753866)
		(stroke
			(width 0.087376)
			(type default)
		)
		(layer "B.Cu")
	)
	(gr_line
		(start 4.891024 -445.359028)
		(end 5.08 -445.548004)
		(stroke
			(width 0.087376)
			(type default)
		)
		(layer "B.Cu")
	)
	(gr_line
		(start 4.891024 -444.92418)
		(end 5.08 -444.735204)
		(stroke
			(width 0.087376)
			(type default)
		)
		(layer "B.Cu")
	)
	(gr_line
		(start 4.891024 -442.159136)
		(end 5.08 -442.348112)
		(stroke
			(width 0.087376)
			(type default)
		)
		(layer "B.Cu")
	)
	(gr_line
		(start 4.891024 -441.724288)
		(end 5.08 -441.535312)
		(stroke
			(width 0.087376)
			(type default)
		)
		(layer "B.Cu")
	)
	(gr_line
		(start 4.891024 -438.95899)
		(end 5.08 -439.147966)
		(stroke
			(width 0.087376)
			(type default)
		)
		(layer "B.Cu")
	)
	(gr_line
		(start 4.891024 -438.524142)
		(end 5.08 -438.335166)
		(stroke
			(width 0.087376)
			(type default)
		)
		(layer "B.Cu")
	)
	(gr_line
		(start 4.891024 -435.759098)
		(end 5.08 -435.948074)
		(stroke
			(width 0.087376)
			(type default)
		)
		(layer "B.Cu")
	)
	(gr_line
		(start 4.891024 -435.32425)
		(end 5.08 -435.135274)
		(stroke
			(width 0.087376)
			(type default)
		)
		(layer "B.Cu")
	)
	(gr_line
		(start 4.891024 -430.158906)
		(end 5.08 -430.347882)
		(stroke
			(width 0.087376)
			(type default)
		)
		(layer "B.Cu")
	)
	(gr_line
		(start 4.891024 -429.724058)
		(end 5.08 -429.535082)
		(stroke
			(width 0.087376)
			(type default)
		)
		(layer "B.Cu")
	)
	(gr_line
		(start 4.891024 -426.959014)
		(end 5.08 -427.14799)
		(stroke
			(width 0.087376)
			(type default)
		)
		(layer "B.Cu")
	)
	(gr_line
		(start 4.891024 -426.524166)
		(end 5.08 -426.33519)
		(stroke
			(width 0.087376)
			(type default)
		)
		(layer "B.Cu")
	)
	(gr_line
		(start 4.891024 -423.759122)
		(end 5.08 -423.948098)
		(stroke
			(width 0.087376)
			(type default)
		)
		(layer "B.Cu")
	)
	(gr_line
		(start 4.891024 -423.324274)
		(end 5.08 -423.135298)
		(stroke
			(width 0.087376)
			(type default)
		)
		(layer "B.Cu")
	)
	(gr_line
		(start 4.891024 -417.359084)
		(end 5.08 -417.54806)
		(stroke
			(width 0.087376)
			(type default)
		)
		(layer "B.Cu")
	)
	(gr_line
		(start 4.891024 -416.924236)
		(end 5.08 -416.73526)
		(stroke
			(width 0.087376)
			(type default)
		)
		(layer "B.Cu")
	)
	(gr_line
		(start 4.891024 -414.158938)
		(end 5.08 -414.347914)
		(stroke
			(width 0.087376)
			(type default)
		)
		(layer "B.Cu")
	)
	(gr_line
		(start 4.891024 -413.72409)
		(end 5.08 -413.535114)
		(stroke
			(width 0.087376)
			(type default)
		)
		(layer "B.Cu")
	)
	(gr_line
		(start 4.891024 -410.959046)
		(end 5.08 -411.148022)
		(stroke
			(width 0.087376)
			(type default)
		)
		(layer "B.Cu")
	)
	(gr_line
		(start 4.891024 -410.524198)
		(end 5.08 -410.335222)
		(stroke
			(width 0.087376)
			(type default)
		)
		(layer "B.Cu")
	)
	(gr_line
		(start 4.891024 -407.7589)
		(end 5.08 -407.947876)
		(stroke
			(width 0.087376)
			(type default)
		)
		(layer "B.Cu")
	)
	(gr_line
		(start 4.891024 -407.324052)
		(end 5.08 -407.135076)
		(stroke
			(width 0.087376)
			(type default)
		)
		(layer "B.Cu")
	)
	(gr_line
		(start 4.891024 -404.559008)
		(end 5.08 -404.747984)
		(stroke
			(width 0.087376)
			(type default)
		)
		(layer "B.Cu")
	)
	(gr_line
		(start 4.891024 -404.12416)
		(end 5.08 -403.935184)
		(stroke
			(width 0.087376)
			(type default)
		)
		(layer "B.Cu")
	)
	(gr_line
		(start 4.891024 -398.95907)
		(end 5.08 -399.148046)
		(stroke
			(width 0.087376)
			(type default)
		)
		(layer "B.Cu")
	)
	(gr_line
		(start 4.891024 -398.524222)
		(end 5.08 -398.335246)
		(stroke
			(width 0.087376)
			(type default)
		)
		(layer "B.Cu")
	)
	(gr_line
		(start 4.891024 -395.758924)
		(end 5.08 -395.9479)
		(stroke
			(width 0.087376)
			(type default)
		)
		(layer "B.Cu")
	)
	(gr_line
		(start 4.891024 -395.324076)
		(end 5.08 -395.1351)
		(stroke
			(width 0.087376)
			(type default)
		)
		(layer "B.Cu")
	)
	(gr_line
		(start 4.891024 -392.559032)
		(end 5.08 -392.748008)
		(stroke
			(width 0.087376)
			(type default)
		)
		(layer "B.Cu")
	)
	(gr_line
		(start 4.891024 -392.124184)
		(end 5.08 -391.935208)
		(stroke
			(width 0.087376)
			(type default)
		)
		(layer "B.Cu")
	)
	(gr_line
		(start 4.891024 -389.35914)
		(end 5.08 -389.548116)
		(stroke
			(width 0.087376)
			(type default)
		)
		(layer "B.Cu")
	)
	(gr_line
		(start 4.891024 -388.924292)
		(end 5.08 -388.735316)
		(stroke
			(width 0.087376)
			(type default)
		)
		(layer "B.Cu")
	)
	(gr_line
		(start 4.891024 -358.559354)
		(end 5.08 -358.74833)
		(stroke
			(width 0.087376)
			(type default)
		)
		(layer "B.Cu")
	)
	(gr_line
		(start 4.891024 -358.124506)
		(end 5.08 -357.93553)
		(stroke
			(width 0.087376)
			(type default)
		)
		(layer "B.Cu")
	)
	(gr_line
		(start 4.891024 -355.359208)
		(end 5.08 -355.548184)
		(stroke
			(width 0.087376)
			(type default)
		)
		(layer "B.Cu")
	)
	(gr_line
		(start 4.891024 -354.92436)
		(end 5.08 -354.735384)
		(stroke
			(width 0.087376)
			(type default)
		)
		(layer "B.Cu")
	)
	(gr_line
		(start 4.891024 -352.159316)
		(end 5.08 -352.348292)
		(stroke
			(width 0.087376)
			(type default)
		)
		(layer "B.Cu")
	)
	(gr_line
		(start 4.891024 -351.724468)
		(end 5.08 -351.535492)
		(stroke
			(width 0.087376)
			(type default)
		)
		(layer "B.Cu")
	)
	(gr_line
		(start 4.891024 -348.95917)
		(end 5.08 -349.148146)
		(stroke
			(width 0.087376)
			(type default)
		)
		(layer "B.Cu")
	)
	(gr_line
		(start 4.891024 -348.524322)
		(end 5.08 -348.335346)
		(stroke
			(width 0.087376)
			(type default)
		)
		(layer "B.Cu")
	)
	(gr_line
		(start 4.891024 -345.759278)
		(end 5.08 -345.948254)
		(stroke
			(width 0.087376)
			(type default)
		)
		(layer "B.Cu")
	)
	(gr_line
		(start 4.891024 -345.32443)
		(end 5.08 -345.135454)
		(stroke
			(width 0.087376)
			(type default)
		)
		(layer "B.Cu")
	)
	(gr_line
		(start 4.891024 -342.559132)
		(end 5.08 -342.748108)
		(stroke
			(width 0.087376)
			(type default)
		)
		(layer "B.Cu")
	)
	(gr_line
		(start 4.891024 -342.124284)
		(end 5.08 -341.935308)
		(stroke
			(width 0.087376)
			(type default)
		)
		(layer "B.Cu")
	)
	(gr_line
		(start 4.891024 -339.35924)
		(end 5.08 -339.548216)
		(stroke
			(width 0.087376)
			(type default)
		)
		(layer "B.Cu")
	)
	(gr_line
		(start 4.891024 -338.924392)
		(end 5.08 -338.735416)
		(stroke
			(width 0.087376)
			(type default)
		)
		(layer "B.Cu")
	)
	(gr_line
		(start 4.891024 -336.159348)
		(end 5.08 -336.348324)
		(stroke
			(width 0.087376)
			(type default)
		)
		(layer "B.Cu")
	)
	(gr_line
		(start 4.891024 -335.7245)
		(end 5.08 -335.535524)
		(stroke
			(width 0.087376)
			(type default)
		)
		(layer "B.Cu")
	)
	(gr_line
		(start 4.891024 -330.559156)
		(end 5.08 -330.748132)
		(stroke
			(width 0.087376)
			(type default)
		)
		(layer "B.Cu")
	)
	(gr_line
		(start 4.891024 -330.124308)
		(end 5.08 -329.935332)
		(stroke
			(width 0.087376)
			(type default)
		)
		(layer "B.Cu")
	)
	(gr_line
		(start 4.891024 -327.359264)
		(end 5.08 -327.54824)
		(stroke
			(width 0.087376)
			(type default)
		)
		(layer "B.Cu")
	)
	(gr_line
		(start 4.891024 -326.924416)
		(end 5.08 -326.73544)
		(stroke
			(width 0.087376)
			(type default)
		)
		(layer "B.Cu")
	)
	(gr_line
		(start 4.891024 -324.159118)
		(end 5.08 -324.348094)
		(stroke
			(width 0.087376)
			(type default)
		)
		(layer "B.Cu")
	)
	(gr_line
		(start 4.891024 -323.72427)
		(end 5.08 -323.535294)
		(stroke
			(width 0.087376)
			(type default)
		)
		(layer "B.Cu")
	)
	(gr_line
		(start 4.891024 -320.959226)
		(end 5.08 -321.148202)
		(stroke
			(width 0.087376)
			(type default)
		)
		(layer "B.Cu")
	)
	(gr_line
		(start 4.891024 -320.524378)
		(end 5.08 -320.335402)
		(stroke
			(width 0.087376)
			(type default)
		)
		(layer "B.Cu")
	)
	(gr_line
		(start 4.891024 -317.759334)
		(end 5.08 -317.94831)
		(stroke
			(width 0.087376)
			(type default)
		)
		(layer "B.Cu")
	)
	(gr_line
		(start 4.891024 -317.324486)
		(end 5.08 -317.13551)
		(stroke
			(width 0.087376)
			(type default)
		)
		(layer "B.Cu")
	)
	(gr_line
		(start 4.891024 -309.75935)
		(end 5.08 -309.948326)
		(stroke
			(width 0.087376)
			(type default)
		)
		(layer "B.Cu")
	)
	(gr_line
		(start 4.891024 -309.324502)
		(end 5.08 -309.135526)
		(stroke
			(width 0.087376)
			(type default)
		)
		(layer "B.Cu")
	)
	(gr_line
		(start 4.891024 -306.559204)
		(end 5.08 -306.74818)
		(stroke
			(width 0.087376)
			(type default)
		)
		(layer "B.Cu")
	)
	(gr_line
		(start 4.891024 -306.124356)
		(end 5.08 -305.93538)
		(stroke
			(width 0.087376)
			(type default)
		)
		(layer "B.Cu")
	)
	(gr_line
		(start 4.891024 -303.359312)
		(end 5.08 -303.548288)
		(stroke
			(width 0.087376)
			(type default)
		)
		(layer "B.Cu")
	)
	(gr_line
		(start 4.891024 -302.924464)
		(end 5.08 -302.735488)
		(stroke
			(width 0.087376)
			(type default)
		)
		(layer "B.Cu")
	)
	(gr_line
		(start 4.891024 -300.159166)
		(end 5.08 -300.348142)
		(stroke
			(width 0.087376)
			(type default)
		)
		(layer "B.Cu")
	)
	(gr_line
		(start 4.891024 -299.724318)
		(end 5.08 -299.535342)
		(stroke
			(width 0.087376)
			(type default)
		)
		(layer "B.Cu")
	)
	(gr_line
		(start 4.891024 -296.959274)
		(end 5.08 -297.14825)
		(stroke
			(width 0.087376)
			(type default)
		)
		(layer "B.Cu")
	)
	(gr_line
		(start 4.891024 -296.524426)
		(end 5.08 -296.33545)
		(stroke
			(width 0.087376)
			(type default)
		)
		(layer "B.Cu")
	)
	(gr_line
		(start 4.891024 -293.759128)
		(end 5.08 -293.948104)
		(stroke
			(width 0.087376)
			(type default)
		)
		(layer "B.Cu")
	)
	(gr_line
		(start 4.891024 -293.32428)
		(end 5.08 -293.135304)
		(stroke
			(width 0.087376)
			(type default)
		)
		(layer "B.Cu")
	)
	(gr_line
		(start 4.891024 -290.559236)
		(end 5.08 -290.748212)
		(stroke
			(width 0.087376)
			(type default)
		)
		(layer "B.Cu")
	)
	(gr_line
		(start 4.891024 -290.124388)
		(end 5.08 -289.935412)
		(stroke
			(width 0.087376)
			(type default)
		)
		(layer "B.Cu")
	)
	(gr_line
		(start 4.891024 -284.159198)
		(end 5.08 -284.348174)
		(stroke
			(width 0.087376)
			(type default)
		)
		(layer "B.Cu")
	)
	(gr_line
		(start 4.891024 -283.72435)
		(end 5.08 -283.535374)
		(stroke
			(width 0.087376)
			(type default)
		)
		(layer "B.Cu")
	)
	(gr_line
		(start 4.891024 -280.959306)
		(end 5.08 -281.148282)
		(stroke
			(width 0.087376)
			(type default)
		)
		(layer "B.Cu")
	)
	(gr_line
		(start 4.891024 -280.524458)
		(end 5.08 -280.335482)
		(stroke
			(width 0.087376)
			(type default)
		)
		(layer "B.Cu")
	)
	(gr_line
		(start 4.891024 -232.559352)
		(end 5.08 -232.748328)
		(stroke
			(width 0.087376)
			(type default)
		)
		(layer "B.Cu")
	)
	(gr_line
		(start 4.891024 -232.124504)
		(end 5.08 -231.935528)
		(stroke
			(width 0.087376)
			(type default)
		)
		(layer "B.Cu")
	)
	(gr_line
		(start 4.891024 -229.359206)
		(end 5.08 -229.548182)
		(stroke
			(width 0.087376)
			(type default)
		)
		(layer "B.Cu")
	)
	(gr_line
		(start 4.891024 -228.924358)
		(end 5.08 -228.735382)
		(stroke
			(width 0.087376)
			(type default)
		)
		(layer "B.Cu")
	)
	(gr_line
		(start 4.891024 -222.959168)
		(end 5.08 -223.148144)
		(stroke
			(width 0.087376)
			(type default)
		)
		(layer "B.Cu")
	)
	(gr_line
		(start 4.891024 -222.52432)
		(end 5.08 -222.335344)
		(stroke
			(width 0.087376)
			(type default)
		)
		(layer "B.Cu")
	)
	(gr_line
		(start 4.891024 -219.759276)
		(end 5.08 -219.948252)
		(stroke
			(width 0.087376)
			(type default)
		)
		(layer "B.Cu")
	)
	(gr_line
		(start 4.891024 -219.324428)
		(end 5.08 -219.135452)
		(stroke
			(width 0.087376)
			(type default)
		)
		(layer "B.Cu")
	)
	(gr_line
		(start 4.891024 -216.55913)
		(end 5.08 -216.748106)
		(stroke
			(width 0.087376)
			(type default)
		)
		(layer "B.Cu")
	)
	(gr_line
		(start 4.891024 -216.124282)
		(end 5.08 -215.935306)
		(stroke
			(width 0.087376)
			(type default)
		)
		(layer "B.Cu")
	)
	(gr_line
		(start 4.891024 -213.359238)
		(end 5.08 -213.548214)
		(stroke
			(width 0.087376)
			(type default)
		)
		(layer "B.Cu")
	)
	(gr_line
		(start 4.891024 -212.92439)
		(end 5.08 -212.735414)
		(stroke
			(width 0.087376)
			(type default)
		)
		(layer "B.Cu")
	)
	(gr_line
		(start 4.891024 -210.159346)
		(end 5.08 -210.348322)
		(stroke
			(width 0.087376)
			(type default)
		)
		(layer "B.Cu")
	)
	(gr_line
		(start 4.891024 -209.724498)
		(end 5.08 -209.535522)
		(stroke
			(width 0.087376)
			(type default)
		)
		(layer "B.Cu")
	)
	(gr_line
		(start 4.891024 -206.9592)
		(end 5.08 -207.148176)
		(stroke
			(width 0.087376)
			(type default)
		)
		(layer "B.Cu")
	)
	(gr_line
		(start 4.891024 -206.524352)
		(end 5.08 -206.335376)
		(stroke
			(width 0.087376)
			(type default)
		)
		(layer "B.Cu")
	)
	(gr_line
		(start 4.891024 -203.759308)
		(end 5.08 -203.948284)
		(stroke
			(width 0.087376)
			(type default)
		)
		(layer "B.Cu")
	)
	(gr_line
		(start 4.891024 -203.32446)
		(end 5.08 -203.135484)
		(stroke
			(width 0.087376)
			(type default)
		)
		(layer "B.Cu")
	)
	(gr_line
		(start 4.891024 -200.559162)
		(end 5.08 -200.748138)
		(stroke
			(width 0.087376)
			(type default)
		)
		(layer "B.Cu")
	)
	(gr_line
		(start 4.891024 -200.124314)
		(end 5.08 -199.935338)
		(stroke
			(width 0.087376)
			(type default)
		)
		(layer "B.Cu")
	)
	(gr_line
		(start 4.891024 -194.959224)
		(end 5.08 -195.1482)
		(stroke
			(width 0.087376)
			(type default)
		)
		(layer "B.Cu")
	)
	(gr_line
		(start 4.891024 -194.524376)
		(end 5.08 -194.3354)
		(stroke
			(width 0.087376)
			(type default)
		)
		(layer "B.Cu")
	)
	(gr_line
		(start 4.891024 -191.759332)
		(end 5.08 -191.948308)
		(stroke
			(width 0.087376)
			(type default)
		)
		(layer "B.Cu")
	)
	(gr_line
		(start 4.891024 -191.324484)
		(end 5.08 -191.135508)
		(stroke
			(width 0.087376)
			(type default)
		)
		(layer "B.Cu")
	)
	(gr_line
		(start 4.891024 -183.759348)
		(end 5.08 -183.948324)
		(stroke
			(width 0.087376)
			(type default)
		)
		(layer "B.Cu")
	)
	(gr_line
		(start 4.891024 -183.3245)
		(end 5.08 -183.135524)
		(stroke
			(width 0.087376)
			(type default)
		)
		(layer "B.Cu")
	)
	(gr_line
		(start 4.891024 -180.559202)
		(end 5.08 -180.748178)
		(stroke
			(width 0.087376)
			(type default)
		)
		(layer "B.Cu")
	)
	(gr_line
		(start 4.891024 -180.124354)
		(end 5.08 -179.935378)
		(stroke
			(width 0.087376)
			(type default)
		)
		(layer "B.Cu")
	)
	(gr_line
		(start 4.891024 -177.35931)
		(end 5.08 -177.548286)
		(stroke
			(width 0.087376)
			(type default)
		)
		(layer "B.Cu")
	)
	(gr_line
		(start 4.891024 -176.924462)
		(end 5.08 -176.735486)
		(stroke
			(width 0.087376)
			(type default)
		)
		(layer "B.Cu")
	)
	(gr_line
		(start 4.891024 -174.159164)
		(end 5.08 -174.34814)
		(stroke
			(width 0.087376)
			(type default)
		)
		(layer "B.Cu")
	)
	(gr_line
		(start 4.891024 -173.724316)
		(end 5.08 -173.53534)
		(stroke
			(width 0.087376)
			(type default)
		)
		(layer "B.Cu")
	)
	(gr_line
		(start 4.891024 -170.959272)
		(end 5.08 -171.148248)
		(stroke
			(width 0.087376)
			(type default)
		)
		(layer "B.Cu")
	)
	(gr_line
		(start 4.891024 -170.524424)
		(end 5.08 -170.335448)
		(stroke
			(width 0.087376)
			(type default)
		)
		(layer "B.Cu")
	)
	(gr_line
		(start 4.891024 -167.759126)
		(end 5.08 -167.948102)
		(stroke
			(width 0.087376)
			(type default)
		)
		(layer "B.Cu")
	)
	(gr_line
		(start 4.891024 -167.324278)
		(end 5.08 -167.135302)
		(stroke
			(width 0.087376)
			(type default)
		)
		(layer "B.Cu")
	)
	(gr_line
		(start 4.891024 -164.559234)
		(end 5.08 -164.74821)
		(stroke
			(width 0.087376)
			(type default)
		)
		(layer "B.Cu")
	)
	(gr_line
		(start 4.891024 -164.124386)
		(end 5.08 -163.93541)
		(stroke
			(width 0.087376)
			(type default)
		)
		(layer "B.Cu")
	)
	(gr_line
		(start 4.891024 -161.359342)
		(end 5.08 -161.548318)
		(stroke
			(width 0.087376)
			(type default)
		)
		(layer "B.Cu")
	)
	(gr_line
		(start 4.891024 -160.924494)
		(end 5.08 -160.735518)
		(stroke
			(width 0.087376)
			(type default)
		)
		(layer "B.Cu")
	)
	(gr_line
		(start 4.891024 -158.159196)
		(end 5.08 -158.348172)
		(stroke
			(width 0.087376)
			(type default)
		)
		(layer "B.Cu")
	)
	(gr_line
		(start 4.891024 -157.724348)
		(end 5.08 -157.535372)
		(stroke
			(width 0.087376)
			(type default)
		)
		(layer "B.Cu")
	)
	(gr_line
		(start 4.891024 -154.959304)
		(end 5.08 -155.14828)
		(stroke
			(width 0.087376)
			(type default)
		)
		(layer "B.Cu")
	)
	(gr_line
		(start 4.891024 -154.524456)
		(end 5.08 -154.33548)
		(stroke
			(width 0.087376)
			(type default)
		)
		(layer "B.Cu")
	)
	(gr_line
		(start 5.987796 -384.55854)
		(end 6.136894 -384.707638)
		(stroke
			(width 0.087376)
			(type default)
		)
		(layer "B.Cu")
	)
	(gr_line
		(start 6.136894 -384.707638)
		(end 6.613398 -384.707638)
		(stroke
			(width 0.087376)
			(type default)
		)
		(layer "B.Cu")
	)
	(gr_line
		(start 6.29285 -384.250946)
		(end 6.457442 -384.250946)
		(stroke
			(width 0.087376)
			(type default)
		)
		(layer "B.Cu")
	)
	(gr_line
		(start 6.477 -449.467732)
		(end 6.665976 -449.278756)
		(stroke
			(width 0.087376)
			(type default)
		)
		(layer "B.Cu")
	)
	(gr_line
		(start 6.613398 -384.707638)
		(end 6.762496 -384.55854)
		(stroke
			(width 0.087376)
			(type default)
		)
		(layer "B.Cu")
	)
	(gr_line
		(start 7.100824 -449.278756)
		(end 7.2898 -449.467732)
		(stroke
			(width 0.087376)
			(type default)
		)
		(layer "B.Cu")
	)
	(gr_line
		(start 7.291832 -384.55854)
		(end 7.427214 -384.693922)
		(stroke
			(width 0.087376)
			(type default)
		)
		(layer "B.Cu")
	)
	(gr_line
		(start 7.427214 -384.693922)
		(end 7.93115 -384.693922)
		(stroke
			(width 0.087376)
			(type default)
		)
		(layer "B.Cu")
	)
	(gr_line
		(start 7.596886 -384.250946)
		(end 7.761478 -384.250946)
		(stroke
			(width 0.087376)
			(type default)
		)
		(layer "B.Cu")
	)
	(gr_line
		(start 7.93115 -384.693922)
		(end 8.066532 -384.55854)
		(stroke
			(width 0.087376)
			(type default)
		)
		(layer "B.Cu")
	)
	(gr_line
		(start 8.382254 -385.603242)
		(end 8.57123 -385.414266)
		(stroke
			(width 0.087376)
			(type default)
		)
		(layer "B.Cu")
	)
	(gr_line
		(start 9.006078 -385.414266)
		(end 9.195054 -385.603242)
		(stroke
			(width 0.087376)
			(type default)
		)
		(layer "B.Cu")
	)
	(gr_line
		(start 17.272 -445.416178)
		(end 17.460976 -445.227202)
		(stroke
			(width 0.087376)
			(type default)
		)
		(layer "B.Cu")
	)
	(gr_line
		(start 17.272 -444.603378)
		(end 17.460976 -444.792354)
		(stroke
			(width 0.087376)
			(type default)
		)
		(layer "B.Cu")
	)
	(gr_line
		(start 17.272 -342.41613)
		(end 17.460976 -342.227154)
		(stroke
			(width 0.087376)
			(type default)
		)
		(layer "B.Cu")
	)
	(gr_line
		(start 17.272 -341.60333)
		(end 17.460976 -341.792306)
		(stroke
			(width 0.087376)
			(type default)
		)
		(layer "B.Cu")
	)
	(gr_line
		(start 17.272 -239.416082)
		(end 17.460976 -239.227106)
		(stroke
			(width 0.087376)
			(type default)
		)
		(layer "B.Cu")
	)
	(gr_line
		(start 17.272 -238.603282)
		(end 17.460976 -238.792258)
		(stroke
			(width 0.087376)
			(type default)
		)
		(layer "B.Cu")
	)
	(gr_line
		(start 17.272 -136.416034)
		(end 17.460976 -136.227058)
		(stroke
			(width 0.087376)
			(type default)
		)
		(layer "B.Cu")
	)
	(gr_line
		(start 17.272 -135.603234)
		(end 17.460976 -135.79221)
		(stroke
			(width 0.087376)
			(type default)
		)
		(layer "B.Cu")
	)
	(gr_line
		(start 17.272 -33.415986)
		(end 17.460976 -33.22701)
		(stroke
			(width 0.087376)
			(type default)
		)
		(layer "B.Cu")
	)
	(gr_line
		(start 17.272 -32.603186)
		(end 17.460976 -32.792162)
		(stroke
			(width 0.087376)
			(type default)
		)
		(layer "B.Cu")
	)
	(gr_line
		(start 20.82927 -391.287)
		(end 20.919694 -391.377424)
		(stroke
			(width 0.085598)
			(type default)
		)
		(layer "B.Cu")
	)
	(gr_line
		(start 20.82927 -391.287)
		(end 20.919694 -391.196576)
		(stroke
			(width 0.085598)
			(type default)
		)
		(layer "B.Cu")
	)
	(gr_line
		(start 21.11375 -391.57148)
		(end 21.11375 -391.634218)
		(stroke
			(width 0.085598)
			(type default)
		)
		(layer "B.Cu")
	)
	(gr_line
		(start 21.59 -391.01903)
		(end 21.59 -391.081768)
		(stroke
			(width 0.085598)
			(type default)
		)
		(layer "B.Cu")
	)
	(gr_line
		(start 21.704808 -391.377424)
		(end 21.795232 -391.287)
		(stroke
			(width 0.085598)
			(type default)
		)
		(layer "B.Cu")
	)
	(gr_line
		(start 21.704808 -391.196576)
		(end 21.795232 -391.287)
		(stroke
			(width 0.085598)
			(type default)
		)
		(layer "B.Cu")
	)
	(gr_line
		(start 28.085288 -238.835692)
		(end 28.21051 -238.71047)
		(stroke
			(width 0.087376)
			(type default)
		)
		(layer "B.Cu")
	)
	(gr_line
		(start 28.21051 -238.71047)
		(end 28.734766 -238.71047)
		(stroke
			(width 0.087376)
			(type default)
		)
		(layer "B.Cu")
	)
	(gr_line
		(start 28.390342 -239.143286)
		(end 28.554934 -239.143286)
		(stroke
			(width 0.087376)
			(type default)
		)
		(layer "B.Cu")
	)
	(gr_line
		(start 28.734766 -238.71047)
		(end 28.859988 -238.835692)
		(stroke
			(width 0.087376)
			(type default)
		)
		(layer "B.Cu")
	)
	(gr_line
		(start 29.389324 -238.835692)
		(end 29.514546 -238.71047)
		(stroke
			(width 0.087376)
			(type default)
		)
		(layer "B.Cu")
	)
	(gr_line
		(start 29.514546 -238.71047)
		(end 30.038802 -238.71047)
		(stroke
			(width 0.087376)
			(type default)
		)
		(layer "B.Cu")
	)
	(gr_line
		(start 29.694378 -239.143286)
		(end 29.85897 -239.143286)
		(stroke
			(width 0.087376)
			(type default)
		)
		(layer "B.Cu")
	)
	(gr_line
		(start 29.816298 -391.772902)
		(end 29.816298 -392.1125)
		(stroke
			(width 0.085598)
			(type default)
		)
		(layer "B.Cu")
	)
	(gr_line
		(start 29.816298 -391.772902)
		(end 29.97327 -391.61593)
		(stroke
			(width 0.085598)
			(type default)
		)
		(layer "B.Cu")
	)
	(gr_line
		(start 29.816298 -390.674098)
		(end 29.97327 -390.83107)
		(stroke
			(width 0.085598)
			(type default)
		)
		(layer "B.Cu")
	)
	(gr_line
		(start 29.816298 -390.2075)
		(end 29.816298 -390.674098)
		(stroke
			(width 0.085598)
			(type default)
		)
		(layer "B.Cu")
	)
	(gr_line
		(start 30.038802 -238.71047)
		(end 30.164024 -238.835692)
		(stroke
			(width 0.087376)
			(type default)
		)
		(layer "B.Cu")
	)
	(gr_line
		(start 30.69336 -238.835692)
		(end 30.818582 -238.71047)
		(stroke
			(width 0.087376)
			(type default)
		)
		(layer "B.Cu")
	)
	(gr_line
		(start 30.818582 -238.71047)
		(end 31.342838 -238.71047)
		(stroke
			(width 0.087376)
			(type default)
		)
		(layer "B.Cu")
	)
	(gr_line
		(start 30.998414 -239.143286)
		(end 31.163006 -239.143286)
		(stroke
			(width 0.087376)
			(type default)
		)
		(layer "B.Cu")
	)
	(gr_line
		(start 31.202376 -424.7896)
		(end 31.6738 -424.7896)
		(stroke
			(width 0.085598)
			(type default)
		)
		(layer "B.Cu")
	)
	(gr_line
		(start 31.307024 -136.227566)
		(end 31.496 -136.416542)
		(stroke
			(width 0.087376)
			(type default)
		)
		(layer "B.Cu")
	)
	(gr_line
		(start 31.307024 -135.792718)
		(end 31.496 -135.603742)
		(stroke
			(width 0.087376)
			(type default)
		)
		(layer "B.Cu")
	)
	(gr_line
		(start 31.307024 -33.22701)
		(end 31.496 -33.415986)
		(stroke
			(width 0.087376)
			(type default)
		)
		(layer "B.Cu")
	)
	(gr_line
		(start 31.307024 -32.792162)
		(end 31.496 -32.603186)
		(stroke
			(width 0.087376)
			(type default)
		)
		(layer "B.Cu")
	)
	(gr_line
		(start 31.342838 -238.71047)
		(end 31.46806 -238.835692)
		(stroke
			(width 0.087376)
			(type default)
		)
		(layer "B.Cu")
	)
	(gr_line
		(start 31.561024 -445.20866)
		(end 31.75 -445.397636)
		(stroke
			(width 0.087376)
			(type default)
		)
		(layer "B.Cu")
	)
	(gr_line
		(start 31.561024 -444.773812)
		(end 31.75 -444.584836)
		(stroke
			(width 0.087376)
			(type default)
		)
		(layer "B.Cu")
	)
	(gr_line
		(start 31.6738 -424.7896)
		(end 31.682944 -424.780456)
		(stroke
			(width 0.085598)
			(type default)
		)
		(layer "B.Cu")
	)
	(gr_line
		(start 32.005016 -218.322906)
		(end 32.060134 -218.378024)
		(stroke
			(width 0.085598)
			(type default)
		)
		(layer "B.Cu")
	)
	(gr_line
		(start 32.005016 -217.537792)
		(end 32.060134 -217.482674)
		(stroke
			(width 0.085598)
			(type default)
		)
		(layer "B.Cu")
	)
	(gr_line
		(start 32.060134 -218.378024)
		(end 32.060134 -218.7575)
		(stroke
			(width 0.085598)
			(type default)
		)
		(layer "B.Cu")
	)
	(gr_line
		(start 32.060134 -216.8525)
		(end 32.060134 -217.482674)
		(stroke
			(width 0.085598)
			(type default)
		)
		(layer "B.Cu")
	)
	(gr_line
		(start 32.468058 -424.780456)
		(end 32.477202 -424.7896)
		(stroke
			(width 0.085598)
			(type default)
		)
		(layer "B.Cu")
	)
	(gr_line
		(start 32.477202 -424.7896)
		(end 33.107376 -424.7896)
		(stroke
			(width 0.085598)
			(type default)
		)
		(layer "B.Cu")
	)
	(gr_line
		(start 32.704024 -342.208358)
		(end 32.893 -342.397334)
		(stroke
			(width 0.087376)
			(type default)
		)
		(layer "B.Cu")
	)
	(gr_line
		(start 32.704024 -341.77351)
		(end 32.893 -341.584534)
		(stroke
			(width 0.087376)
			(type default)
		)
		(layer "B.Cu")
	)
	(gr_line
		(start 34.01314 -238.835692)
		(end 34.138362 -238.71047)
		(stroke
			(width 0.087376)
			(type default)
		)
		(layer "B.Cu")
	)
	(gr_line
		(start 34.138362 -238.71047)
		(end 34.662618 -238.71047)
		(stroke
			(width 0.087376)
			(type default)
		)
		(layer "B.Cu")
	)
	(gr_line
		(start 34.318194 -239.143286)
		(end 34.482786 -239.143286)
		(stroke
			(width 0.087376)
			(type default)
		)
		(layer "B.Cu")
	)
	(gr_line
		(start 34.662618 -238.71047)
		(end 34.78784 -238.835692)
		(stroke
			(width 0.087376)
			(type default)
		)
		(layer "B.Cu")
	)
	(gr_line
		(start 35.317176 -238.835692)
		(end 35.442398 -238.71047)
		(stroke
			(width 0.087376)
			(type default)
		)
		(layer "B.Cu")
	)
	(gr_line
		(start 35.442398 -238.71047)
		(end 35.966654 -238.71047)
		(stroke
			(width 0.087376)
			(type default)
		)
		(layer "B.Cu")
	)
	(gr_line
		(start 35.62223 -239.143286)
		(end 35.786822 -239.143286)
		(stroke
			(width 0.087376)
			(type default)
		)
		(layer "B.Cu")
	)
	(gr_line
		(start 35.966654 -238.71047)
		(end 36.091876 -238.835692)
		(stroke
			(width 0.087376)
			(type default)
		)
		(layer "B.Cu")
	)
	(gr_line
		(start 42.229024 -239.20831)
		(end 42.418 -239.397286)
		(stroke
			(width 0.087376)
			(type default)
		)
		(layer "B.Cu")
	)
	(gr_line
		(start 42.229024 -238.773462)
		(end 42.418 -238.584486)
		(stroke
			(width 0.087376)
			(type default)
		)
		(layer "B.Cu")
	)
	(gr_line
		(start 44.9072 -471.790268)
		(end 45.096176 -471.979244)
		(stroke
			(width 0.087376)
			(type default)
		)
		(layer "B.Cu")
	)
	(gr_line
		(start 44.9072 -368.79022)
		(end 45.096176 -368.979196)
		(stroke
			(width 0.087376)
			(type default)
		)
		(layer "B.Cu")
	)
	(gr_line
		(start 44.9072 -265.790172)
		(end 45.096176 -265.979148)
		(stroke
			(width 0.087376)
			(type default)
		)
		(layer "B.Cu")
	)
	(gr_line
		(start 44.9072 -162.790124)
		(end 45.096176 -162.9791)
		(stroke
			(width 0.087376)
			(type default)
		)
		(layer "B.Cu")
	)
	(gr_line
		(start 44.9072 -59.790076)
		(end 45.096176 -59.979052)
		(stroke
			(width 0.087376)
			(type default)
		)
		(layer "B.Cu")
	)
	(gr_line
		(start 45.531024 -471.979244)
		(end 45.72 -471.790268)
		(stroke
			(width 0.087376)
			(type default)
		)
		(layer "B.Cu")
	)
	(gr_line
		(start 45.531024 -368.979196)
		(end 45.72 -368.79022)
		(stroke
			(width 0.087376)
			(type default)
		)
		(layer "B.Cu")
	)
	(gr_line
		(start 45.531024 -265.979148)
		(end 45.72 -265.790172)
		(stroke
			(width 0.087376)
			(type default)
		)
		(layer "B.Cu")
	)
	(gr_line
		(start 45.531024 -162.9791)
		(end 45.72 -162.790124)
		(stroke
			(width 0.087376)
			(type default)
		)
		(layer "B.Cu")
	)
	(gr_line
		(start 45.531024 -59.979052)
		(end 45.72 -59.790076)
		(stroke
			(width 0.087376)
			(type default)
		)
		(layer "B.Cu")
	)
	(gr_line
		(start 46.569376 -205.2828)
		(end 47.0408 -205.2828)
		(stroke
			(width 0.085598)
			(type default)
		)
		(layer "B.Cu")
	)
	(gr_line
		(start 47.0408 -205.2828)
		(end 47.13097 -205.19263)
		(stroke
			(width 0.085598)
			(type default)
		)
		(layer "B.Cu")
	)
	(gr_line
		(start 47.670974 -134.1374)
		(end 47.714662 -134.1374)
		(stroke
			(width 0.085598)
			(type default)
		)
		(layer "B.Cu")
	)
	(gr_line
		(start 47.878492 -134.758684)
		(end 47.968916 -134.849108)
		(stroke
			(width 0.085598)
			(type default)
		)
		(layer "B.Cu")
	)
	(gr_line
		(start 47.878492 -133.97357)
		(end 47.968916 -133.883146)
		(stroke
			(width 0.085598)
			(type default)
		)
		(layer "B.Cu")
	)
	(gr_line
		(start 47.91583 -205.19263)
		(end 48.006 -205.2828)
		(stroke
			(width 0.085598)
			(type default)
		)
		(layer "B.Cu")
	)
	(gr_line
		(start 47.968916 -134.849108)
		(end 48.05934 -134.758684)
		(stroke
			(width 0.085598)
			(type default)
		)
		(layer "B.Cu")
	)
	(gr_line
		(start 47.968916 -133.883146)
		(end 48.05934 -133.97357)
		(stroke
			(width 0.085598)
			(type default)
		)
		(layer "B.Cu")
	)
	(gr_line
		(start 48.006 -205.2828)
		(end 48.474376 -205.2828)
		(stroke
			(width 0.085598)
			(type default)
		)
		(layer "B.Cu")
	)
	(gr_line
		(start 48.198024 -473.20327)
		(end 48.387 -473.392246)
		(stroke
			(width 0.087376)
			(type default)
		)
		(layer "B.Cu")
	)
	(gr_line
		(start 48.198024 -472.768422)
		(end 48.387 -472.579446)
		(stroke
			(width 0.087376)
			(type default)
		)
		(layer "B.Cu")
	)
	(gr_line
		(start 48.198024 -370.203222)
		(end 48.387 -370.392198)
		(stroke
			(width 0.087376)
			(type default)
		)
		(layer "B.Cu")
	)
	(gr_line
		(start 48.198024 -369.768374)
		(end 48.387 -369.579398)
		(stroke
			(width 0.087376)
			(type default)
		)
		(layer "B.Cu")
	)
	(gr_line
		(start 48.198024 -267.203174)
		(end 48.387 -267.39215)
		(stroke
			(width 0.087376)
			(type default)
		)
		(layer "B.Cu")
	)
	(gr_line
		(start 48.198024 -266.768326)
		(end 48.387 -266.57935)
		(stroke
			(width 0.087376)
			(type default)
		)
		(layer "B.Cu")
	)
	(gr_line
		(start 48.198024 -164.203126)
		(end 48.387 -164.392102)
		(stroke
			(width 0.087376)
			(type default)
		)
		(layer "B.Cu")
	)
	(gr_line
		(start 48.198024 -163.768278)
		(end 48.387 -163.579302)
		(stroke
			(width 0.087376)
			(type default)
		)
		(layer "B.Cu")
	)
	(gr_line
		(start 48.198024 -61.203078)
		(end 48.387 -61.392054)
		(stroke
			(width 0.087376)
			(type default)
		)
		(layer "B.Cu")
	)
	(gr_line
		(start 48.198024 -60.76823)
		(end 48.387 -60.579254)
		(stroke
			(width 0.087376)
			(type default)
		)
		(layer "B.Cu")
	)
	(gr_line
		(start 48.223424 -134.5946)
		(end 48.267112 -134.5946)
		(stroke
			(width 0.085598)
			(type default)
		)
		(layer "B.Cu")
	)
	(gr_line
		(start 56.046624 -111.379)
		(end 56.54675 -111.379)
		(stroke
			(width 0.085598)
			(type default)
		)
		(layer "B.Cu")
	)
	(gr_line
		(start 57.32145 -111.379)
		(end 57.951624 -111.379)
		(stroke
			(width 0.085598)
			(type default)
		)
		(layer "B.Cu")
	)
	(gr_line
		(start 59.015376 -441.96)
		(end 59.4868 -441.96)
		(stroke
			(width 0.085598)
			(type default)
		)
		(layer "B.Cu")
	)
	(gr_line
		(start 59.4868 -441.96)
		(end 59.61507 -441.83173)
		(stroke
			(width 0.085598)
			(type default)
		)
		(layer "B.Cu")
	)
	(gr_line
		(start 59.856624 -97.04324)
		(end 60.486798 -97.04324)
		(stroke
			(width 0.085598)
			(type default)
		)
		(layer "B.Cu")
	)
	(gr_line
		(start 60.39993 -441.83173)
		(end 60.5282 -441.96)
		(stroke
			(width 0.085598)
			(type default)
		)
		(layer "B.Cu")
	)
	(gr_line
		(start 60.486798 -97.04324)
		(end 60.541916 -97.098358)
		(stroke
			(width 0.085598)
			(type default)
		)
		(layer "B.Cu")
	)
	(gr_line
		(start 60.5282 -441.96)
		(end 60.920376 -441.96)
		(stroke
			(width 0.085598)
			(type default)
		)
		(layer "B.Cu")
	)
	(gr_line
		(start 61.32703 -97.098358)
		(end 61.382148 -97.04324)
		(stroke
			(width 0.085598)
			(type default)
		)
		(layer "B.Cu")
	)
	(gr_line
		(start 61.382148 -97.04324)
		(end 61.761624 -97.04324)
		(stroke
			(width 0.085598)
			(type default)
		)
		(layer "B.Cu")
	)
	(gr_line
		(start 61.590682 -321.045332)
		(end 61.6458 -321.10045)
		(stroke
			(width 0.085598)
			(type default)
		)
		(layer "B.Cu")
	)
	(gr_line
		(start 61.590682 -320.260218)
		(end 61.6458 -320.2051)
		(stroke
			(width 0.085598)
			(type default)
		)
		(layer "B.Cu")
	)
	(gr_line
		(start 61.6458 -321.10045)
		(end 61.6458 -321.730624)
		(stroke
			(width 0.085598)
			(type default)
		)
		(layer "B.Cu")
	)
	(gr_line
		(start 61.6458 -319.825624)
		(end 61.6458 -320.2051)
		(stroke
			(width 0.085598)
			(type default)
		)
		(layer "B.Cu")
	)
	(gr_line
		(start 63.119 -436.069232)
		(end 63.209424 -435.978808)
		(stroke
			(width 0.085598)
			(type default)
		)
		(layer "B.Cu")
	)
	(gr_line
		(start 63.119 -435.10327)
		(end 63.209424 -435.193694)
		(stroke
			(width 0.085598)
			(type default)
		)
		(layer "B.Cu")
	)
	(gr_line
		(start 63.929768 -441.597542)
		(end 64.020192 -441.507118)
		(stroke
			(width 0.085598)
			(type default)
		)
		(layer "B.Cu")
	)
	(gr_line
		(start 64.805306 -441.507118)
		(end 64.89573 -441.597542)
		(stroke
			(width 0.085598)
			(type default)
		)
		(layer "B.Cu")
	)
	(gr_line
		(start 67.094608 -435.1401)
		(end 67.094862 -435.1401)
		(stroke
			(width 0.085598)
			(type default)
		)
		(layer "B.Cu")
	)
	(gr_line
		(start 67.485514 -435.530752)
		(end 67.647312 -435.530752)
		(stroke
			(width 0.085598)
			(type default)
		)
		(layer "B.Cu")
	)
	(gr_line
		(start 68.286376 -300.49724)
		(end 68.91655 -300.49724)
		(stroke
			(width 0.085598)
			(type default)
		)
		(layer "B.Cu")
	)
	(gr_line
		(start 68.438776 -150.971758)
		(end 68.5292 -151.062182)
		(stroke
			(width 0.085598)
			(type default)
		)
		(layer "B.Cu")
	)
	(gr_line
		(start 68.438776 -150.186644)
		(end 68.5292 -150.09622)
		(stroke
			(width 0.085598)
			(type default)
		)
		(layer "B.Cu")
	)
	(gr_line
		(start 68.489576 -359.912158)
		(end 68.58 -360.002582)
		(stroke
			(width 0.085598)
			(type default)
		)
		(layer "B.Cu")
	)
	(gr_line
		(start 68.489576 -359.127044)
		(end 68.58 -359.03662)
		(stroke
			(width 0.085598)
			(type default)
		)
		(layer "B.Cu")
	)
	(gr_line
		(start 68.489576 -147.949158)
		(end 68.58 -148.039582)
		(stroke
			(width 0.085598)
			(type default)
		)
		(layer "B.Cu")
	)
	(gr_line
		(start 68.489576 -147.164044)
		(end 68.58 -147.07362)
		(stroke
			(width 0.085598)
			(type default)
		)
		(layer "B.Cu")
	)
	(gr_line
		(start 68.489576 -144.926558)
		(end 68.58 -145.016982)
		(stroke
			(width 0.085598)
			(type default)
		)
		(layer "B.Cu")
	)
	(gr_line
		(start 68.489576 -144.141444)
		(end 68.58 -144.05102)
		(stroke
			(width 0.085598)
			(type default)
		)
		(layer "B.Cu")
	)
	(gr_line
		(start 68.514976 -363.002576)
		(end 68.6054 -363.093)
		(stroke
			(width 0.085598)
			(type default)
		)
		(layer "B.Cu")
	)
	(gr_line
		(start 68.514976 -362.217462)
		(end 68.6054 -362.127038)
		(stroke
			(width 0.085598)
			(type default)
		)
		(layer "B.Cu")
	)
	(gr_line
		(start 68.91655 -300.49724)
		(end 68.971668 -300.552358)
		(stroke
			(width 0.085598)
			(type default)
		)
		(layer "B.Cu")
	)
	(gr_line
		(start 69.240146 -438.441084)
		(end 69.33057 -438.531508)
		(stroke
			(width 0.085598)
			(type default)
		)
		(layer "B.Cu")
	)
	(gr_line
		(start 69.240146 -438.441084)
		(end 69.33057 -438.35066)
		(stroke
			(width 0.085598)
			(type default)
		)
		(layer "B.Cu")
	)
	(gr_line
		(start 69.446902 -438.64784)
		(end 69.446902 -438.783476)
		(stroke
			(width 0.085598)
			(type default)
		)
		(layer "B.Cu")
	)
	(gr_line
		(start 69.756782 -300.552358)
		(end 69.8119 -300.49724)
		(stroke
			(width 0.085598)
			(type default)
		)
		(layer "B.Cu")
	)
	(gr_line
		(start 69.8119 -300.49724)
		(end 70.191376 -300.49724)
		(stroke
			(width 0.085598)
			(type default)
		)
		(layer "B.Cu")
	)
	(gr_line
		(start 69.99605 -438.09539)
		(end 69.99605 -438.231026)
		(stroke
			(width 0.085598)
			(type default)
		)
		(layer "B.Cu")
	)
	(gr_line
		(start 70.115684 -438.531508)
		(end 70.206108 -438.441084)
		(stroke
			(width 0.085598)
			(type default)
		)
		(layer "B.Cu")
	)
	(gr_line
		(start 70.115684 -438.35066)
		(end 70.206108 -438.441084)
		(stroke
			(width 0.085598)
			(type default)
		)
		(layer "B.Cu")
	)
	(gr_line
		(start 71.63562 -368.6556)
		(end 71.726044 -368.746024)
		(stroke
			(width 0.085598)
			(type default)
		)
		(layer "B.Cu")
	)
	(gr_line
		(start 72.136 -138.843258)
		(end 72.136 -139.406376)
		(stroke
			(width 0.085598)
			(type default)
		)
		(layer "B.Cu")
	)
	(gr_line
		(start 72.136 -138.843258)
		(end 72.15505 -138.824208)
		(stroke
			(width 0.085598)
			(type default)
		)
		(layer "B.Cu")
	)
	(gr_line
		(start 72.136 -138.020298)
		(end 72.15505 -138.039348)
		(stroke
			(width 0.085598)
			(type default)
		)
		(layer "B.Cu")
	)
	(gr_line
		(start 72.136 -137.501376)
		(end 72.136 -138.020298)
		(stroke
			(width 0.085598)
			(type default)
		)
		(layer "B.Cu")
	)
	(gr_line
		(start 72.39 -431.9524)
		(end 72.578976 -431.763424)
		(stroke
			(width 0.087376)
			(type default)
		)
		(layer "B.Cu")
	)
	(gr_line
		(start 72.39 -431.1396)
		(end 72.578976 -431.328576)
		(stroke
			(width 0.087376)
			(type default)
		)
		(layer "B.Cu")
	)
	(gr_line
		(start 72.511158 -368.746024)
		(end 72.601582 -368.6556)
		(stroke
			(width 0.085598)
			(type default)
		)
		(layer "B.Cu")
	)
	(gr_line
		(start 72.67702 -156.3878)
		(end 72.767444 -156.478224)
		(stroke
			(width 0.085598)
			(type default)
		)
		(layer "B.Cu")
	)
	(gr_line
		(start 72.940418 -350.52)
		(end 73.030842 -350.610424)
		(stroke
			(width 0.085598)
			(type default)
		)
		(layer "B.Cu")
	)
	(gr_line
		(start 72.940418 -350.52)
		(end 73.030842 -350.429576)
		(stroke
			(width 0.085598)
			(type default)
		)
		(layer "B.Cu")
	)
	(gr_line
		(start 73.552558 -156.478224)
		(end 73.642982 -156.3878)
		(stroke
			(width 0.085598)
			(type default)
		)
		(layer "B.Cu")
	)
	(gr_line
		(start 73.815956 -350.610424)
		(end 73.90638 -350.52)
		(stroke
			(width 0.085598)
			(type default)
		)
		(layer "B.Cu")
	)
	(gr_line
		(start 73.815956 -350.429576)
		(end 73.90638 -350.52)
		(stroke
			(width 0.085598)
			(type default)
		)
		(layer "B.Cu")
	)
	(gr_line
		(start 74.2696 -430.1236)
		(end 74.458576 -430.312576)
		(stroke
			(width 0.087376)
			(type default)
		)
		(layer "B.Cu")
	)
	(gr_line
		(start 74.337418 -141.097)
		(end 74.666856 -140.767562)
		(stroke
			(width 0.085598)
			(type default)
		)
		(layer "B.Cu")
	)
	(gr_line
		(start 74.63282 -368.681)
		(end 74.723244 -368.771424)
		(stroke
			(width 0.085598)
			(type default)
		)
		(layer "B.Cu")
	)
	(gr_line
		(start 74.893424 -430.312576)
		(end 75.0824 -430.1236)
		(stroke
			(width 0.087376)
			(type default)
		)
		(layer "B.Cu")
	)
	(gr_line
		(start 75.221846 -141.015466)
		(end 75.30338 -141.097)
		(stroke
			(width 0.085598)
			(type default)
		)
		(layer "B.Cu")
	)
	(gr_line
		(start 75.508358 -368.771424)
		(end 75.598782 -368.681)
		(stroke
			(width 0.085598)
			(type default)
		)
		(layer "B.Cu")
	)
	(gr_line
		(start 75.69962 -157.734)
		(end 75.802998 -157.837378)
		(stroke
			(width 0.085598)
			(type default)
		)
		(layer "B.Cu")
	)
	(gr_line
		(start 75.802998 -157.837378)
		(end 75.802998 -157.926532)
		(stroke
			(width 0.085598)
			(type default)
		)
		(layer "B.Cu")
	)
	(gr_line
		(start 76.530454 -157.869128)
		(end 76.665582 -157.734)
		(stroke
			(width 0.085598)
			(type default)
		)
		(layer "B.Cu")
	)
	(gr_line
		(start 77.68082 -368.6302)
		(end 77.771244 -368.720624)
		(stroke
			(width 0.085598)
			(type default)
		)
		(layer "B.Cu")
	)
	(gr_line
		(start 78.556358 -368.720624)
		(end 78.646782 -368.6302)
		(stroke
			(width 0.085598)
			(type default)
		)
		(layer "B.Cu")
	)
	(gr_line
		(start 78.74762 -156.337)
		(end 78.838044 -156.427424)
		(stroke
			(width 0.085598)
			(type default)
		)
		(layer "B.Cu")
	)
	(gr_line
		(start 79.623158 -156.427424)
		(end 79.713582 -156.337)
		(stroke
			(width 0.085598)
			(type default)
		)
		(layer "B.Cu")
	)
	(gr_line
		(start 80.557624 -303.13376)
		(end 80.98536 -303.13376)
		(stroke
			(width 0.085598)
			(type default)
		)
		(layer "B.Cu")
	)
	(gr_line
		(start 80.811624 -429.87976)
		(end 81.371694 -430.43983)
		(stroke
			(width 0.085598)
			(type default)
		)
		(layer "B.Cu")
	)
	(gr_line
		(start 80.811624 -429.87976)
		(end 81.371694 -429.31969)
		(stroke
			(width 0.085598)
			(type default)
		)
		(layer "B.Cu")
	)
	(gr_line
		(start 80.938624 -99.42576)
		(end 81.568798 -99.42576)
		(stroke
			(width 0.085598)
			(type default)
		)
		(layer "B.Cu")
	)
	(gr_line
		(start 80.98536 -303.13376)
		(end 81.06537 -303.21377)
		(stroke
			(width 0.085598)
			(type default)
		)
		(layer "B.Cu")
	)
	(gr_line
		(start 81.568798 -99.42576)
		(end 81.623916 -99.480878)
		(stroke
			(width 0.085598)
			(type default)
		)
		(layer "B.Cu")
	)
	(gr_line
		(start 81.85023 -303.21377)
		(end 81.93024 -303.13376)
		(stroke
			(width 0.085598)
			(type default)
		)
		(layer "B.Cu")
	)
	(gr_line
		(start 81.93024 -303.13376)
		(end 82.462624 -303.13376)
		(stroke
			(width 0.085598)
			(type default)
		)
		(layer "B.Cu")
	)
	(gr_line
		(start 82.156554 -430.43983)
		(end 82.716624 -429.87976)
		(stroke
			(width 0.085598)
			(type default)
		)
		(layer "B.Cu")
	)
	(gr_line
		(start 82.156554 -429.31969)
		(end 82.716624 -429.87976)
		(stroke
			(width 0.085598)
			(type default)
		)
		(layer "B.Cu")
	)
	(gr_line
		(start 82.40903 -99.480878)
		(end 82.464148 -99.42576)
		(stroke
			(width 0.085598)
			(type default)
		)
		(layer "B.Cu")
	)
	(gr_line
		(start 82.464148 -99.42576)
		(end 82.843624 -99.42576)
		(stroke
			(width 0.085598)
			(type default)
		)
		(layer "B.Cu")
	)
	(gr_line
		(start 82.51698 -206.348584)
		(end 82.846418 -206.019146)
		(stroke
			(width 0.085598)
			(type default)
		)
		(layer "B.Cu")
	)
	(gr_line
		(start 82.764884 -206.903574)
		(end 82.846418 -206.985108)
		(stroke
			(width 0.085598)
			(type default)
		)
		(layer "B.Cu")
	)
	(gr_line
		(start 83.82 -364.53318)
		(end 83.910424 -364.442756)
		(stroke
			(width 0.085598)
			(type default)
		)
		(layer "B.Cu")
	)
	(gr_line
		(start 83.82 -363.567218)
		(end 83.910424 -363.657642)
		(stroke
			(width 0.085598)
			(type default)
		)
		(layer "B.Cu")
	)
	(gr_line
		(start 83.82 -361.56138)
		(end 83.910424 -361.470956)
		(stroke
			(width 0.085598)
			(type default)
		)
		(layer "B.Cu")
	)
	(gr_line
		(start 83.82 -360.595418)
		(end 83.910424 -360.685842)
		(stroke
			(width 0.085598)
			(type default)
		)
		(layer "B.Cu")
	)
	(gr_line
		(start 83.8962 -358.4194)
		(end 83.896708 -358.418892)
		(stroke
			(width 0.085598)
			(type default)
		)
		(layer "B.Cu")
	)
	(gr_line
		(start 83.8962 -357.453438)
		(end 83.980528 -357.537766)
		(stroke
			(width 0.085598)
			(type default)
		)
		(layer "B.Cu")
	)
	(gr_line
		(start 83.896708 -358.4067)
		(end 83.896708 -358.418892)
		(stroke
			(width 0.085598)
			(type default)
		)
		(layer "B.Cu")
	)
	(gr_line
		(start 83.896708 -358.4067)
		(end 83.980528 -358.32288)
		(stroke
			(width 0.085598)
			(type default)
		)
		(layer "B.Cu")
	)
	(gr_line
		(start 86.233 -146.42338)
		(end 86.323424 -146.332956)
		(stroke
			(width 0.085598)
			(type default)
		)
		(layer "B.Cu")
	)
	(gr_line
		(start 86.233 -145.457418)
		(end 86.323424 -145.547842)
		(stroke
			(width 0.085598)
			(type default)
		)
		(layer "B.Cu")
	)
	(gr_line
		(start 89.066624 -358.394)
		(end 89.5604 -358.394)
		(stroke
			(width 0.085598)
			(type default)
		)
		(layer "B.Cu")
	)
	(gr_line
		(start 89.5604 -358.394)
		(end 89.63787 -358.47147)
		(stroke
			(width 0.085598)
			(type default)
		)
		(layer "B.Cu")
	)
	(gr_line
		(start 90.42273 -358.47147)
		(end 90.5002 -358.394)
		(stroke
			(width 0.085598)
			(type default)
		)
		(layer "B.Cu")
	)
	(gr_line
		(start 90.5002 -358.394)
		(end 90.971624 -358.394)
		(stroke
			(width 0.085598)
			(type default)
		)
		(layer "B.Cu")
	)
	(gr_line
		(start 94.74327 -445.880236)
		(end 94.833694 -445.97066)
		(stroke
			(width 0.085598)
			(type default)
		)
		(layer "B.Cu")
	)
	(gr_line
		(start 95.618808 -445.97066)
		(end 95.709232 -445.880236)
		(stroke
			(width 0.085598)
			(type default)
		)
		(layer "B.Cu")
	)
	(gr_line
		(start 104.775 -288.485326)
		(end 104.775 -289.1155)
		(stroke
			(width 0.085598)
			(type default)
		)
		(layer "B.Cu")
	)
	(gr_line
		(start 104.775 -287.2105)
		(end 104.775 -287.7312)
		(stroke
			(width 0.085598)
			(type default)
		)
		(layer "B.Cu")
	)
	(gr_line
		(start 108.02493 -76.822554)
		(end 108.585 -77.382624)
		(stroke
			(width 0.085598)
			(type default)
		)
		(layer "B.Cu")
	)
	(gr_line
		(start 108.02493 -76.037694)
		(end 108.585 -75.477624)
		(stroke
			(width 0.085598)
			(type default)
		)
		(layer "B.Cu")
	)
	(gr_line
		(start 108.585 -77.382624)
		(end 109.14507 -76.822554)
		(stroke
			(width 0.085598)
			(type default)
		)
		(layer "B.Cu")
	)
	(gr_line
		(start 108.585 -75.477624)
		(end 109.14507 -76.037694)
		(stroke
			(width 0.085598)
			(type default)
		)
		(layer "B.Cu")
	)
	(gr_line
		(start 109.513624 -423.926)
		(end 110.143798 -423.926)
		(stroke
			(width 0.085598)
			(type default)
		)
		(layer "B.Cu")
	)
	(gr_line
		(start 110.143798 -423.926)
		(end 110.278418 -424.06062)
		(stroke
			(width 0.085598)
			(type default)
		)
		(layer "B.Cu")
	)
	(gr_line
		(start 111.063532 -424.06062)
		(end 111.198152 -423.926)
		(stroke
			(width 0.085598)
			(type default)
		)
		(layer "B.Cu")
	)
	(gr_line
		(start 111.198152 -423.926)
		(end 111.418624 -423.926)
		(stroke
			(width 0.085598)
			(type default)
		)
		(layer "B.Cu")
	)
	(gr_line
		(start 114.466624 -442.722)
		(end 115.096798 -442.722)
		(stroke
			(width 0.085598)
			(type default)
		)
		(layer "B.Cu")
	)
	(gr_line
		(start 115.096798 -442.722)
		(end 115.151916 -442.777118)
		(stroke
			(width 0.085598)
			(type default)
		)
		(layer "B.Cu")
	)
	(gr_line
		(start 115.93703 -442.777118)
		(end 115.992148 -442.722)
		(stroke
			(width 0.085598)
			(type default)
		)
		(layer "B.Cu")
	)
	(gr_line
		(start 115.992148 -442.722)
		(end 116.371624 -442.722)
		(stroke
			(width 0.085598)
			(type default)
		)
		(layer "B.Cu")
	)
	(gr_line
		(start 130.214624 -158.369)
		(end 130.844798 -158.369)
		(stroke
			(width 0.085598)
			(type default)
		)
		(layer "B.Cu")
	)
	(gr_line
		(start 130.844798 -158.369)
		(end 130.899916 -158.313882)
		(stroke
			(width 0.085598)
			(type default)
		)
		(layer "B.Cu")
	)
	(gr_line
		(start 131.68503 -158.313882)
		(end 131.740148 -158.369)
		(stroke
			(width 0.085598)
			(type default)
		)
		(layer "B.Cu")
	)
	(gr_line
		(start 131.740148 -158.369)
		(end 132.119624 -158.369)
		(stroke
			(width 0.085598)
			(type default)
		)
		(layer "B.Cu")
	)
	(gr_line
		(start 140.97 -134.5946)
		(end 140.97 -135.088376)
		(stroke
			(width 0.085598)
			(type default)
		)
		(layer "B.Cu")
	)
	(gr_line
		(start 140.97 -133.183376)
		(end 140.97 -133.81355)
		(stroke
			(width 0.085598)
			(type default)
		)
		(layer "B.Cu")
	)
	(gr_line
		(start 201.164698 -50.049684)
		(end 201.255122 -50.140108)
		(stroke
			(width 0.085598)
			(type default)
		)
		(layer "B.Cu")
	)
	(gr_line
		(start 201.164698 -49.26457)
		(end 201.255122 -49.174146)
		(stroke
			(width 0.085598)
			(type default)
		)
		(layer "B.Cu")
	)
	(gr_line
		(start 229.907084 -471.790268)
		(end 230.09606 -471.979244)
		(stroke
			(width 0.087376)
			(type default)
		)
		(layer "B.Cu")
	)
	(gr_line
		(start 229.907084 -368.79022)
		(end 230.09606 -368.979196)
		(stroke
			(width 0.087376)
			(type default)
		)
		(layer "B.Cu")
	)
	(gr_line
		(start 229.907084 -265.790172)
		(end 230.09606 -265.979148)
		(stroke
			(width 0.087376)
			(type default)
		)
		(layer "B.Cu")
	)
	(gr_line
		(start 229.907084 -162.790124)
		(end 230.09606 -162.9791)
		(stroke
			(width 0.087376)
			(type default)
		)
		(layer "B.Cu")
	)
	(gr_line
		(start 229.907084 -59.790076)
		(end 230.09606 -59.979052)
		(stroke
			(width 0.087376)
			(type default)
		)
		(layer "B.Cu")
	)
	(gr_line
		(start 230.530908 -471.979244)
		(end 230.719884 -471.790268)
		(stroke
			(width 0.087376)
			(type default)
		)
		(layer "B.Cu")
	)
	(gr_line
		(start 230.530908 -368.979196)
		(end 230.719884 -368.79022)
		(stroke
			(width 0.087376)
			(type default)
		)
		(layer "B.Cu")
	)
	(gr_line
		(start 230.530908 -265.979148)
		(end 230.719884 -265.790172)
		(stroke
			(width 0.087376)
			(type default)
		)
		(layer "B.Cu")
	)
	(gr_line
		(start 230.530908 -162.9791)
		(end 230.719884 -162.790124)
		(stroke
			(width 0.087376)
			(type default)
		)
		(layer "B.Cu")
	)
	(gr_line
		(start 230.530908 -59.979052)
		(end 230.719884 -59.790076)
		(stroke
			(width 0.087376)
			(type default)
		)
		(layer "B.Cu")
	)
	(gr_line
		(start 233.197908 -473.20327)
		(end 233.386884 -473.392246)
		(stroke
			(width 0.087376)
			(type default)
		)
		(layer "B.Cu")
	)
	(gr_line
		(start 233.197908 -472.768422)
		(end 233.386884 -472.579446)
		(stroke
			(width 0.087376)
			(type default)
		)
		(layer "B.Cu")
	)
	(gr_line
		(start 233.197908 -370.203222)
		(end 233.386884 -370.392198)
		(stroke
			(width 0.087376)
			(type default)
		)
		(layer "B.Cu")
	)
	(gr_line
		(start 233.197908 -369.768374)
		(end 233.386884 -369.579398)
		(stroke
			(width 0.087376)
			(type default)
		)
		(layer "B.Cu")
	)
	(gr_line
		(start 233.197908 -267.203174)
		(end 233.386884 -267.39215)
		(stroke
			(width 0.087376)
			(type default)
		)
		(layer "B.Cu")
	)
	(gr_line
		(start 233.197908 -266.768326)
		(end 233.386884 -266.57935)
		(stroke
			(width 0.087376)
			(type default)
		)
		(layer "B.Cu")
	)
	(gr_line
		(start 233.197908 -164.203126)
		(end 233.386884 -164.392102)
		(stroke
			(width 0.087376)
			(type default)
		)
		(layer "B.Cu")
	)
	(gr_line
		(start 233.197908 -163.768278)
		(end 233.386884 -163.579302)
		(stroke
			(width 0.087376)
			(type default)
		)
		(layer "B.Cu")
	)
	(gr_line
		(start 233.197908 -61.203078)
		(end 233.386884 -61.392054)
		(stroke
			(width 0.087376)
			(type default)
		)
		(layer "B.Cu")
	)
	(gr_line
		(start 233.197908 -60.76823)
		(end 233.386884 -60.579254)
		(stroke
			(width 0.087376)
			(type default)
		)
		(layer "B.Cu")
	)
	(gr_line
		(start 248.793 -423.6212)
		(end 248.793 -424.1165)
		(stroke
			(width 0.085598)
			(type default)
		)
		(layer "B.Cu")
	)
	(gr_line
		(start 248.793 -423.6212)
		(end 248.85777 -423.55643)
		(stroke
			(width 0.085598)
			(type default)
		)
		(layer "B.Cu")
	)
	(gr_line
		(start 248.793 -422.7068)
		(end 248.85777 -422.77157)
		(stroke
			(width 0.085598)
			(type default)
		)
		(layer "B.Cu")
	)
	(gr_line
		(start 248.793 -422.2115)
		(end 248.793 -422.7068)
		(stroke
			(width 0.085598)
			(type default)
		)
		(layer "B.Cu")
	)
	(gr_line
		(start 251.931932 -423.559732)
		(end 252.832108 -424.459908)
		(stroke
			(width 0.085598)
			(type default)
		)
		(layer "B.Cu")
	)
	(gr_line
		(start 251.931932 -422.774618)
		(end 252.786642 -421.919908)
		(stroke
			(width 0.085598)
			(type default)
		)
		(layer "B.Cu")
	)
	(gr_line
		(start 252.786642 -421.919908)
		(end 256.093976 -421.919908)
		(stroke
			(width 0.085598)
			(type default)
		)
		(layer "B.Cu")
	)
	(gr_line
		(start 252.832108 -424.459908)
		(end 256.093976 -424.459908)
		(stroke
			(width 0.085598)
			(type default)
		)
		(layer "B.Cu")
	)
	(gr_line
		(start 0 -505.000006)
		(end 0 -421.942006)
		(stroke
			(width 1.524)
			(type default)
		)
		(layer "In1.Cu")
	)
	(gr_arc
		(start 0 -505.000006)
		(mid 0.292895 -505.707108)
		(end 0.999998 -506.000004)
		(stroke
			(width 1.524)
			(type default)
		)
		(layer "In1.Cu")
	)
	(gr_line
		(start 0 -421.942006)
		(end 0.500126 -421.44188)
		(stroke
			(width 1.524)
			(type default)
		)
		(layer "In1.Cu")
	)
	(gr_line
		(start 0 -418.742114)
		(end 0 -315.941964)
		(stroke
			(width 1.524)
			(type default)
		)
		(layer "In1.Cu")
	)
	(gr_line
		(start 0 -315.941964)
		(end 0.500126 -315.442092)
		(stroke
			(width 1.524)
			(type default)
		)
		(layer "In1.Cu")
	)
	(gr_line
		(start 0 -312.742072)
		(end 0 -189.941962)
		(stroke
			(width 1.524)
			(type default)
		)
		(layer "In1.Cu")
	)
	(gr_line
		(start 0 -189.941962)
		(end 0.500126 -189.44209)
		(stroke
			(width 1.524)
			(type default)
		)
		(layer "In1.Cu")
	)
	(gr_line
		(start 0 -186.74207)
		(end 0 -0.999998)
		(stroke
			(width 1.524)
			(type default)
		)
		(layer "In1.Cu")
	)
	(gr_line
		(start 0.500126 -421.44188)
		(end 4.400042 -421.44188)
		(stroke
			(width 1.524)
			(type default)
		)
		(layer "In1.Cu")
	)
	(gr_line
		(start 0.500126 -419.241986)
		(end 0 -418.742114)
		(stroke
			(width 1.524)
			(type default)
		)
		(layer "In1.Cu")
	)
	(gr_line
		(start 0.500126 -315.442092)
		(end 4.400042 -315.442092)
		(stroke
			(width 1.524)
			(type default)
		)
		(layer "In1.Cu")
	)
	(gr_line
		(start 0.500126 -313.241944)
		(end 0 -312.742072)
		(stroke
			(width 1.524)
			(type default)
		)
		(layer "In1.Cu")
	)
	(gr_line
		(start 0.500126 -189.44209)
		(end 4.400042 -189.44209)
		(stroke
			(width 1.524)
			(type default)
		)
		(layer "In1.Cu")
	)
	(gr_line
		(start 0.500126 -187.241942)
		(end 0 -186.74207)
		(stroke
			(width 1.524)
			(type default)
		)
		(layer "In1.Cu")
	)
	(gr_arc
		(start 0.999998 0)
		(mid 0.292893 -0.292893)
		(end 0 -0.999998)
		(stroke
			(width 1.524)
			(type default)
		)
		(layer "In1.Cu")
	)
	(gr_line
		(start 0.999998 0)
		(end 30.80004 0)
		(stroke
			(width 1.524)
			(type default)
		)
		(layer "In1.Cu")
	)
	(gr_rect
		(start 1.005332 -448.4878)
		(end 3.494532 -449.7959)
		(stroke
			(width 0)
			(type default)
		)
		(fill no)
		(layer "In1.Cu")
	)
	(gr_rect
		(start 1.005332 -446.088008)
		(end 3.494532 -447.395854)
		(stroke
			(width 0)
			(type default)
		)
		(fill no)
		(layer "In1.Cu")
	)
	(gr_rect
		(start 1.005332 -442.887862)
		(end 3.494532 -444.195962)
		(stroke
			(width 0)
			(type default)
		)
		(fill no)
		(layer "In1.Cu")
	)
	(gr_rect
		(start 1.005332 -439.68797)
		(end 3.494532 -440.995816)
		(stroke
			(width 0)
			(type default)
		)
		(fill no)
		(layer "In1.Cu")
	)
	(gr_rect
		(start 1.005332 -436.487824)
		(end 3.494532 -437.795924)
		(stroke
			(width 0)
			(type default)
		)
		(fill no)
		(layer "In1.Cu")
	)
	(gr_rect
		(start 1.005332 -430.887886)
		(end 3.494532 -432.195986)
		(stroke
			(width 0)
			(type default)
		)
		(fill no)
		(layer "In1.Cu")
	)
	(gr_rect
		(start 1.005332 -427.687994)
		(end 3.494532 -428.99584)
		(stroke
			(width 0)
			(type default)
		)
		(fill no)
		(layer "In1.Cu")
	)
	(gr_rect
		(start 1.005332 -424.487848)
		(end 3.494532 -425.795948)
		(stroke
			(width 0)
			(type default)
		)
		(fill no)
		(layer "In1.Cu")
	)
	(gr_rect
		(start 1.005332 -414.887918)
		(end 3.494532 -416.196018)
		(stroke
			(width 0)
			(type default)
		)
		(fill no)
		(layer "In1.Cu")
	)
	(gr_rect
		(start 1.005332 -411.687772)
		(end 3.494532 -412.995872)
		(stroke
			(width 0)
			(type default)
		)
		(fill no)
		(layer "In1.Cu")
	)
	(gr_rect
		(start 1.005332 -408.48788)
		(end 3.494532 -409.79598)
		(stroke
			(width 0)
			(type default)
		)
		(fill no)
		(layer "In1.Cu")
	)
	(gr_rect
		(start 1.005332 -405.287988)
		(end 3.494532 -406.595834)
		(stroke
			(width 0)
			(type default)
		)
		(fill no)
		(layer "In1.Cu")
	)
	(gr_rect
		(start 1.005332 -402.087842)
		(end 3.494532 -403.395942)
		(stroke
			(width 0)
			(type default)
		)
		(fill no)
		(layer "In1.Cu")
	)
	(gr_rect
		(start 1.005332 -396.487904)
		(end 3.494532 -397.796004)
		(stroke
			(width 0)
			(type default)
		)
		(fill no)
		(layer "In1.Cu")
	)
	(gr_rect
		(start 1.005332 -393.288012)
		(end 3.494532 -394.595858)
		(stroke
			(width 0)
			(type default)
		)
		(fill no)
		(layer "In1.Cu")
	)
	(gr_rect
		(start 1.005332 -390.087866)
		(end 3.494532 -391.395966)
		(stroke
			(width 0)
			(type default)
		)
		(fill no)
		(layer "In1.Cu")
	)
	(gr_rect
		(start 1.005332 -386.887974)
		(end 3.494532 -388.19582)
		(stroke
			(width 0)
			(type default)
		)
		(fill no)
		(layer "In1.Cu")
	)
	(gr_rect
		(start 1.005332 -384.487928)
		(end 3.494532 -385.795774)
		(stroke
			(width 0)
			(type default)
		)
		(fill no)
		(layer "In1.Cu")
	)
	(gr_rect
		(start 1.005332 -356.088188)
		(end 3.494532 -357.396034)
		(stroke
			(width 0)
			(type default)
		)
		(fill no)
		(layer "In1.Cu")
	)
	(gr_rect
		(start 1.005332 -352.888042)
		(end 3.494532 -354.196142)
		(stroke
			(width 0)
			(type default)
		)
		(fill no)
		(layer "In1.Cu")
	)
	(gr_rect
		(start 1.005332 -349.68815)
		(end 3.494532 -350.995996)
		(stroke
			(width 0)
			(type default)
		)
		(fill no)
		(layer "In1.Cu")
	)
	(gr_rect
		(start 1.005332 -346.488004)
		(end 3.494532 -347.796104)
		(stroke
			(width 0)
			(type default)
		)
		(fill no)
		(layer "In1.Cu")
	)
	(gr_rect
		(start 1.005332 -343.288112)
		(end 3.494532 -344.596212)
		(stroke
			(width 0)
			(type default)
		)
		(fill no)
		(layer "In1.Cu")
	)
	(gr_rect
		(start 1.005332 -340.08822)
		(end 3.494532 -341.396066)
		(stroke
			(width 0)
			(type default)
		)
		(fill no)
		(layer "In1.Cu")
	)
	(gr_rect
		(start 1.005332 -336.888074)
		(end 3.494532 -338.196174)
		(stroke
			(width 0)
			(type default)
		)
		(fill no)
		(layer "In1.Cu")
	)
	(gr_rect
		(start 1.005332 -333.688182)
		(end 3.494532 -334.996028)
		(stroke
			(width 0)
			(type default)
		)
		(fill no)
		(layer "In1.Cu")
	)
	(gr_rect
		(start 1.005332 -328.08799)
		(end 3.494532 -329.39609)
		(stroke
			(width 0)
			(type default)
		)
		(fill no)
		(layer "In1.Cu")
	)
	(gr_rect
		(start 1.005332 -324.888098)
		(end 3.494532 -326.196198)
		(stroke
			(width 0)
			(type default)
		)
		(fill no)
		(layer "In1.Cu")
	)
	(gr_rect
		(start 1.005332 -321.688206)
		(end 3.494532 -322.996052)
		(stroke
			(width 0)
			(type default)
		)
		(fill no)
		(layer "In1.Cu")
	)
	(gr_rect
		(start 1.005332 -318.48806)
		(end 3.494532 -319.79616)
		(stroke
			(width 0)
			(type default)
		)
		(fill no)
		(layer "In1.Cu")
	)
	(gr_rect
		(start 1.005332 -310.488076)
		(end 3.494532 -311.796176)
		(stroke
			(width 0)
			(type default)
		)
		(fill no)
		(layer "In1.Cu")
	)
	(gr_rect
		(start 1.005332 -307.288184)
		(end 3.494532 -308.59603)
		(stroke
			(width 0)
			(type default)
		)
		(fill no)
		(layer "In1.Cu")
	)
	(gr_rect
		(start 1.005332 -304.088038)
		(end 3.494532 -305.396138)
		(stroke
			(width 0)
			(type default)
		)
		(fill no)
		(layer "In1.Cu")
	)
	(gr_rect
		(start 1.005332 -300.888146)
		(end 3.494532 -302.195992)
		(stroke
			(width 0)
			(type default)
		)
		(fill no)
		(layer "In1.Cu")
	)
	(gr_rect
		(start 1.005332 -297.688)
		(end 3.494532 -298.9961)
		(stroke
			(width 0)
			(type default)
		)
		(fill no)
		(layer "In1.Cu")
	)
	(gr_rect
		(start 1.005332 -294.488108)
		(end 3.494532 -295.796208)
		(stroke
			(width 0)
			(type default)
		)
		(fill no)
		(layer "In1.Cu")
	)
	(gr_rect
		(start 1.005332 -291.288216)
		(end 3.494532 -292.596062)
		(stroke
			(width 0)
			(type default)
		)
		(fill no)
		(layer "In1.Cu")
	)
	(gr_rect
		(start 1.005332 -288.08807)
		(end 3.494532 -289.39617)
		(stroke
			(width 0)
			(type default)
		)
		(fill no)
		(layer "In1.Cu")
	)
	(gr_rect
		(start 1.005332 -281.688032)
		(end 3.494532 -282.996132)
		(stroke
			(width 0)
			(type default)
		)
		(fill no)
		(layer "In1.Cu")
	)
	(gr_rect
		(start 1.005332 -278.48814)
		(end 3.494532 -279.795986)
		(stroke
			(width 0)
			(type default)
		)
		(fill no)
		(layer "In1.Cu")
	)
	(gr_rect
		(start 1.005332 -230.088186)
		(end 3.494532 -231.396032)
		(stroke
			(width 0)
			(type default)
		)
		(fill no)
		(layer "In1.Cu")
	)
	(gr_rect
		(start 1.005332 -226.88804)
		(end 3.494532 -228.19614)
		(stroke
			(width 0)
			(type default)
		)
		(fill no)
		(layer "In1.Cu")
	)
	(gr_rect
		(start 1.005332 -223.688148)
		(end 3.494532 -224.995994)
		(stroke
			(width 0)
			(type default)
		)
		(fill no)
		(layer "In1.Cu")
	)
	(gr_rect
		(start 1.005332 -220.488002)
		(end 3.494532 -221.796102)
		(stroke
			(width 0)
			(type default)
		)
		(fill no)
		(layer "In1.Cu")
	)
	(gr_rect
		(start 1.005332 -217.28811)
		(end 3.494532 -218.59621)
		(stroke
			(width 0)
			(type default)
		)
		(fill no)
		(layer "In1.Cu")
	)
	(gr_rect
		(start 1.005332 -214.088218)
		(end 3.494532 -215.396064)
		(stroke
			(width 0)
			(type default)
		)
		(fill no)
		(layer "In1.Cu")
	)
	(gr_rect
		(start 1.005332 -210.888072)
		(end 3.494532 -212.196172)
		(stroke
			(width 0)
			(type default)
		)
		(fill no)
		(layer "In1.Cu")
	)
	(gr_rect
		(start 1.005332 -207.68818)
		(end 3.494532 -208.996026)
		(stroke
			(width 0)
			(type default)
		)
		(fill no)
		(layer "In1.Cu")
	)
	(gr_rect
		(start 1.005332 -204.488034)
		(end 3.494532 -205.796134)
		(stroke
			(width 0)
			(type default)
		)
		(fill no)
		(layer "In1.Cu")
	)
	(gr_rect
		(start 1.005332 -201.288142)
		(end 3.494532 -202.595988)
		(stroke
			(width 0)
			(type default)
		)
		(fill no)
		(layer "In1.Cu")
	)
	(gr_rect
		(start 1.005332 -195.688204)
		(end 3.494532 -196.99605)
		(stroke
			(width 0)
			(type default)
		)
		(fill no)
		(layer "In1.Cu")
	)
	(gr_rect
		(start 1.005332 -192.488058)
		(end 3.494532 -193.796158)
		(stroke
			(width 0)
			(type default)
		)
		(fill no)
		(layer "In1.Cu")
	)
	(gr_rect
		(start 1.005332 -184.488074)
		(end 3.494532 -185.796174)
		(stroke
			(width 0)
			(type default)
		)
		(fill no)
		(layer "In1.Cu")
	)
	(gr_rect
		(start 1.005332 -181.288182)
		(end 3.494532 -182.596028)
		(stroke
			(width 0)
			(type default)
		)
		(fill no)
		(layer "In1.Cu")
	)
	(gr_rect
		(start 1.005332 -178.088036)
		(end 3.494532 -179.396136)
		(stroke
			(width 0)
			(type default)
		)
		(fill no)
		(layer "In1.Cu")
	)
	(gr_rect
		(start 1.005332 -174.888144)
		(end 3.494532 -176.19599)
		(stroke
			(width 0)
			(type default)
		)
		(fill no)
		(layer "In1.Cu")
	)
	(gr_rect
		(start 1.005332 -171.687998)
		(end 3.494532 -172.996098)
		(stroke
			(width 0)
			(type default)
		)
		(fill no)
		(layer "In1.Cu")
	)
	(gr_rect
		(start 1.005332 -168.488106)
		(end 3.494532 -169.796206)
		(stroke
			(width 0)
			(type default)
		)
		(fill no)
		(layer "In1.Cu")
	)
	(gr_rect
		(start 1.005332 -162.088068)
		(end 3.494532 -163.396168)
		(stroke
			(width 0)
			(type default)
		)
		(fill no)
		(layer "In1.Cu")
	)
	(gr_rect
		(start 1.005332 -158.888176)
		(end 3.494532 -160.196022)
		(stroke
			(width 0)
			(type default)
		)
		(fill no)
		(layer "In1.Cu")
	)
	(gr_rect
		(start 1.005332 -155.68803)
		(end 3.494532 -156.99613)
		(stroke
			(width 0)
			(type default)
		)
		(fill no)
		(layer "In1.Cu")
	)
	(gr_rect
		(start 1.005332 -152.488138)
		(end 3.494532 -153.795984)
		(stroke
			(width 0)
			(type default)
		)
		(fill no)
		(layer "In1.Cu")
	)
	(gr_arc
		(start 4.400042 -421.44188)
		(mid 5.499862 -420.34206)
		(end 4.400042 -419.241986)
		(stroke
			(width 1.524)
			(type default)
		)
		(layer "In1.Cu")
	)
	(gr_line
		(start 4.400042 -419.241986)
		(end 0.500126 -419.241986)
		(stroke
			(width 1.524)
			(type default)
		)
		(layer "In1.Cu")
	)
	(gr_arc
		(start 4.400042 -315.442092)
		(mid 5.500116 -314.342018)
		(end 4.400042 -313.241944)
		(stroke
			(width 1.524)
			(type default)
		)
		(layer "In1.Cu")
	)
	(gr_line
		(start 4.400042 -313.241944)
		(end 0.500126 -313.241944)
		(stroke
			(width 1.524)
			(type default)
		)
		(layer "In1.Cu")
	)
	(gr_arc
		(start 4.400042 -189.44209)
		(mid 5.500116 -188.342016)
		(end 4.400042 -187.241942)
		(stroke
			(width 1.524)
			(type default)
		)
		(layer "In1.Cu")
	)
	(gr_line
		(start 4.400042 -187.241942)
		(end 0.500126 -187.241942)
		(stroke
			(width 1.524)
			(type default)
		)
		(layer "In1.Cu")
	)
	(gr_arc
		(start 4.56946 -445.54775)
		(mid 5.079873 -446.058544)
		(end 5.59054 -445.548004)
		(stroke
			(width 0.2)
			(type default)
		)
		(layer "In1.Cu")
	)
	(gr_line
		(start 4.56946 -444.735204)
		(end 4.56946 -445.54775)
		(stroke
			(width 0.2)
			(type default)
		)
		(layer "In1.Cu")
	)
	(gr_arc
		(start 4.56946 -442.347858)
		(mid 5.079873 -442.858652)
		(end 5.59054 -442.348112)
		(stroke
			(width 0.2)
			(type default)
		)
		(layer "In1.Cu")
	)
	(gr_line
		(start 4.56946 -441.535312)
		(end 4.56946 -442.347858)
		(stroke
			(width 0.2)
			(type default)
		)
		(layer "In1.Cu")
	)
	(gr_arc
		(start 4.56946 -439.147712)
		(mid 5.079873 -439.658506)
		(end 5.59054 -439.147966)
		(stroke
			(width 0.2)
			(type default)
		)
		(layer "In1.Cu")
	)
	(gr_line
		(start 4.56946 -438.335166)
		(end 4.56946 -439.147712)
		(stroke
			(width 0.2)
			(type default)
		)
		(layer "In1.Cu")
	)
	(gr_arc
		(start 4.56946 -435.94782)
		(mid 5.079873 -436.458614)
		(end 5.59054 -435.948074)
		(stroke
			(width 0.2)
			(type default)
		)
		(layer "In1.Cu")
	)
	(gr_line
		(start 4.56946 -435.135274)
		(end 4.56946 -435.94782)
		(stroke
			(width 0.2)
			(type default)
		)
		(layer "In1.Cu")
	)
	(gr_arc
		(start 4.56946 -430.347882)
		(mid 5.08 -430.858422)
		(end 5.59054 -430.347882)
		(stroke
			(width 0.2)
			(type default)
		)
		(layer "In1.Cu")
	)
	(gr_line
		(start 4.56946 -429.535082)
		(end 4.56946 -430.347882)
		(stroke
			(width 0.2)
			(type default)
		)
		(layer "In1.Cu")
	)
	(gr_arc
		(start 4.56946 -427.14799)
		(mid 5.08 -427.65853)
		(end 5.59054 -427.14799)
		(stroke
			(width 0.2)
			(type default)
		)
		(layer "In1.Cu")
	)
	(gr_line
		(start 4.56946 -426.33519)
		(end 4.56946 -427.14799)
		(stroke
			(width 0.2)
			(type default)
		)
		(layer "In1.Cu")
	)
	(gr_arc
		(start 4.56946 -423.948098)
		(mid 5.08 -424.458638)
		(end 5.59054 -423.948098)
		(stroke
			(width 0.2)
			(type default)
		)
		(layer "In1.Cu")
	)
	(gr_line
		(start 4.56946 -423.135298)
		(end 4.56946 -423.948098)
		(stroke
			(width 0.2)
			(type default)
		)
		(layer "In1.Cu")
	)
	(gr_arc
		(start 4.56946 -417.54806)
		(mid 5.08 -418.0586)
		(end 5.59054 -417.54806)
		(stroke
			(width 0.2)
			(type default)
		)
		(layer "In1.Cu")
	)
	(gr_line
		(start 4.56946 -416.73526)
		(end 4.56946 -417.54806)
		(stroke
			(width 0.2)
			(type default)
		)
		(layer "In1.Cu")
	)
	(gr_arc
		(start 4.56946 -414.34766)
		(mid 5.079873 -414.858454)
		(end 5.59054 -414.347914)
		(stroke
			(width 0.2)
			(type default)
		)
		(layer "In1.Cu")
	)
	(gr_line
		(start 4.56946 -413.535114)
		(end 4.56946 -414.34766)
		(stroke
			(width 0.2)
			(type default)
		)
		(layer "In1.Cu")
	)
	(gr_arc
		(start 4.56946 -411.147768)
		(mid 5.079873 -411.658562)
		(end 5.59054 -411.148022)
		(stroke
			(width 0.2)
			(type default)
		)
		(layer "In1.Cu")
	)
	(gr_line
		(start 4.56946 -410.335222)
		(end 4.56946 -411.147768)
		(stroke
			(width 0.2)
			(type default)
		)
		(layer "In1.Cu")
	)
	(gr_arc
		(start 4.56946 -407.947622)
		(mid 5.079873 -408.458416)
		(end 5.59054 -407.947876)
		(stroke
			(width 0.2)
			(type default)
		)
		(layer "In1.Cu")
	)
	(gr_line
		(start 4.56946 -407.135076)
		(end 4.56946 -407.947622)
		(stroke
			(width 0.2)
			(type default)
		)
		(layer "In1.Cu")
	)
	(gr_arc
		(start 4.56946 -404.74773)
		(mid 5.079873 -405.258524)
		(end 5.59054 -404.747984)
		(stroke
			(width 0.2)
			(type default)
		)
		(layer "In1.Cu")
	)
	(gr_line
		(start 4.56946 -403.935184)
		(end 4.56946 -404.74773)
		(stroke
			(width 0.2)
			(type default)
		)
		(layer "In1.Cu")
	)
	(gr_arc
		(start 4.56946 -399.148046)
		(mid 5.08 -399.658586)
		(end 5.59054 -399.148046)
		(stroke
			(width 0.2)
			(type default)
		)
		(layer "In1.Cu")
	)
	(gr_line
		(start 4.56946 -398.335246)
		(end 4.56946 -399.148046)
		(stroke
			(width 0.2)
			(type default)
		)
		(layer "In1.Cu")
	)
	(gr_arc
		(start 4.56946 -395.9479)
		(mid 5.08 -396.45844)
		(end 5.59054 -395.9479)
		(stroke
			(width 0.2)
			(type default)
		)
		(layer "In1.Cu")
	)
	(gr_line
		(start 4.56946 -395.1351)
		(end 4.56946 -395.9479)
		(stroke
			(width 0.2)
			(type default)
		)
		(layer "In1.Cu")
	)
	(gr_arc
		(start 4.56946 -392.748008)
		(mid 5.08 -393.258548)
		(end 5.59054 -392.748008)
		(stroke
			(width 0.2)
			(type default)
		)
		(layer "In1.Cu")
	)
	(gr_line
		(start 4.56946 -391.935208)
		(end 4.56946 -392.748008)
		(stroke
			(width 0.2)
			(type default)
		)
		(layer "In1.Cu")
	)
	(gr_arc
		(start 4.56946 -389.548116)
		(mid 5.08 -390.058656)
		(end 5.59054 -389.548116)
		(stroke
			(width 0.2)
			(type default)
		)
		(layer "In1.Cu")
	)
	(gr_line
		(start 4.56946 -388.735316)
		(end 4.56946 -389.548116)
		(stroke
			(width 0.2)
			(type default)
		)
		(layer "In1.Cu")
	)
	(gr_arc
		(start 4.56946 -358.74833)
		(mid 5.08 -359.25887)
		(end 5.59054 -358.74833)
		(stroke
			(width 0.2)
			(type default)
		)
		(layer "In1.Cu")
	)
	(gr_line
		(start 4.56946 -357.93553)
		(end 4.56946 -358.74833)
		(stroke
			(width 0.2)
			(type default)
		)
		(layer "In1.Cu")
	)
	(gr_arc
		(start 4.56946 -355.548184)
		(mid 5.08 -356.058724)
		(end 5.59054 -355.548184)
		(stroke
			(width 0.2)
			(type default)
		)
		(layer "In1.Cu")
	)
	(gr_line
		(start 4.56946 -354.735384)
		(end 4.56946 -355.548184)
		(stroke
			(width 0.2)
			(type default)
		)
		(layer "In1.Cu")
	)
	(gr_arc
		(start 4.56946 -352.348292)
		(mid 5.08 -352.858832)
		(end 5.59054 -352.348292)
		(stroke
			(width 0.2)
			(type default)
		)
		(layer "In1.Cu")
	)
	(gr_line
		(start 4.56946 -351.535492)
		(end 4.56946 -352.348292)
		(stroke
			(width 0.2)
			(type default)
		)
		(layer "In1.Cu")
	)
	(gr_arc
		(start 4.56946 -349.148146)
		(mid 5.08 -349.658686)
		(end 5.59054 -349.148146)
		(stroke
			(width 0.2)
			(type default)
		)
		(layer "In1.Cu")
	)
	(gr_line
		(start 4.56946 -348.335346)
		(end 4.56946 -349.148146)
		(stroke
			(width 0.2)
			(type default)
		)
		(layer "In1.Cu")
	)
	(gr_arc
		(start 4.56946 -345.948254)
		(mid 5.08 -346.458794)
		(end 5.59054 -345.948254)
		(stroke
			(width 0.2)
			(type default)
		)
		(layer "In1.Cu")
	)
	(gr_line
		(start 4.56946 -345.135454)
		(end 4.56946 -345.948254)
		(stroke
			(width 0.2)
			(type default)
		)
		(layer "In1.Cu")
	)
	(gr_arc
		(start 4.56946 -342.748108)
		(mid 5.08 -343.258648)
		(end 5.59054 -342.748108)
		(stroke
			(width 0.2)
			(type default)
		)
		(layer "In1.Cu")
	)
	(gr_line
		(start 4.56946 -341.935308)
		(end 4.56946 -342.748108)
		(stroke
			(width 0.2)
			(type default)
		)
		(layer "In1.Cu")
	)
	(gr_arc
		(start 4.56946 -339.548216)
		(mid 5.08 -340.058756)
		(end 5.59054 -339.548216)
		(stroke
			(width 0.2)
			(type default)
		)
		(layer "In1.Cu")
	)
	(gr_line
		(start 4.56946 -338.735416)
		(end 4.56946 -339.548216)
		(stroke
			(width 0.2)
			(type default)
		)
		(layer "In1.Cu")
	)
	(gr_arc
		(start 4.56946 -336.348324)
		(mid 5.08 -336.858864)
		(end 5.59054 -336.348324)
		(stroke
			(width 0.2)
			(type default)
		)
		(layer "In1.Cu")
	)
	(gr_line
		(start 4.56946 -335.535524)
		(end 4.56946 -336.348324)
		(stroke
			(width 0.2)
			(type default)
		)
		(layer "In1.Cu")
	)
	(gr_arc
		(start 4.56946 -330.748132)
		(mid 5.08 -331.258672)
		(end 5.59054 -330.748132)
		(stroke
			(width 0.2)
			(type default)
		)
		(layer "In1.Cu")
	)
	(gr_line
		(start 4.56946 -329.935332)
		(end 4.56946 -330.748132)
		(stroke
			(width 0.2)
			(type default)
		)
		(layer "In1.Cu")
	)
	(gr_arc
		(start 4.56946 -327.54824)
		(mid 5.08 -328.05878)
		(end 5.59054 -327.54824)
		(stroke
			(width 0.2)
			(type default)
		)
		(layer "In1.Cu")
	)
	(gr_line
		(start 4.56946 -326.73544)
		(end 4.56946 -327.54824)
		(stroke
			(width 0.2)
			(type default)
		)
		(layer "In1.Cu")
	)
	(gr_arc
		(start 4.56946 -324.348094)
		(mid 5.08 -324.858634)
		(end 5.59054 -324.348094)
		(stroke
			(width 0.2)
			(type default)
		)
		(layer "In1.Cu")
	)
	(gr_line
		(start 4.56946 -323.535294)
		(end 4.56946 -324.348094)
		(stroke
			(width 0.2)
			(type default)
		)
		(layer "In1.Cu")
	)
	(gr_arc
		(start 4.56946 -321.148202)
		(mid 5.08 -321.658742)
		(end 5.59054 -321.148202)
		(stroke
			(width 0.2)
			(type default)
		)
		(layer "In1.Cu")
	)
	(gr_line
		(start 4.56946 -320.335402)
		(end 4.56946 -321.148202)
		(stroke
			(width 0.2)
			(type default)
		)
		(layer "In1.Cu")
	)
	(gr_arc
		(start 4.56946 -317.94831)
		(mid 5.08 -318.45885)
		(end 5.59054 -317.94831)
		(stroke
			(width 0.2)
			(type default)
		)
		(layer "In1.Cu")
	)
	(gr_line
		(start 4.56946 -317.13551)
		(end 4.56946 -317.94831)
		(stroke
			(width 0.2)
			(type default)
		)
		(layer "In1.Cu")
	)
	(gr_arc
		(start 4.56946 -309.948326)
		(mid 5.08 -310.458866)
		(end 5.59054 -309.948326)
		(stroke
			(width 0.2)
			(type default)
		)
		(layer "In1.Cu")
	)
	(gr_line
		(start 4.56946 -309.135526)
		(end 4.56946 -309.948326)
		(stroke
			(width 0.2)
			(type default)
		)
		(layer "In1.Cu")
	)
	(gr_arc
		(start 4.56946 -306.74818)
		(mid 5.08 -307.25872)
		(end 5.59054 -306.74818)
		(stroke
			(width 0.2)
			(type default)
		)
		(layer "In1.Cu")
	)
	(gr_line
		(start 4.56946 -305.93538)
		(end 4.56946 -306.74818)
		(stroke
			(width 0.2)
			(type default)
		)
		(layer "In1.Cu")
	)
	(gr_arc
		(start 4.56946 -303.548288)
		(mid 5.08 -304.058828)
		(end 5.59054 -303.548288)
		(stroke
			(width 0.2)
			(type default)
		)
		(layer "In1.Cu")
	)
	(gr_line
		(start 4.56946 -302.735488)
		(end 4.56946 -303.548288)
		(stroke
			(width 0.2)
			(type default)
		)
		(layer "In1.Cu")
	)
	(gr_arc
		(start 4.56946 -300.348142)
		(mid 5.08 -300.858682)
		(end 5.59054 -300.348142)
		(stroke
			(width 0.2)
			(type default)
		)
		(layer "In1.Cu")
	)
	(gr_line
		(start 4.56946 -299.535342)
		(end 4.56946 -300.348142)
		(stroke
			(width 0.2)
			(type default)
		)
		(layer "In1.Cu")
	)
	(gr_arc
		(start 4.56946 -297.14825)
		(mid 5.08 -297.65879)
		(end 5.59054 -297.14825)
		(stroke
			(width 0.2)
			(type default)
		)
		(layer "In1.Cu")
	)
	(gr_line
		(start 4.56946 -296.33545)
		(end 4.56946 -297.14825)
		(stroke
			(width 0.2)
			(type default)
		)
		(layer "In1.Cu")
	)
	(gr_arc
		(start 4.56946 -293.948104)
		(mid 5.08 -294.458644)
		(end 5.59054 -293.948104)
		(stroke
			(width 0.2)
			(type default)
		)
		(layer "In1.Cu")
	)
	(gr_line
		(start 4.56946 -293.135304)
		(end 4.56946 -293.948104)
		(stroke
			(width 0.2)
			(type default)
		)
		(layer "In1.Cu")
	)
	(gr_arc
		(start 4.56946 -290.748212)
		(mid 5.08 -291.258752)
		(end 5.59054 -290.748212)
		(stroke
			(width 0.2)
			(type default)
		)
		(layer "In1.Cu")
	)
	(gr_line
		(start 4.56946 -289.935412)
		(end 4.56946 -290.748212)
		(stroke
			(width 0.2)
			(type default)
		)
		(layer "In1.Cu")
	)
	(gr_arc
		(start 4.56946 -284.348174)
		(mid 5.08 -284.858714)
		(end 5.59054 -284.348174)
		(stroke
			(width 0.2)
			(type default)
		)
		(layer "In1.Cu")
	)
	(gr_line
		(start 4.56946 -283.535374)
		(end 4.56946 -284.348174)
		(stroke
			(width 0.2)
			(type default)
		)
		(layer "In1.Cu")
	)
	(gr_arc
		(start 4.56946 -281.148282)
		(mid 5.08 -281.658822)
		(end 5.59054 -281.148282)
		(stroke
			(width 0.2)
			(type default)
		)
		(layer "In1.Cu")
	)
	(gr_line
		(start 4.56946 -280.335482)
		(end 4.56946 -281.148282)
		(stroke
			(width 0.2)
			(type default)
		)
		(layer "In1.Cu")
	)
	(gr_arc
		(start 4.56946 -232.748328)
		(mid 5.08 -233.258868)
		(end 5.59054 -232.748328)
		(stroke
			(width 0.2)
			(type default)
		)
		(layer "In1.Cu")
	)
	(gr_line
		(start 4.56946 -231.935528)
		(end 4.56946 -232.748328)
		(stroke
			(width 0.2)
			(type default)
		)
		(layer "In1.Cu")
	)
	(gr_arc
		(start 4.56946 -229.548182)
		(mid 5.08 -230.058722)
		(end 5.59054 -229.548182)
		(stroke
			(width 0.2)
			(type default)
		)
		(layer "In1.Cu")
	)
	(gr_line
		(start 4.56946 -228.735382)
		(end 4.56946 -229.548182)
		(stroke
			(width 0.2)
			(type default)
		)
		(layer "In1.Cu")
	)
	(gr_arc
		(start 4.56946 -223.148144)
		(mid 5.08 -223.658684)
		(end 5.59054 -223.148144)
		(stroke
			(width 0.2)
			(type default)
		)
		(layer "In1.Cu")
	)
	(gr_line
		(start 4.56946 -222.335344)
		(end 4.56946 -223.148144)
		(stroke
			(width 0.2)
			(type default)
		)
		(layer "In1.Cu")
	)
	(gr_arc
		(start 4.56946 -219.948252)
		(mid 5.08 -220.458792)
		(end 5.59054 -219.948252)
		(stroke
			(width 0.2)
			(type default)
		)
		(layer "In1.Cu")
	)
	(gr_line
		(start 4.56946 -219.135452)
		(end 4.56946 -219.948252)
		(stroke
			(width 0.2)
			(type default)
		)
		(layer "In1.Cu")
	)
	(gr_arc
		(start 4.56946 -216.748106)
		(mid 5.08 -217.258646)
		(end 5.59054 -216.748106)
		(stroke
			(width 0.2)
			(type default)
		)
		(layer "In1.Cu")
	)
	(gr_line
		(start 4.56946 -215.935306)
		(end 4.56946 -216.748106)
		(stroke
			(width 0.2)
			(type default)
		)
		(layer "In1.Cu")
	)
	(gr_arc
		(start 4.56946 -213.548214)
		(mid 5.08 -214.058754)
		(end 5.59054 -213.548214)
		(stroke
			(width 0.2)
			(type default)
		)
		(layer "In1.Cu")
	)
	(gr_line
		(start 4.56946 -212.735414)
		(end 4.56946 -213.548214)
		(stroke
			(width 0.2)
			(type default)
		)
		(layer "In1.Cu")
	)
	(gr_arc
		(start 4.56946 -210.348322)
		(mid 5.08 -210.858862)
		(end 5.59054 -210.348322)
		(stroke
			(width 0.2)
			(type default)
		)
		(layer "In1.Cu")
	)
	(gr_line
		(start 4.56946 -209.535522)
		(end 4.56946 -210.348322)
		(stroke
			(width 0.2)
			(type default)
		)
		(layer "In1.Cu")
	)
	(gr_arc
		(start 4.56946 -207.148176)
		(mid 5.08 -207.658716)
		(end 5.59054 -207.148176)
		(stroke
			(width 0.2)
			(type default)
		)
		(layer "In1.Cu")
	)
	(gr_line
		(start 4.56946 -206.335376)
		(end 4.56946 -207.148176)
		(stroke
			(width 0.2)
			(type default)
		)
		(layer "In1.Cu")
	)
	(gr_arc
		(start 4.56946 -203.948284)
		(mid 5.08 -204.458824)
		(end 5.59054 -203.948284)
		(stroke
			(width 0.2)
			(type default)
		)
		(layer "In1.Cu")
	)
	(gr_line
		(start 4.56946 -203.135484)
		(end 4.56946 -203.948284)
		(stroke
			(width 0.2)
			(type default)
		)
		(layer "In1.Cu")
	)
	(gr_arc
		(start 4.56946 -200.748138)
		(mid 5.08 -201.258678)
		(end 5.59054 -200.748138)
		(stroke
			(width 0.2)
			(type default)
		)
		(layer "In1.Cu")
	)
	(gr_line
		(start 4.56946 -199.935338)
		(end 4.56946 -200.748138)
		(stroke
			(width 0.2)
			(type default)
		)
		(layer "In1.Cu")
	)
	(gr_arc
		(start 4.56946 -195.1482)
		(mid 5.08 -195.65874)
		(end 5.59054 -195.1482)
		(stroke
			(width 0.2)
			(type default)
		)
		(layer "In1.Cu")
	)
	(gr_line
		(start 4.56946 -194.3354)
		(end 4.56946 -195.1482)
		(stroke
			(width 0.2)
			(type default)
		)
		(layer "In1.Cu")
	)
	(gr_arc
		(start 4.56946 -191.948308)
		(mid 5.08 -192.458848)
		(end 5.59054 -191.948308)
		(stroke
			(width 0.2)
			(type default)
		)
		(layer "In1.Cu")
	)
	(gr_line
		(start 4.56946 -191.135508)
		(end 4.56946 -191.948308)
		(stroke
			(width 0.2)
			(type default)
		)
		(layer "In1.Cu")
	)
	(gr_arc
		(start 4.56946 -183.948324)
		(mid 5.08 -184.458864)
		(end 5.59054 -183.948324)
		(stroke
			(width 0.2)
			(type default)
		)
		(layer "In1.Cu")
	)
	(gr_line
		(start 4.56946 -183.135524)
		(end 4.56946 -183.948324)
		(stroke
			(width 0.2)
			(type default)
		)
		(layer "In1.Cu")
	)
	(gr_arc
		(start 4.56946 -180.748178)
		(mid 5.08 -181.258718)
		(end 5.59054 -180.748178)
		(stroke
			(width 0.2)
			(type default)
		)
		(layer "In1.Cu")
	)
	(gr_line
		(start 4.56946 -179.935378)
		(end 4.56946 -180.748178)
		(stroke
			(width 0.2)
			(type default)
		)
		(layer "In1.Cu")
	)
	(gr_arc
		(start 4.56946 -177.548286)
		(mid 5.08 -178.058826)
		(end 5.59054 -177.548286)
		(stroke
			(width 0.2)
			(type default)
		)
		(layer "In1.Cu")
	)
	(gr_line
		(start 4.56946 -176.735486)
		(end 4.56946 -177.548286)
		(stroke
			(width 0.2)
			(type default)
		)
		(layer "In1.Cu")
	)
	(gr_arc
		(start 4.56946 -174.34814)
		(mid 5.08 -174.85868)
		(end 5.59054 -174.34814)
		(stroke
			(width 0.2)
			(type default)
		)
		(layer "In1.Cu")
	)
	(gr_line
		(start 4.56946 -173.53534)
		(end 4.56946 -174.34814)
		(stroke
			(width 0.2)
			(type default)
		)
		(layer "In1.Cu")
	)
	(gr_arc
		(start 4.56946 -171.148248)
		(mid 5.08 -171.658788)
		(end 5.59054 -171.148248)
		(stroke
			(width 0.2)
			(type default)
		)
		(layer "In1.Cu")
	)
	(gr_line
		(start 4.56946 -170.335448)
		(end 4.56946 -171.148248)
		(stroke
			(width 0.2)
			(type default)
		)
		(layer "In1.Cu")
	)
	(gr_arc
		(start 4.56946 -167.948102)
		(mid 5.08 -168.458642)
		(end 5.59054 -167.948102)
		(stroke
			(width 0.2)
			(type default)
		)
		(layer "In1.Cu")
	)
	(gr_line
		(start 4.56946 -167.135302)
		(end 4.56946 -167.948102)
		(stroke
			(width 0.2)
			(type default)
		)
		(layer "In1.Cu")
	)
	(gr_arc
		(start 4.56946 -164.74821)
		(mid 5.08 -165.25875)
		(end 5.59054 -164.74821)
		(stroke
			(width 0.2)
			(type default)
		)
		(layer "In1.Cu")
	)
	(gr_line
		(start 4.56946 -163.93541)
		(end 4.56946 -164.74821)
		(stroke
			(width 0.2)
			(type default)
		)
		(layer "In1.Cu")
	)
	(gr_arc
		(start 4.56946 -161.548318)
		(mid 5.08 -162.058858)
		(end 5.59054 -161.548318)
		(stroke
			(width 0.2)
			(type default)
		)
		(layer "In1.Cu")
	)
	(gr_line
		(start 4.56946 -160.735518)
		(end 4.56946 -161.548318)
		(stroke
			(width 0.2)
			(type default)
		)
		(layer "In1.Cu")
	)
	(gr_arc
		(start 4.56946 -158.348172)
		(mid 5.08 -158.858712)
		(end 5.59054 -158.348172)
		(stroke
			(width 0.2)
			(type default)
		)
		(layer "In1.Cu")
	)
	(gr_line
		(start 4.56946 -157.535372)
		(end 4.56946 -158.348172)
		(stroke
			(width 0.2)
			(type default)
		)
		(layer "In1.Cu")
	)
	(gr_arc
		(start 4.56946 -155.14828)
		(mid 5.08 -155.65882)
		(end 5.59054 -155.14828)
		(stroke
			(width 0.2)
			(type default)
		)
		(layer "In1.Cu")
	)
	(gr_line
		(start 4.56946 -154.33548)
		(end 4.56946 -155.14828)
		(stroke
			(width 0.2)
			(type default)
		)
		(layer "In1.Cu")
	)
	(gr_line
		(start 5.59054 -445.548004)
		(end 5.59054 -444.735204)
		(stroke
			(width 0.2)
			(type default)
		)
		(layer "In1.Cu")
	)
	(gr_arc
		(start 5.59054 -444.735204)
		(mid 5.08 -444.224664)
		(end 4.56946 -444.735204)
		(stroke
			(width 0.2)
			(type default)
		)
		(layer "In1.Cu")
	)
	(gr_line
		(start 5.59054 -442.348112)
		(end 5.59054 -441.535312)
		(stroke
			(width 0.2)
			(type default)
		)
		(layer "In1.Cu")
	)
	(gr_arc
		(start 5.59054 -441.535312)
		(mid 5.08 -441.024772)
		(end 4.56946 -441.535312)
		(stroke
			(width 0.2)
			(type default)
		)
		(layer "In1.Cu")
	)
	(gr_line
		(start 5.59054 -439.147966)
		(end 5.59054 -438.335166)
		(stroke
			(width 0.2)
			(type default)
		)
		(layer "In1.Cu")
	)
	(gr_arc
		(start 5.59054 -438.335166)
		(mid 5.08 -437.824626)
		(end 4.56946 -438.335166)
		(stroke
			(width 0.2)
			(type default)
		)
		(layer "In1.Cu")
	)
	(gr_line
		(start 5.59054 -435.948074)
		(end 5.59054 -435.135274)
		(stroke
			(width 0.2)
			(type default)
		)
		(layer "In1.Cu")
	)
	(gr_arc
		(start 5.59054 -435.135274)
		(mid 5.08 -434.624734)
		(end 4.56946 -435.135274)
		(stroke
			(width 0.2)
			(type default)
		)
		(layer "In1.Cu")
	)
	(gr_line
		(start 5.59054 -430.347882)
		(end 5.59054 -429.535336)
		(stroke
			(width 0.2)
			(type default)
		)
		(layer "In1.Cu")
	)
	(gr_arc
		(start 5.59054 -429.535336)
		(mid 5.080127 -429.024542)
		(end 4.56946 -429.535082)
		(stroke
			(width 0.2)
			(type default)
		)
		(layer "In1.Cu")
	)
	(gr_line
		(start 5.59054 -427.14799)
		(end 5.59054 -426.335444)
		(stroke
			(width 0.2)
			(type default)
		)
		(layer "In1.Cu")
	)
	(gr_arc
		(start 5.59054 -426.335444)
		(mid 5.080127 -425.82465)
		(end 4.56946 -426.33519)
		(stroke
			(width 0.2)
			(type default)
		)
		(layer "In1.Cu")
	)
	(gr_line
		(start 5.59054 -423.948098)
		(end 5.59054 -423.135552)
		(stroke
			(width 0.2)
			(type default)
		)
		(layer "In1.Cu")
	)
	(gr_arc
		(start 5.59054 -423.135552)
		(mid 5.080127 -422.624758)
		(end 4.56946 -423.135298)
		(stroke
			(width 0.2)
			(type default)
		)
		(layer "In1.Cu")
	)
	(gr_line
		(start 5.59054 -417.54806)
		(end 5.59054 -416.735514)
		(stroke
			(width 0.2)
			(type default)
		)
		(layer "In1.Cu")
	)
	(gr_arc
		(start 5.59054 -416.735514)
		(mid 5.080127 -416.22472)
		(end 4.56946 -416.73526)
		(stroke
			(width 0.2)
			(type default)
		)
		(layer "In1.Cu")
	)
	(gr_line
		(start 5.59054 -414.347914)
		(end 5.59054 -413.535114)
		(stroke
			(width 0.2)
			(type default)
		)
		(layer "In1.Cu")
	)
	(gr_arc
		(start 5.59054 -413.535114)
		(mid 5.08 -413.024574)
		(end 4.56946 -413.535114)
		(stroke
			(width 0.2)
			(type default)
		)
		(layer "In1.Cu")
	)
	(gr_line
		(start 5.59054 -411.148022)
		(end 5.59054 -410.335222)
		(stroke
			(width 0.2)
			(type default)
		)
		(layer "In1.Cu")
	)
	(gr_arc
		(start 5.59054 -410.335222)
		(mid 5.08 -409.824682)
		(end 4.56946 -410.335222)
		(stroke
			(width 0.2)
			(type default)
		)
		(layer "In1.Cu")
	)
	(gr_line
		(start 5.59054 -407.947876)
		(end 5.59054 -407.135076)
		(stroke
			(width 0.2)
			(type default)
		)
		(layer "In1.Cu")
	)
	(gr_arc
		(start 5.59054 -407.135076)
		(mid 5.08 -406.624536)
		(end 4.56946 -407.135076)
		(stroke
			(width 0.2)
			(type default)
		)
		(layer "In1.Cu")
	)
	(gr_line
		(start 5.59054 -404.747984)
		(end 5.59054 -403.935184)
		(stroke
			(width 0.2)
			(type default)
		)
		(layer "In1.Cu")
	)
	(gr_arc
		(start 5.59054 -403.935184)
		(mid 5.08 -403.424644)
		(end 4.56946 -403.935184)
		(stroke
			(width 0.2)
			(type default)
		)
		(layer "In1.Cu")
	)
	(gr_line
		(start 5.59054 -399.148046)
		(end 5.59054 -398.3355)
		(stroke
			(width 0.2)
			(type default)
		)
		(layer "In1.Cu")
	)
	(gr_arc
		(start 5.59054 -398.3355)
		(mid 5.080127 -397.824706)
		(end 4.56946 -398.335246)
		(stroke
			(width 0.2)
			(type default)
		)
		(layer "In1.Cu")
	)
	(gr_line
		(start 5.59054 -395.9479)
		(end 5.59054 -395.135354)
		(stroke
			(width 0.2)
			(type default)
		)
		(layer "In1.Cu")
	)
	(gr_arc
		(start 5.59054 -395.135354)
		(mid 5.080127 -394.62456)
		(end 4.56946 -395.1351)
		(stroke
			(width 0.2)
			(type default)
		)
		(layer "In1.Cu")
	)
	(gr_line
		(start 5.59054 -392.748008)
		(end 5.59054 -391.935462)
		(stroke
			(width 0.2)
			(type default)
		)
		(layer "In1.Cu")
	)
	(gr_arc
		(start 5.59054 -391.935462)
		(mid 5.080127 -391.424668)
		(end 4.56946 -391.935208)
		(stroke
			(width 0.2)
			(type default)
		)
		(layer "In1.Cu")
	)
	(gr_line
		(start 5.59054 -389.548116)
		(end 5.59054 -388.73557)
		(stroke
			(width 0.2)
			(type default)
		)
		(layer "In1.Cu")
	)
	(gr_arc
		(start 5.59054 -388.73557)
		(mid 5.080127 -388.224776)
		(end 4.56946 -388.735316)
		(stroke
			(width 0.2)
			(type default)
		)
		(layer "In1.Cu")
	)
	(gr_line
		(start 5.59054 -358.74833)
		(end 5.59054 -357.935784)
		(stroke
			(width 0.2)
			(type default)
		)
		(layer "In1.Cu")
	)
	(gr_arc
		(start 5.59054 -357.935784)
		(mid 5.080127 -357.42499)
		(end 4.56946 -357.93553)
		(stroke
			(width 0.2)
			(type default)
		)
		(layer "In1.Cu")
	)
	(gr_line
		(start 5.59054 -355.548184)
		(end 5.59054 -354.735638)
		(stroke
			(width 0.2)
			(type default)
		)
		(layer "In1.Cu")
	)
	(gr_arc
		(start 5.59054 -354.735638)
		(mid 5.080127 -354.224844)
		(end 4.56946 -354.735384)
		(stroke
			(width 0.2)
			(type default)
		)
		(layer "In1.Cu")
	)
	(gr_line
		(start 5.59054 -352.348292)
		(end 5.59054 -351.535746)
		(stroke
			(width 0.2)
			(type default)
		)
		(layer "In1.Cu")
	)
	(gr_arc
		(start 5.59054 -351.535746)
		(mid 5.080127 -351.024952)
		(end 4.56946 -351.535492)
		(stroke
			(width 0.2)
			(type default)
		)
		(layer "In1.Cu")
	)
	(gr_line
		(start 5.59054 -349.148146)
		(end 5.59054 -348.3356)
		(stroke
			(width 0.2)
			(type default)
		)
		(layer "In1.Cu")
	)
	(gr_arc
		(start 5.59054 -348.3356)
		(mid 5.080127 -347.824806)
		(end 4.56946 -348.335346)
		(stroke
			(width 0.2)
			(type default)
		)
		(layer "In1.Cu")
	)
	(gr_line
		(start 5.59054 -345.948254)
		(end 5.59054 -345.135708)
		(stroke
			(width 0.2)
			(type default)
		)
		(layer "In1.Cu")
	)
	(gr_arc
		(start 5.59054 -345.135708)
		(mid 5.080127 -344.624914)
		(end 4.56946 -345.135454)
		(stroke
			(width 0.2)
			(type default)
		)
		(layer "In1.Cu")
	)
	(gr_line
		(start 5.59054 -342.748108)
		(end 5.59054 -341.935562)
		(stroke
			(width 0.2)
			(type default)
		)
		(layer "In1.Cu")
	)
	(gr_arc
		(start 5.59054 -341.935562)
		(mid 5.080127 -341.424768)
		(end 4.56946 -341.935308)
		(stroke
			(width 0.2)
			(type default)
		)
		(layer "In1.Cu")
	)
	(gr_line
		(start 5.59054 -339.548216)
		(end 5.59054 -338.73567)
		(stroke
			(width 0.2)
			(type default)
		)
		(layer "In1.Cu")
	)
	(gr_arc
		(start 5.59054 -338.73567)
		(mid 5.080127 -338.224876)
		(end 4.56946 -338.735416)
		(stroke
			(width 0.2)
			(type default)
		)
		(layer "In1.Cu")
	)
	(gr_line
		(start 5.59054 -336.348324)
		(end 5.59054 -335.535778)
		(stroke
			(width 0.2)
			(type default)
		)
		(layer "In1.Cu")
	)
	(gr_arc
		(start 5.59054 -335.535778)
		(mid 5.080127 -335.024984)
		(end 4.56946 -335.535524)
		(stroke
			(width 0.2)
			(type default)
		)
		(layer "In1.Cu")
	)
	(gr_line
		(start 5.59054 -330.748132)
		(end 5.59054 -329.935586)
		(stroke
			(width 0.2)
			(type default)
		)
		(layer "In1.Cu")
	)
	(gr_arc
		(start 5.59054 -329.935586)
		(mid 5.080127 -329.424792)
		(end 4.56946 -329.935332)
		(stroke
			(width 0.2)
			(type default)
		)
		(layer "In1.Cu")
	)
	(gr_line
		(start 5.59054 -327.54824)
		(end 5.59054 -326.735694)
		(stroke
			(width 0.2)
			(type default)
		)
		(layer "In1.Cu")
	)
	(gr_arc
		(start 5.59054 -326.735694)
		(mid 5.080127 -326.2249)
		(end 4.56946 -326.73544)
		(stroke
			(width 0.2)
			(type default)
		)
		(layer "In1.Cu")
	)
	(gr_line
		(start 5.59054 -324.348094)
		(end 5.59054 -323.535548)
		(stroke
			(width 0.2)
			(type default)
		)
		(layer "In1.Cu")
	)
	(gr_arc
		(start 5.59054 -323.535548)
		(mid 5.080127 -323.024754)
		(end 4.56946 -323.535294)
		(stroke
			(width 0.2)
			(type default)
		)
		(layer "In1.Cu")
	)
	(gr_line
		(start 5.59054 -321.148202)
		(end 5.59054 -320.335656)
		(stroke
			(width 0.2)
			(type default)
		)
		(layer "In1.Cu")
	)
	(gr_arc
		(start 5.59054 -320.335656)
		(mid 5.080127 -319.824862)
		(end 4.56946 -320.335402)
		(stroke
			(width 0.2)
			(type default)
		)
		(layer "In1.Cu")
	)
	(gr_line
		(start 5.59054 -317.94831)
		(end 5.59054 -317.135764)
		(stroke
			(width 0.2)
			(type default)
		)
		(layer "In1.Cu")
	)
	(gr_arc
		(start 5.59054 -317.135764)
		(mid 5.080127 -316.62497)
		(end 4.56946 -317.13551)
		(stroke
			(width 0.2)
			(type default)
		)
		(layer "In1.Cu")
	)
	(gr_line
		(start 5.59054 -309.948326)
		(end 5.59054 -309.13578)
		(stroke
			(width 0.2)
			(type default)
		)
		(layer "In1.Cu")
	)
	(gr_arc
		(start 5.59054 -309.13578)
		(mid 5.080127 -308.624986)
		(end 4.56946 -309.135526)
		(stroke
			(width 0.2)
			(type default)
		)
		(layer "In1.Cu")
	)
	(gr_line
		(start 5.59054 -306.74818)
		(end 5.59054 -305.935634)
		(stroke
			(width 0.2)
			(type default)
		)
		(layer "In1.Cu")
	)
	(gr_arc
		(start 5.59054 -305.935634)
		(mid 5.080127 -305.42484)
		(end 4.56946 -305.93538)
		(stroke
			(width 0.2)
			(type default)
		)
		(layer "In1.Cu")
	)
	(gr_line
		(start 5.59054 -303.548288)
		(end 5.59054 -302.735742)
		(stroke
			(width 0.2)
			(type default)
		)
		(layer "In1.Cu")
	)
	(gr_arc
		(start 5.59054 -302.735742)
		(mid 5.080127 -302.224948)
		(end 4.56946 -302.735488)
		(stroke
			(width 0.2)
			(type default)
		)
		(layer "In1.Cu")
	)
	(gr_line
		(start 5.59054 -300.348142)
		(end 5.59054 -299.535596)
		(stroke
			(width 0.2)
			(type default)
		)
		(layer "In1.Cu")
	)
	(gr_arc
		(start 5.59054 -299.535596)
		(mid 5.080127 -299.024802)
		(end 4.56946 -299.535342)
		(stroke
			(width 0.2)
			(type default)
		)
		(layer "In1.Cu")
	)
	(gr_line
		(start 5.59054 -297.14825)
		(end 5.59054 -296.335704)
		(stroke
			(width 0.2)
			(type default)
		)
		(layer "In1.Cu")
	)
	(gr_arc
		(start 5.59054 -296.335704)
		(mid 5.080127 -295.82491)
		(end 4.56946 -296.33545)
		(stroke
			(width 0.2)
			(type default)
		)
		(layer "In1.Cu")
	)
	(gr_line
		(start 5.59054 -293.948104)
		(end 5.59054 -293.135558)
		(stroke
			(width 0.2)
			(type default)
		)
		(layer "In1.Cu")
	)
	(gr_arc
		(start 5.59054 -293.135558)
		(mid 5.080127 -292.624764)
		(end 4.56946 -293.135304)
		(stroke
			(width 0.2)
			(type default)
		)
		(layer "In1.Cu")
	)
	(gr_line
		(start 5.59054 -290.748212)
		(end 5.59054 -289.935666)
		(stroke
			(width 0.2)
			(type default)
		)
		(layer "In1.Cu")
	)
	(gr_arc
		(start 5.59054 -289.935666)
		(mid 5.080127 -289.424872)
		(end 4.56946 -289.935412)
		(stroke
			(width 0.2)
			(type default)
		)
		(layer "In1.Cu")
	)
	(gr_line
		(start 5.59054 -284.348174)
		(end 5.59054 -283.535628)
		(stroke
			(width 0.2)
			(type default)
		)
		(layer "In1.Cu")
	)
	(gr_arc
		(start 5.59054 -283.535628)
		(mid 5.080127 -283.024834)
		(end 4.56946 -283.535374)
		(stroke
			(width 0.2)
			(type default)
		)
		(layer "In1.Cu")
	)
	(gr_line
		(start 5.59054 -281.148282)
		(end 5.59054 -280.335736)
		(stroke
			(width 0.2)
			(type default)
		)
		(layer "In1.Cu")
	)
	(gr_arc
		(start 5.59054 -280.335736)
		(mid 5.080127 -279.824942)
		(end 4.56946 -280.335482)
		(stroke
			(width 0.2)
			(type default)
		)
		(layer "In1.Cu")
	)
	(gr_line
		(start 5.59054 -232.748328)
		(end 5.59054 -231.935782)
		(stroke
			(width 0.2)
			(type default)
		)
		(layer "In1.Cu")
	)
	(gr_arc
		(start 5.59054 -231.935782)
		(mid 5.080127 -231.424988)
		(end 4.56946 -231.935528)
		(stroke
			(width 0.2)
			(type default)
		)
		(layer "In1.Cu")
	)
	(gr_line
		(start 5.59054 -229.548182)
		(end 5.59054 -228.735636)
		(stroke
			(width 0.2)
			(type default)
		)
		(layer "In1.Cu")
	)
	(gr_arc
		(start 5.59054 -228.735636)
		(mid 5.080127 -228.224842)
		(end 4.56946 -228.735382)
		(stroke
			(width 0.2)
			(type default)
		)
		(layer "In1.Cu")
	)
	(gr_line
		(start 5.59054 -223.148144)
		(end 5.59054 -222.335598)
		(stroke
			(width 0.2)
			(type default)
		)
		(layer "In1.Cu")
	)
	(gr_arc
		(start 5.59054 -222.335598)
		(mid 5.080127 -221.824804)
		(end 4.56946 -222.335344)
		(stroke
			(width 0.2)
			(type default)
		)
		(layer "In1.Cu")
	)
	(gr_line
		(start 5.59054 -219.948252)
		(end 5.59054 -219.135706)
		(stroke
			(width 0.2)
			(type default)
		)
		(layer "In1.Cu")
	)
	(gr_arc
		(start 5.59054 -219.135706)
		(mid 5.080127 -218.624912)
		(end 4.56946 -219.135452)
		(stroke
			(width 0.2)
			(type default)
		)
		(layer "In1.Cu")
	)
	(gr_line
		(start 5.59054 -216.748106)
		(end 5.59054 -215.93556)
		(stroke
			(width 0.2)
			(type default)
		)
		(layer "In1.Cu")
	)
	(gr_arc
		(start 5.59054 -215.93556)
		(mid 5.080127 -215.424766)
		(end 4.56946 -215.935306)
		(stroke
			(width 0.2)
			(type default)
		)
		(layer "In1.Cu")
	)
	(gr_line
		(start 5.59054 -213.548214)
		(end 5.59054 -212.735668)
		(stroke
			(width 0.2)
			(type default)
		)
		(layer "In1.Cu")
	)
	(gr_arc
		(start 5.59054 -212.735668)
		(mid 5.080127 -212.224874)
		(end 4.56946 -212.735414)
		(stroke
			(width 0.2)
			(type default)
		)
		(layer "In1.Cu")
	)
	(gr_line
		(start 5.59054 -210.348322)
		(end 5.59054 -209.535776)
		(stroke
			(width 0.2)
			(type default)
		)
		(layer "In1.Cu")
	)
	(gr_arc
		(start 5.59054 -209.535776)
		(mid 5.080127 -209.024982)
		(end 4.56946 -209.535522)
		(stroke
			(width 0.2)
			(type default)
		)
		(layer "In1.Cu")
	)
	(gr_line
		(start 5.59054 -207.148176)
		(end 5.59054 -206.33563)
		(stroke
			(width 0.2)
			(type default)
		)
		(layer "In1.Cu")
	)
	(gr_arc
		(start 5.59054 -206.33563)
		(mid 5.080127 -205.824836)
		(end 4.56946 -206.335376)
		(stroke
			(width 0.2)
			(type default)
		)
		(layer "In1.Cu")
	)
	(gr_line
		(start 5.59054 -203.948284)
		(end 5.59054 -203.135738)
		(stroke
			(width 0.2)
			(type default)
		)
		(layer "In1.Cu")
	)
	(gr_arc
		(start 5.59054 -203.135738)
		(mid 5.080127 -202.624944)
		(end 4.56946 -203.135484)
		(stroke
			(width 0.2)
			(type default)
		)
		(layer "In1.Cu")
	)
	(gr_line
		(start 5.59054 -200.748138)
		(end 5.59054 -199.935592)
		(stroke
			(width 0.2)
			(type default)
		)
		(layer "In1.Cu")
	)
	(gr_arc
		(start 5.59054 -199.935592)
		(mid 5.080127 -199.424798)
		(end 4.56946 -199.935338)
		(stroke
			(width 0.2)
			(type default)
		)
		(layer "In1.Cu")
	)
	(gr_line
		(start 5.59054 -195.1482)
		(end 5.59054 -194.335654)
		(stroke
			(width 0.2)
			(type default)
		)
		(layer "In1.Cu")
	)
	(gr_arc
		(start 5.59054 -194.335654)
		(mid 5.080127 -193.82486)
		(end 4.56946 -194.3354)
		(stroke
			(width 0.2)
			(type default)
		)
		(layer "In1.Cu")
	)
	(gr_line
		(start 5.59054 -191.948308)
		(end 5.59054 -191.135762)
		(stroke
			(width 0.2)
			(type default)
		)
		(layer "In1.Cu")
	)
	(gr_arc
		(start 5.59054 -191.135762)
		(mid 5.080127 -190.624968)
		(end 4.56946 -191.135508)
		(stroke
			(width 0.2)
			(type default)
		)
		(layer "In1.Cu")
	)
	(gr_line
		(start 5.59054 -183.948324)
		(end 5.59054 -183.135778)
		(stroke
			(width 0.2)
			(type default)
		)
		(layer "In1.Cu")
	)
	(gr_arc
		(start 5.59054 -183.135778)
		(mid 5.080127 -182.624984)
		(end 4.56946 -183.135524)
		(stroke
			(width 0.2)
			(type default)
		)
		(layer "In1.Cu")
	)
	(gr_line
		(start 5.59054 -180.748178)
		(end 5.59054 -179.935632)
		(stroke
			(width 0.2)
			(type default)
		)
		(layer "In1.Cu")
	)
	(gr_arc
		(start 5.59054 -179.935632)
		(mid 5.080127 -179.424838)
		(end 4.56946 -179.935378)
		(stroke
			(width 0.2)
			(type default)
		)
		(layer "In1.Cu")
	)
	(gr_line
		(start 5.59054 -177.548286)
		(end 5.59054 -176.73574)
		(stroke
			(width 0.2)
			(type default)
		)
		(layer "In1.Cu")
	)
	(gr_arc
		(start 5.59054 -176.73574)
		(mid 5.080127 -176.224946)
		(end 4.56946 -176.735486)
		(stroke
			(width 0.2)
			(type default)
		)
		(layer "In1.Cu")
	)
	(gr_line
		(start 5.59054 -174.34814)
		(end 5.59054 -173.535594)
		(stroke
			(width 0.2)
			(type default)
		)
		(layer "In1.Cu")
	)
	(gr_arc
		(start 5.59054 -173.535594)
		(mid 5.080127 -173.0248)
		(end 4.56946 -173.53534)
		(stroke
			(width 0.2)
			(type default)
		)
		(layer "In1.Cu")
	)
	(gr_line
		(start 5.59054 -171.148248)
		(end 5.59054 -170.335702)
		(stroke
			(width 0.2)
			(type default)
		)
		(layer "In1.Cu")
	)
	(gr_arc
		(start 5.59054 -170.335702)
		(mid 5.080127 -169.824908)
		(end 4.56946 -170.335448)
		(stroke
			(width 0.2)
			(type default)
		)
		(layer "In1.Cu")
	)
	(gr_line
		(start 5.59054 -167.948102)
		(end 5.59054 -167.135556)
		(stroke
			(width 0.2)
			(type default)
		)
		(layer "In1.Cu")
	)
	(gr_arc
		(start 5.59054 -167.135556)
		(mid 5.080127 -166.624762)
		(end 4.56946 -167.135302)
		(stroke
			(width 0.2)
			(type default)
		)
		(layer "In1.Cu")
	)
	(gr_line
		(start 5.59054 -164.74821)
		(end 5.59054 -163.935664)
		(stroke
			(width 0.2)
			(type default)
		)
		(layer "In1.Cu")
	)
	(gr_arc
		(start 5.59054 -163.935664)
		(mid 5.080127 -163.42487)
		(end 4.56946 -163.93541)
		(stroke
			(width 0.2)
			(type default)
		)
		(layer "In1.Cu")
	)
	(gr_line
		(start 5.59054 -161.548318)
		(end 5.59054 -160.735772)
		(stroke
			(width 0.2)
			(type default)
		)
		(layer "In1.Cu")
	)
	(gr_arc
		(start 5.59054 -160.735772)
		(mid 5.080127 -160.224978)
		(end 4.56946 -160.735518)
		(stroke
			(width 0.2)
			(type default)
		)
		(layer "In1.Cu")
	)
	(gr_line
		(start 5.59054 -158.348172)
		(end 5.59054 -157.535626)
		(stroke
			(width 0.2)
			(type default)
		)
		(layer "In1.Cu")
	)
	(gr_arc
		(start 5.59054 -157.535626)
		(mid 5.080127 -157.024832)
		(end 4.56946 -157.535372)
		(stroke
			(width 0.2)
			(type default)
		)
		(layer "In1.Cu")
	)
	(gr_line
		(start 5.59054 -155.14828)
		(end 5.59054 -154.335734)
		(stroke
			(width 0.2)
			(type default)
		)
		(layer "In1.Cu")
	)
	(gr_arc
		(start 5.59054 -154.335734)
		(mid 5.080127 -153.82494)
		(end 4.56946 -154.33548)
		(stroke
			(width 0.2)
			(type default)
		)
		(layer "In1.Cu")
	)
	(gr_arc
		(start 6.4516 -379.1458)
		(mid 6.481358 -379.217642)
		(end 6.5532 -379.2474)
		(stroke
			(width 0.2)
			(type default)
		)
		(layer "In1.Cu")
	)
	(gr_line
		(start 6.4516 -377.825)
		(end 6.4516 -379.1458)
		(stroke
			(width 0.2)
			(type default)
		)
		(layer "In1.Cu")
	)
	(gr_line
		(start 6.477 -449.978272)
		(end 7.2898 -449.978272)
		(stroke
			(width 0.2)
			(type default)
		)
		(layer "In1.Cu")
	)
	(gr_arc
		(start 6.477254 -448.957192)
		(mid 5.96646 -449.467605)
		(end 6.477 -449.978272)
		(stroke
			(width 0.2)
			(type default)
		)
		(layer "In1.Cu")
	)
	(gr_arc
		(start 6.481826 -447.196718)
		(mid 6.992239 -447.707512)
		(end 7.502906 -447.196972)
		(stroke
			(width 0.2)
			(type default)
		)
		(layer "In1.Cu")
	)
	(gr_line
		(start 6.481826 -446.384172)
		(end 6.481826 -447.196718)
		(stroke
			(width 0.2)
			(type default)
		)
		(layer "In1.Cu")
	)
	(gr_arc
		(start 6.481826 -443.996826)
		(mid 6.992239 -444.50762)
		(end 7.502906 -443.99708)
		(stroke
			(width 0.2)
			(type default)
		)
		(layer "In1.Cu")
	)
	(gr_line
		(start 6.481826 -443.18428)
		(end 6.481826 -443.996826)
		(stroke
			(width 0.2)
			(type default)
		)
		(layer "In1.Cu")
	)
	(gr_arc
		(start 6.481826 -440.79668)
		(mid 6.992239 -441.307474)
		(end 7.502906 -440.796934)
		(stroke
			(width 0.2)
			(type default)
		)
		(layer "In1.Cu")
	)
	(gr_line
		(start 6.481826 -439.984134)
		(end 6.481826 -440.79668)
		(stroke
			(width 0.2)
			(type default)
		)
		(layer "In1.Cu")
	)
	(gr_arc
		(start 6.481826 -437.596788)
		(mid 6.992239 -438.107582)
		(end 7.502906 -437.597042)
		(stroke
			(width 0.2)
			(type default)
		)
		(layer "In1.Cu")
	)
	(gr_line
		(start 6.481826 -436.784242)
		(end 6.481826 -437.596788)
		(stroke
			(width 0.2)
			(type default)
		)
		(layer "In1.Cu")
	)
	(gr_arc
		(start 6.481826 -431.997104)
		(mid 6.992366 -432.507644)
		(end 7.502906 -431.997104)
		(stroke
			(width 0.2)
			(type default)
		)
		(layer "In1.Cu")
	)
	(gr_line
		(start 6.481826 -431.184304)
		(end 6.481826 -431.997104)
		(stroke
			(width 0.2)
			(type default)
		)
		(layer "In1.Cu")
	)
	(gr_arc
		(start 6.481826 -428.796958)
		(mid 6.992366 -429.307498)
		(end 7.502906 -428.796958)
		(stroke
			(width 0.2)
			(type default)
		)
		(layer "In1.Cu")
	)
	(gr_line
		(start 6.481826 -427.984158)
		(end 6.481826 -428.796958)
		(stroke
			(width 0.2)
			(type default)
		)
		(layer "In1.Cu")
	)
	(gr_arc
		(start 6.481826 -425.597066)
		(mid 6.992366 -426.107606)
		(end 7.502906 -425.597066)
		(stroke
			(width 0.2)
			(type default)
		)
		(layer "In1.Cu")
	)
	(gr_line
		(start 6.481826 -424.784266)
		(end 6.481826 -425.597066)
		(stroke
			(width 0.2)
			(type default)
		)
		(layer "In1.Cu")
	)
	(gr_arc
		(start 6.481826 -415.948622)
		(mid 6.992366 -416.459162)
		(end 7.502906 -415.948622)
		(stroke
			(width 0.2)
			(type default)
		)
		(layer "In1.Cu")
	)
	(gr_line
		(start 6.481826 -415.135822)
		(end 6.481826 -415.948622)
		(stroke
			(width 0.2)
			(type default)
		)
		(layer "In1.Cu")
	)
	(gr_arc
		(start 6.481826 -412.748222)
		(mid 6.992239 -413.259016)
		(end 7.502906 -412.748476)
		(stroke
			(width 0.2)
			(type default)
		)
		(layer "In1.Cu")
	)
	(gr_line
		(start 6.481826 -411.935676)
		(end 6.481826 -412.748222)
		(stroke
			(width 0.2)
			(type default)
		)
		(layer "In1.Cu")
	)
	(gr_arc
		(start 6.481826 -409.54833)
		(mid 6.992239 -410.059124)
		(end 7.502906 -409.548584)
		(stroke
			(width 0.2)
			(type default)
		)
		(layer "In1.Cu")
	)
	(gr_line
		(start 6.481826 -408.735784)
		(end 6.481826 -409.54833)
		(stroke
			(width 0.2)
			(type default)
		)
		(layer "In1.Cu")
	)
	(gr_arc
		(start 6.481826 -406.348184)
		(mid 6.992239 -406.858978)
		(end 7.502906 -406.348438)
		(stroke
			(width 0.2)
			(type default)
		)
		(layer "In1.Cu")
	)
	(gr_line
		(start 6.481826 -405.535638)
		(end 6.481826 -406.348184)
		(stroke
			(width 0.2)
			(type default)
		)
		(layer "In1.Cu")
	)
	(gr_arc
		(start 6.481826 -403.148292)
		(mid 6.992239 -403.659086)
		(end 7.502906 -403.148546)
		(stroke
			(width 0.2)
			(type default)
		)
		(layer "In1.Cu")
	)
	(gr_line
		(start 6.481826 -402.335746)
		(end 6.481826 -403.148292)
		(stroke
			(width 0.2)
			(type default)
		)
		(layer "In1.Cu")
	)
	(gr_arc
		(start 6.481826 -397.548608)
		(mid 6.992366 -398.059148)
		(end 7.502906 -397.548608)
		(stroke
			(width 0.2)
			(type default)
		)
		(layer "In1.Cu")
	)
	(gr_line
		(start 6.481826 -396.735808)
		(end 6.481826 -397.548608)
		(stroke
			(width 0.2)
			(type default)
		)
		(layer "In1.Cu")
	)
	(gr_arc
		(start 6.481826 -394.348462)
		(mid 6.992366 -394.859002)
		(end 7.502906 -394.348462)
		(stroke
			(width 0.2)
			(type default)
		)
		(layer "In1.Cu")
	)
	(gr_line
		(start 6.481826 -393.535662)
		(end 6.481826 -394.348462)
		(stroke
			(width 0.2)
			(type default)
		)
		(layer "In1.Cu")
	)
	(gr_arc
		(start 6.481826 -391.14857)
		(mid 6.992366 -391.65911)
		(end 7.502906 -391.14857)
		(stroke
			(width 0.2)
			(type default)
		)
		(layer "In1.Cu")
	)
	(gr_line
		(start 6.481826 -390.33577)
		(end 6.481826 -391.14857)
		(stroke
			(width 0.2)
			(type default)
		)
		(layer "In1.Cu")
	)
	(gr_arc
		(start 6.481826 -387.948424)
		(mid 6.992366 -388.458964)
		(end 7.502906 -387.948424)
		(stroke
			(width 0.2)
			(type default)
		)
		(layer "In1.Cu")
	)
	(gr_line
		(start 6.481826 -387.135624)
		(end 6.481826 -387.948424)
		(stroke
			(width 0.2)
			(type default)
		)
		(layer "In1.Cu")
	)
	(gr_arc
		(start 6.481826 -357.148384)
		(mid 6.992239 -357.659178)
		(end 7.502906 -357.148638)
		(stroke
			(width 0.2)
			(type default)
		)
		(layer "In1.Cu")
	)
	(gr_line
		(start 6.481826 -356.335838)
		(end 6.481826 -357.148384)
		(stroke
			(width 0.2)
			(type default)
		)
		(layer "In1.Cu")
	)
	(gr_arc
		(start 6.481826 -353.948746)
		(mid 6.992366 -354.459286)
		(end 7.502906 -353.948746)
		(stroke
			(width 0.2)
			(type default)
		)
		(layer "In1.Cu")
	)
	(gr_line
		(start 6.481826 -353.135946)
		(end 6.481826 -353.948746)
		(stroke
			(width 0.2)
			(type default)
		)
		(layer "In1.Cu")
	)
	(gr_arc
		(start 6.481826 -350.748346)
		(mid 6.992239 -351.25914)
		(end 7.502906 -350.7486)
		(stroke
			(width 0.2)
			(type default)
		)
		(layer "In1.Cu")
	)
	(gr_line
		(start 6.481826 -349.9358)
		(end 6.481826 -350.748346)
		(stroke
			(width 0.2)
			(type default)
		)
		(layer "In1.Cu")
	)
	(gr_arc
		(start 6.481826 -347.548454)
		(mid 6.992239 -348.059248)
		(end 7.502906 -347.548708)
		(stroke
			(width 0.2)
			(type default)
		)
		(layer "In1.Cu")
	)
	(gr_line
		(start 6.481826 -346.735908)
		(end 6.481826 -347.548454)
		(stroke
			(width 0.2)
			(type default)
		)
		(layer "In1.Cu")
	)
	(gr_arc
		(start 6.481826 -344.399616)
		(mid 6.992366 -344.910156)
		(end 7.502906 -344.399616)
		(stroke
			(width 0.2)
			(type default)
		)
		(layer "In1.Cu")
	)
	(gr_line
		(start 6.481826 -343.586816)
		(end 6.481826 -344.399616)
		(stroke
			(width 0.2)
			(type default)
		)
		(layer "In1.Cu")
	)
	(gr_arc
		(start 6.481826 -341.19947)
		(mid 6.992366 -341.71001)
		(end 7.502906 -341.19947)
		(stroke
			(width 0.2)
			(type default)
		)
		(layer "In1.Cu")
	)
	(gr_line
		(start 6.481826 -340.38667)
		(end 6.481826 -341.19947)
		(stroke
			(width 0.2)
			(type default)
		)
		(layer "In1.Cu")
	)
	(gr_arc
		(start 6.481826 -337.999578)
		(mid 6.992366 -338.510118)
		(end 7.502906 -337.999578)
		(stroke
			(width 0.2)
			(type default)
		)
		(layer "In1.Cu")
	)
	(gr_line
		(start 6.481826 -337.186778)
		(end 6.481826 -337.999578)
		(stroke
			(width 0.2)
			(type default)
		)
		(layer "In1.Cu")
	)
	(gr_arc
		(start 6.481826 -334.799432)
		(mid 6.992366 -335.309972)
		(end 7.502906 -334.799432)
		(stroke
			(width 0.2)
			(type default)
		)
		(layer "In1.Cu")
	)
	(gr_line
		(start 6.481826 -333.986632)
		(end 6.481826 -334.799432)
		(stroke
			(width 0.2)
			(type default)
		)
		(layer "In1.Cu")
	)
	(gr_arc
		(start 6.481826 -329.14844)
		(mid 6.992239 -329.659234)
		(end 7.502906 -329.148694)
		(stroke
			(width 0.2)
			(type default)
		)
		(layer "In1.Cu")
	)
	(gr_line
		(start 6.481826 -328.335894)
		(end 6.481826 -329.14844)
		(stroke
			(width 0.2)
			(type default)
		)
		(layer "In1.Cu")
	)
	(gr_arc
		(start 6.481826 -325.948548)
		(mid 6.992239 -326.459342)
		(end 7.502906 -325.948802)
		(stroke
			(width 0.2)
			(type default)
		)
		(layer "In1.Cu")
	)
	(gr_line
		(start 6.481826 -325.136002)
		(end 6.481826 -325.948548)
		(stroke
			(width 0.2)
			(type default)
		)
		(layer "In1.Cu")
	)
	(gr_arc
		(start 6.481826 -322.748402)
		(mid 6.992239 -323.259196)
		(end 7.502906 -322.748656)
		(stroke
			(width 0.2)
			(type default)
		)
		(layer "In1.Cu")
	)
	(gr_line
		(start 6.481826 -321.935856)
		(end 6.481826 -322.748402)
		(stroke
			(width 0.2)
			(type default)
		)
		(layer "In1.Cu")
	)
	(gr_arc
		(start 6.481826 -319.54851)
		(mid 6.992239 -320.059304)
		(end 7.502906 -319.548764)
		(stroke
			(width 0.2)
			(type default)
		)
		(layer "In1.Cu")
	)
	(gr_line
		(start 6.481826 -318.735964)
		(end 6.481826 -319.54851)
		(stroke
			(width 0.2)
			(type default)
		)
		(layer "In1.Cu")
	)
	(gr_arc
		(start 6.481826 -311.548526)
		(mid 6.992239 -312.05932)
		(end 7.502906 -311.54878)
		(stroke
			(width 0.2)
			(type default)
		)
		(layer "In1.Cu")
	)
	(gr_line
		(start 6.481826 -310.73598)
		(end 6.481826 -311.548526)
		(stroke
			(width 0.2)
			(type default)
		)
		(layer "In1.Cu")
	)
	(gr_arc
		(start 6.481826 -308.34838)
		(mid 6.992239 -308.859174)
		(end 7.502906 -308.348634)
		(stroke
			(width 0.2)
			(type default)
		)
		(layer "In1.Cu")
	)
	(gr_line
		(start 6.481826 -307.535834)
		(end 6.481826 -308.34838)
		(stroke
			(width 0.2)
			(type default)
		)
		(layer "In1.Cu")
	)
	(gr_arc
		(start 6.481826 -305.148488)
		(mid 6.992239 -305.659282)
		(end 7.502906 -305.148742)
		(stroke
			(width 0.2)
			(type default)
		)
		(layer "In1.Cu")
	)
	(gr_line
		(start 6.481826 -304.335942)
		(end 6.481826 -305.148488)
		(stroke
			(width 0.2)
			(type default)
		)
		(layer "In1.Cu")
	)
	(gr_arc
		(start 6.481826 -301.948342)
		(mid 6.992239 -302.459136)
		(end 7.502906 -301.948596)
		(stroke
			(width 0.2)
			(type default)
		)
		(layer "In1.Cu")
	)
	(gr_line
		(start 6.481826 -301.135796)
		(end 6.481826 -301.948342)
		(stroke
			(width 0.2)
			(type default)
		)
		(layer "In1.Cu")
	)
	(gr_arc
		(start 6.481826 -298.74845)
		(mid 6.992239 -299.259244)
		(end 7.502906 -298.748704)
		(stroke
			(width 0.2)
			(type default)
		)
		(layer "In1.Cu")
	)
	(gr_line
		(start 6.481826 -297.935904)
		(end 6.481826 -298.74845)
		(stroke
			(width 0.2)
			(type default)
		)
		(layer "In1.Cu")
	)
	(gr_arc
		(start 6.481826 -295.548558)
		(mid 6.992239 -296.059352)
		(end 7.502906 -295.548812)
		(stroke
			(width 0.2)
			(type default)
		)
		(layer "In1.Cu")
	)
	(gr_line
		(start 6.481826 -294.736012)
		(end 6.481826 -295.548558)
		(stroke
			(width 0.2)
			(type default)
		)
		(layer "In1.Cu")
	)
	(gr_arc
		(start 6.481826 -292.348412)
		(mid 6.992239 -292.859206)
		(end 7.502906 -292.348666)
		(stroke
			(width 0.2)
			(type default)
		)
		(layer "In1.Cu")
	)
	(gr_line
		(start 6.481826 -291.535866)
		(end 6.481826 -292.348412)
		(stroke
			(width 0.2)
			(type default)
		)
		(layer "In1.Cu")
	)
	(gr_arc
		(start 6.481826 -289.148774)
		(mid 6.992366 -289.659314)
		(end 7.502906 -289.148774)
		(stroke
			(width 0.2)
			(type default)
		)
		(layer "In1.Cu")
	)
	(gr_line
		(start 6.481826 -288.335974)
		(end 6.481826 -289.148774)
		(stroke
			(width 0.2)
			(type default)
		)
		(layer "In1.Cu")
	)
	(gr_arc
		(start 6.481826 -282.799536)
		(mid 6.992366 -283.310076)
		(end 7.502906 -282.799536)
		(stroke
			(width 0.2)
			(type default)
		)
		(layer "In1.Cu")
	)
	(gr_line
		(start 6.481826 -281.986736)
		(end 6.481826 -282.799536)
		(stroke
			(width 0.2)
			(type default)
		)
		(layer "In1.Cu")
	)
	(gr_arc
		(start 6.481826 -279.59939)
		(mid 6.992366 -280.10993)
		(end 7.502906 -279.59939)
		(stroke
			(width 0.2)
			(type default)
		)
		(layer "In1.Cu")
	)
	(gr_line
		(start 6.481826 -278.78659)
		(end 6.481826 -279.59939)
		(stroke
			(width 0.2)
			(type default)
		)
		(layer "In1.Cu")
	)
	(gr_arc
		(start 6.481826 -231.148636)
		(mid 6.992366 -231.659176)
		(end 7.502906 -231.148636)
		(stroke
			(width 0.2)
			(type default)
		)
		(layer "In1.Cu")
	)
	(gr_line
		(start 6.481826 -230.335836)
		(end 6.481826 -231.148636)
		(stroke
			(width 0.2)
			(type default)
		)
		(layer "In1.Cu")
	)
	(gr_arc
		(start 6.481826 -227.948744)
		(mid 6.992366 -228.459284)
		(end 7.502906 -227.948744)
		(stroke
			(width 0.2)
			(type default)
		)
		(layer "In1.Cu")
	)
	(gr_line
		(start 6.481826 -227.135944)
		(end 6.481826 -227.948744)
		(stroke
			(width 0.2)
			(type default)
		)
		(layer "In1.Cu")
	)
	(gr_arc
		(start 6.481826 -224.710498)
		(mid 6.992366 -225.221038)
		(end 7.502906 -224.710498)
		(stroke
			(width 0.2)
			(type default)
		)
		(layer "In1.Cu")
	)
	(gr_line
		(start 6.481826 -223.897698)
		(end 6.481826 -224.710498)
		(stroke
			(width 0.2)
			(type default)
		)
		(layer "In1.Cu")
	)
	(gr_arc
		(start 6.481826 -221.497652)
		(mid 6.992239 -222.008446)
		(end 7.502906 -221.497906)
		(stroke
			(width 0.2)
			(type default)
		)
		(layer "In1.Cu")
	)
	(gr_line
		(start 6.481826 -220.685106)
		(end 6.481826 -221.497652)
		(stroke
			(width 0.2)
			(type default)
		)
		(layer "In1.Cu")
	)
	(gr_arc
		(start 6.481826 -218.298014)
		(mid 6.992366 -218.808554)
		(end 7.502906 -218.298014)
		(stroke
			(width 0.2)
			(type default)
		)
		(layer "In1.Cu")
	)
	(gr_line
		(start 6.481826 -217.485214)
		(end 6.481826 -218.298014)
		(stroke
			(width 0.2)
			(type default)
		)
		(layer "In1.Cu")
	)
	(gr_arc
		(start 6.481826 -215.097868)
		(mid 6.992366 -215.608408)
		(end 7.502906 -215.097868)
		(stroke
			(width 0.2)
			(type default)
		)
		(layer "In1.Cu")
	)
	(gr_line
		(start 6.481826 -214.285068)
		(end 6.481826 -215.097868)
		(stroke
			(width 0.2)
			(type default)
		)
		(layer "In1.Cu")
	)
	(gr_arc
		(start 6.481826 -211.948776)
		(mid 6.992366 -212.459316)
		(end 7.502906 -211.948776)
		(stroke
			(width 0.2)
			(type default)
		)
		(layer "In1.Cu")
	)
	(gr_line
		(start 6.481826 -211.135976)
		(end 6.481826 -211.948776)
		(stroke
			(width 0.2)
			(type default)
		)
		(layer "In1.Cu")
	)
	(gr_arc
		(start 6.481826 -208.74863)
		(mid 6.992366 -209.25917)
		(end 7.502906 -208.74863)
		(stroke
			(width 0.2)
			(type default)
		)
		(layer "In1.Cu")
	)
	(gr_line
		(start 6.481826 -207.93583)
		(end 6.481826 -208.74863)
		(stroke
			(width 0.2)
			(type default)
		)
		(layer "In1.Cu")
	)
	(gr_arc
		(start 6.481826 -205.548738)
		(mid 6.992366 -206.059278)
		(end 7.502906 -205.548738)
		(stroke
			(width 0.2)
			(type default)
		)
		(layer "In1.Cu")
	)
	(gr_line
		(start 6.481826 -204.735938)
		(end 6.481826 -205.548738)
		(stroke
			(width 0.2)
			(type default)
		)
		(layer "In1.Cu")
	)
	(gr_arc
		(start 6.481826 -202.348592)
		(mid 6.992366 -202.859132)
		(end 7.502906 -202.348592)
		(stroke
			(width 0.2)
			(type default)
		)
		(layer "In1.Cu")
	)
	(gr_line
		(start 6.481826 -201.535792)
		(end 6.481826 -202.348592)
		(stroke
			(width 0.2)
			(type default)
		)
		(layer "In1.Cu")
	)
	(gr_arc
		(start 6.481826 -196.748654)
		(mid 6.992366 -197.259194)
		(end 7.502906 -196.748654)
		(stroke
			(width 0.2)
			(type default)
		)
		(layer "In1.Cu")
	)
	(gr_line
		(start 6.481826 -195.935854)
		(end 6.481826 -196.748654)
		(stroke
			(width 0.2)
			(type default)
		)
		(layer "In1.Cu")
	)
	(gr_arc
		(start 6.481826 -193.548762)
		(mid 6.992366 -194.059302)
		(end 7.502906 -193.548762)
		(stroke
			(width 0.2)
			(type default)
		)
		(layer "In1.Cu")
	)
	(gr_line
		(start 6.481826 -192.735962)
		(end 6.481826 -193.548762)
		(stroke
			(width 0.2)
			(type default)
		)
		(layer "In1.Cu")
	)
	(gr_arc
		(start 6.481826 -185.548778)
		(mid 6.992366 -186.059318)
		(end 7.502906 -185.548778)
		(stroke
			(width 0.2)
			(type default)
		)
		(layer "In1.Cu")
	)
	(gr_line
		(start 6.481826 -184.735978)
		(end 6.481826 -185.548778)
		(stroke
			(width 0.2)
			(type default)
		)
		(layer "In1.Cu")
	)
	(gr_arc
		(start 6.481826 -182.348632)
		(mid 6.992366 -182.859172)
		(end 7.502906 -182.348632)
		(stroke
			(width 0.2)
			(type default)
		)
		(layer "In1.Cu")
	)
	(gr_line
		(start 6.481826 -181.535832)
		(end 6.481826 -182.348632)
		(stroke
			(width 0.2)
			(type default)
		)
		(layer "In1.Cu")
	)
	(gr_arc
		(start 6.481826 -179.19954)
		(mid 6.992366 -179.71008)
		(end 7.502906 -179.19954)
		(stroke
			(width 0.2)
			(type default)
		)
		(layer "In1.Cu")
	)
	(gr_line
		(start 6.481826 -178.38674)
		(end 6.481826 -179.19954)
		(stroke
			(width 0.2)
			(type default)
		)
		(layer "In1.Cu")
	)
	(gr_arc
		(start 6.481826 -175.999394)
		(mid 6.992366 -176.509934)
		(end 7.502906 -175.999394)
		(stroke
			(width 0.2)
			(type default)
		)
		(layer "In1.Cu")
	)
	(gr_line
		(start 6.481826 -175.186594)
		(end 6.481826 -175.999394)
		(stroke
			(width 0.2)
			(type default)
		)
		(layer "In1.Cu")
	)
	(gr_arc
		(start 6.481826 -172.799502)
		(mid 6.992366 -173.310042)
		(end 7.502906 -172.799502)
		(stroke
			(width 0.2)
			(type default)
		)
		(layer "In1.Cu")
	)
	(gr_line
		(start 6.481826 -171.986702)
		(end 6.481826 -172.799502)
		(stroke
			(width 0.2)
			(type default)
		)
		(layer "In1.Cu")
	)
	(gr_arc
		(start 6.481826 -169.59961)
		(mid 6.992366 -170.11015)
		(end 7.502906 -169.59961)
		(stroke
			(width 0.2)
			(type default)
		)
		(layer "In1.Cu")
	)
	(gr_line
		(start 6.481826 -168.78681)
		(end 6.481826 -169.59961)
		(stroke
			(width 0.2)
			(type default)
		)
		(layer "In1.Cu")
	)
	(gr_arc
		(start 6.481826 -163.199572)
		(mid 6.992366 -163.710112)
		(end 7.502906 -163.199572)
		(stroke
			(width 0.2)
			(type default)
		)
		(layer "In1.Cu")
	)
	(gr_line
		(start 6.481826 -162.386772)
		(end 6.481826 -163.199572)
		(stroke
			(width 0.2)
			(type default)
		)
		(layer "In1.Cu")
	)
	(gr_arc
		(start 6.481826 -159.999426)
		(mid 6.992366 -160.509966)
		(end 7.502906 -159.999426)
		(stroke
			(width 0.2)
			(type default)
		)
		(layer "In1.Cu")
	)
	(gr_line
		(start 6.481826 -159.186626)
		(end 6.481826 -159.999426)
		(stroke
			(width 0.2)
			(type default)
		)
		(layer "In1.Cu")
	)
	(gr_arc
		(start 6.481826 -156.786834)
		(mid 6.992366 -157.297374)
		(end 7.502906 -156.786834)
		(stroke
			(width 0.2)
			(type default)
		)
		(layer "In1.Cu")
	)
	(gr_line
		(start 6.481826 -155.974034)
		(end 6.481826 -156.786834)
		(stroke
			(width 0.2)
			(type default)
		)
		(layer "In1.Cu")
	)
	(gr_arc
		(start 6.481826 -153.599388)
		(mid 6.992366 -154.109928)
		(end 7.502906 -153.599388)
		(stroke
			(width 0.2)
			(type default)
		)
		(layer "In1.Cu")
	)
	(gr_line
		(start 6.481826 -152.786588)
		(end 6.481826 -153.599388)
		(stroke
			(width 0.2)
			(type default)
		)
		(layer "In1.Cu")
	)
	(gr_line
		(start 6.5532 -379.2474)
		(end 7.874 -379.2474)
		(stroke
			(width 0.2)
			(type default)
		)
		(layer "In1.Cu")
	)
	(gr_arc
		(start 6.5532 -377.7234)
		(mid 6.481358 -377.753158)
		(end 6.4516 -377.825)
		(stroke
			(width 0.2)
			(type default)
		)
		(layer "In1.Cu")
	)
	(gr_arc
		(start 7.1628 -452.0311)
		(mid 7.192558 -452.102942)
		(end 7.2644 -452.1327)
		(stroke
			(width 0.2)
			(type default)
		)
		(layer "In1.Cu")
	)
	(gr_line
		(start 7.1628 -450.7357)
		(end 7.1628 -452.0311)
		(stroke
			(width 0.2)
			(type default)
		)
		(layer "In1.Cu")
	)
	(gr_line
		(start 7.2644 -452.1327)
		(end 8.5852 -452.1327)
		(stroke
			(width 0.2)
			(type default)
		)
		(layer "In1.Cu")
	)
	(gr_arc
		(start 7.2644 -450.6341)
		(mid 7.192558 -450.663858)
		(end 7.1628 -450.7357)
		(stroke
			(width 0.2)
			(type default)
		)
		(layer "In1.Cu")
	)
	(gr_arc
		(start 7.2898 -449.978272)
		(mid 7.80034 -449.467732)
		(end 7.2898 -448.957192)
		(stroke
			(width 0.2)
			(type default)
		)
		(layer "In1.Cu")
	)
	(gr_line
		(start 7.2898 -448.957192)
		(end 6.477254 -448.957192)
		(stroke
			(width 0.2)
			(type default)
		)
		(layer "In1.Cu")
	)
	(gr_line
		(start 7.502906 -447.196972)
		(end 7.502906 -446.384172)
		(stroke
			(width 0.2)
			(type default)
		)
		(layer "In1.Cu")
	)
	(gr_arc
		(start 7.502906 -446.384172)
		(mid 6.992366 -445.873632)
		(end 6.481826 -446.384172)
		(stroke
			(width 0.2)
			(type default)
		)
		(layer "In1.Cu")
	)
	(gr_line
		(start 7.502906 -443.99708)
		(end 7.502906 -443.18428)
		(stroke
			(width 0.2)
			(type default)
		)
		(layer "In1.Cu")
	)
	(gr_arc
		(start 7.502906 -443.18428)
		(mid 6.992366 -442.67374)
		(end 6.481826 -443.18428)
		(stroke
			(width 0.2)
			(type default)
		)
		(layer "In1.Cu")
	)
	(gr_line
		(start 7.502906 -440.796934)
		(end 7.502906 -439.984134)
		(stroke
			(width 0.2)
			(type default)
		)
		(layer "In1.Cu")
	)
	(gr_arc
		(start 7.502906 -439.984134)
		(mid 6.992366 -439.473594)
		(end 6.481826 -439.984134)
		(stroke
			(width 0.2)
			(type default)
		)
		(layer "In1.Cu")
	)
	(gr_line
		(start 7.502906 -437.597042)
		(end 7.502906 -436.784242)
		(stroke
			(width 0.2)
			(type default)
		)
		(layer "In1.Cu")
	)
	(gr_arc
		(start 7.502906 -436.784242)
		(mid 6.992366 -436.273702)
		(end 6.481826 -436.784242)
		(stroke
			(width 0.2)
			(type default)
		)
		(layer "In1.Cu")
	)
	(gr_line
		(start 7.502906 -431.997104)
		(end 7.502906 -431.184558)
		(stroke
			(width 0.2)
			(type default)
		)
		(layer "In1.Cu")
	)
	(gr_arc
		(start 7.502906 -431.184558)
		(mid 6.992493 -430.673764)
		(end 6.481826 -431.184304)
		(stroke
			(width 0.2)
			(type default)
		)
		(layer "In1.Cu")
	)
	(gr_line
		(start 7.502906 -428.796958)
		(end 7.502906 -427.984412)
		(stroke
			(width 0.2)
			(type default)
		)
		(layer "In1.Cu")
	)
	(gr_arc
		(start 7.502906 -427.984412)
		(mid 6.992493 -427.473618)
		(end 6.481826 -427.984158)
		(stroke
			(width 0.2)
			(type default)
		)
		(layer "In1.Cu")
	)
	(gr_line
		(start 7.502906 -425.597066)
		(end 7.502906 -424.78452)
		(stroke
			(width 0.2)
			(type default)
		)
		(layer "In1.Cu")
	)
	(gr_arc
		(start 7.502906 -424.78452)
		(mid 6.992493 -424.273726)
		(end 6.481826 -424.784266)
		(stroke
			(width 0.2)
			(type default)
		)
		(layer "In1.Cu")
	)
	(gr_line
		(start 7.502906 -415.948622)
		(end 7.502906 -415.136076)
		(stroke
			(width 0.2)
			(type default)
		)
		(layer "In1.Cu")
	)
	(gr_arc
		(start 7.502906 -415.136076)
		(mid 6.992493 -414.625282)
		(end 6.481826 -415.135822)
		(stroke
			(width 0.2)
			(type default)
		)
		(layer "In1.Cu")
	)
	(gr_line
		(start 7.502906 -412.748476)
		(end 7.502906 -411.935676)
		(stroke
			(width 0.2)
			(type default)
		)
		(layer "In1.Cu")
	)
	(gr_arc
		(start 7.502906 -411.935676)
		(mid 6.992366 -411.425136)
		(end 6.481826 -411.935676)
		(stroke
			(width 0.2)
			(type default)
		)
		(layer "In1.Cu")
	)
	(gr_line
		(start 7.502906 -409.548584)
		(end 7.502906 -408.735784)
		(stroke
			(width 0.2)
			(type default)
		)
		(layer "In1.Cu")
	)
	(gr_arc
		(start 7.502906 -408.735784)
		(mid 6.992366 -408.225244)
		(end 6.481826 -408.735784)
		(stroke
			(width 0.2)
			(type default)
		)
		(layer "In1.Cu")
	)
	(gr_line
		(start 7.502906 -406.348438)
		(end 7.502906 -405.535638)
		(stroke
			(width 0.2)
			(type default)
		)
		(layer "In1.Cu")
	)
	(gr_arc
		(start 7.502906 -405.535638)
		(mid 6.992366 -405.025098)
		(end 6.481826 -405.535638)
		(stroke
			(width 0.2)
			(type default)
		)
		(layer "In1.Cu")
	)
	(gr_line
		(start 7.502906 -403.148546)
		(end 7.502906 -402.335746)
		(stroke
			(width 0.2)
			(type default)
		)
		(layer "In1.Cu")
	)
	(gr_arc
		(start 7.502906 -402.335746)
		(mid 6.992366 -401.825206)
		(end 6.481826 -402.335746)
		(stroke
			(width 0.2)
			(type default)
		)
		(layer "In1.Cu")
	)
	(gr_line
		(start 7.502906 -397.548608)
		(end 7.502906 -396.736062)
		(stroke
			(width 0.2)
			(type default)
		)
		(layer "In1.Cu")
	)
	(gr_arc
		(start 7.502906 -396.736062)
		(mid 6.992493 -396.225268)
		(end 6.481826 -396.735808)
		(stroke
			(width 0.2)
			(type default)
		)
		(layer "In1.Cu")
	)
	(gr_line
		(start 7.502906 -394.348462)
		(end 7.502906 -393.535916)
		(stroke
			(width 0.2)
			(type default)
		)
		(layer "In1.Cu")
	)
	(gr_arc
		(start 7.502906 -393.535916)
		(mid 6.992493 -393.025122)
		(end 6.481826 -393.535662)
		(stroke
			(width 0.2)
			(type default)
		)
		(layer "In1.Cu")
	)
	(gr_line
		(start 7.502906 -391.14857)
		(end 7.502906 -390.336024)
		(stroke
			(width 0.2)
			(type default)
		)
		(layer "In1.Cu")
	)
	(gr_arc
		(start 7.502906 -390.336024)
		(mid 6.992493 -389.82523)
		(end 6.481826 -390.33577)
		(stroke
			(width 0.2)
			(type default)
		)
		(layer "In1.Cu")
	)
	(gr_line
		(start 7.502906 -387.948424)
		(end 7.502906 -387.135878)
		(stroke
			(width 0.2)
			(type default)
		)
		(layer "In1.Cu")
	)
	(gr_arc
		(start 7.502906 -387.135878)
		(mid 6.992493 -386.625084)
		(end 6.481826 -387.135624)
		(stroke
			(width 0.2)
			(type default)
		)
		(layer "In1.Cu")
	)
	(gr_line
		(start 7.502906 -357.148638)
		(end 7.502906 -356.335838)
		(stroke
			(width 0.2)
			(type default)
		)
		(layer "In1.Cu")
	)
	(gr_arc
		(start 7.502906 -356.335838)
		(mid 6.992366 -355.825298)
		(end 6.481826 -356.335838)
		(stroke
			(width 0.2)
			(type default)
		)
		(layer "In1.Cu")
	)
	(gr_line
		(start 7.502906 -353.948746)
		(end 7.502906 -353.1362)
		(stroke
			(width 0.2)
			(type default)
		)
		(layer "In1.Cu")
	)
	(gr_arc
		(start 7.502906 -353.1362)
		(mid 6.992493 -352.625406)
		(end 6.481826 -353.135946)
		(stroke
			(width 0.2)
			(type default)
		)
		(layer "In1.Cu")
	)
	(gr_line
		(start 7.502906 -350.7486)
		(end 7.502906 -349.9358)
		(stroke
			(width 0.2)
			(type default)
		)
		(layer "In1.Cu")
	)
	(gr_arc
		(start 7.502906 -349.9358)
		(mid 6.992366 -349.42526)
		(end 6.481826 -349.9358)
		(stroke
			(width 0.2)
			(type default)
		)
		(layer "In1.Cu")
	)
	(gr_line
		(start 7.502906 -347.548708)
		(end 7.502906 -346.735908)
		(stroke
			(width 0.2)
			(type default)
		)
		(layer "In1.Cu")
	)
	(gr_arc
		(start 7.502906 -346.735908)
		(mid 6.992366 -346.225368)
		(end 6.481826 -346.735908)
		(stroke
			(width 0.2)
			(type default)
		)
		(layer "In1.Cu")
	)
	(gr_line
		(start 7.502906 -344.399616)
		(end 7.502906 -343.58707)
		(stroke
			(width 0.2)
			(type default)
		)
		(layer "In1.Cu")
	)
	(gr_arc
		(start 7.502906 -343.58707)
		(mid 6.992493 -343.076276)
		(end 6.481826 -343.586816)
		(stroke
			(width 0.2)
			(type default)
		)
		(layer "In1.Cu")
	)
	(gr_line
		(start 7.502906 -341.19947)
		(end 7.502906 -340.386924)
		(stroke
			(width 0.2)
			(type default)
		)
		(layer "In1.Cu")
	)
	(gr_arc
		(start 7.502906 -340.386924)
		(mid 6.992493 -339.87613)
		(end 6.481826 -340.38667)
		(stroke
			(width 0.2)
			(type default)
		)
		(layer "In1.Cu")
	)
	(gr_line
		(start 7.502906 -337.999578)
		(end 7.502906 -337.187032)
		(stroke
			(width 0.2)
			(type default)
		)
		(layer "In1.Cu")
	)
	(gr_arc
		(start 7.502906 -337.187032)
		(mid 6.992493 -336.676238)
		(end 6.481826 -337.186778)
		(stroke
			(width 0.2)
			(type default)
		)
		(layer "In1.Cu")
	)
	(gr_line
		(start 7.502906 -334.799432)
		(end 7.502906 -333.986886)
		(stroke
			(width 0.2)
			(type default)
		)
		(layer "In1.Cu")
	)
	(gr_arc
		(start 7.502906 -333.986886)
		(mid 6.992493 -333.476092)
		(end 6.481826 -333.986632)
		(stroke
			(width 0.2)
			(type default)
		)
		(layer "In1.Cu")
	)
	(gr_line
		(start 7.502906 -329.148694)
		(end 7.502906 -328.335894)
		(stroke
			(width 0.2)
			(type default)
		)
		(layer "In1.Cu")
	)
	(gr_arc
		(start 7.502906 -328.335894)
		(mid 6.992366 -327.825354)
		(end 6.481826 -328.335894)
		(stroke
			(width 0.2)
			(type default)
		)
		(layer "In1.Cu")
	)
	(gr_line
		(start 7.502906 -325.948802)
		(end 7.502906 -325.136002)
		(stroke
			(width 0.2)
			(type default)
		)
		(layer "In1.Cu")
	)
	(gr_arc
		(start 7.502906 -325.136002)
		(mid 6.992366 -324.625462)
		(end 6.481826 -325.136002)
		(stroke
			(width 0.2)
			(type default)
		)
		(layer "In1.Cu")
	)
	(gr_line
		(start 7.502906 -322.748656)
		(end 7.502906 -321.935856)
		(stroke
			(width 0.2)
			(type default)
		)
		(layer "In1.Cu")
	)
	(gr_arc
		(start 7.502906 -321.935856)
		(mid 6.992366 -321.425316)
		(end 6.481826 -321.935856)
		(stroke
			(width 0.2)
			(type default)
		)
		(layer "In1.Cu")
	)
	(gr_line
		(start 7.502906 -319.548764)
		(end 7.502906 -318.735964)
		(stroke
			(width 0.2)
			(type default)
		)
		(layer "In1.Cu")
	)
	(gr_arc
		(start 7.502906 -318.735964)
		(mid 6.992366 -318.225424)
		(end 6.481826 -318.735964)
		(stroke
			(width 0.2)
			(type default)
		)
		(layer "In1.Cu")
	)
	(gr_line
		(start 7.502906 -311.54878)
		(end 7.502906 -310.73598)
		(stroke
			(width 0.2)
			(type default)
		)
		(layer "In1.Cu")
	)
	(gr_arc
		(start 7.502906 -310.73598)
		(mid 6.992366 -310.22544)
		(end 6.481826 -310.73598)
		(stroke
			(width 0.2)
			(type default)
		)
		(layer "In1.Cu")
	)
	(gr_line
		(start 7.502906 -308.348634)
		(end 7.502906 -307.535834)
		(stroke
			(width 0.2)
			(type default)
		)
		(layer "In1.Cu")
	)
	(gr_arc
		(start 7.502906 -307.535834)
		(mid 6.992366 -307.025294)
		(end 6.481826 -307.535834)
		(stroke
			(width 0.2)
			(type default)
		)
		(layer "In1.Cu")
	)
	(gr_line
		(start 7.502906 -305.148742)
		(end 7.502906 -304.335942)
		(stroke
			(width 0.2)
			(type default)
		)
		(layer "In1.Cu")
	)
	(gr_arc
		(start 7.502906 -304.335942)
		(mid 6.992366 -303.825402)
		(end 6.481826 -304.335942)
		(stroke
			(width 0.2)
			(type default)
		)
		(layer "In1.Cu")
	)
	(gr_line
		(start 7.502906 -301.948596)
		(end 7.502906 -301.135796)
		(stroke
			(width 0.2)
			(type default)
		)
		(layer "In1.Cu")
	)
	(gr_arc
		(start 7.502906 -301.135796)
		(mid 6.992366 -300.625256)
		(end 6.481826 -301.135796)
		(stroke
			(width 0.2)
			(type default)
		)
		(layer "In1.Cu")
	)
	(gr_line
		(start 7.502906 -298.748704)
		(end 7.502906 -297.935904)
		(stroke
			(width 0.2)
			(type default)
		)
		(layer "In1.Cu")
	)
	(gr_arc
		(start 7.502906 -297.935904)
		(mid 6.992366 -297.425364)
		(end 6.481826 -297.935904)
		(stroke
			(width 0.2)
			(type default)
		)
		(layer "In1.Cu")
	)
	(gr_line
		(start 7.502906 -295.548812)
		(end 7.502906 -294.736012)
		(stroke
			(width 0.2)
			(type default)
		)
		(layer "In1.Cu")
	)
	(gr_arc
		(start 7.502906 -294.736012)
		(mid 6.992366 -294.225472)
		(end 6.481826 -294.736012)
		(stroke
			(width 0.2)
			(type default)
		)
		(layer "In1.Cu")
	)
	(gr_line
		(start 7.502906 -292.348666)
		(end 7.502906 -291.535866)
		(stroke
			(width 0.2)
			(type default)
		)
		(layer "In1.Cu")
	)
	(gr_arc
		(start 7.502906 -291.535866)
		(mid 6.992366 -291.025326)
		(end 6.481826 -291.535866)
		(stroke
			(width 0.2)
			(type default)
		)
		(layer "In1.Cu")
	)
	(gr_line
		(start 7.502906 -289.148774)
		(end 7.502906 -288.336228)
		(stroke
			(width 0.2)
			(type default)
		)
		(layer "In1.Cu")
	)
	(gr_arc
		(start 7.502906 -288.336228)
		(mid 6.992493 -287.825434)
		(end 6.481826 -288.335974)
		(stroke
			(width 0.2)
			(type default)
		)
		(layer "In1.Cu")
	)
	(gr_line
		(start 7.502906 -282.799536)
		(end 7.502906 -281.98699)
		(stroke
			(width 0.2)
			(type default)
		)
		(layer "In1.Cu")
	)
	(gr_arc
		(start 7.502906 -281.98699)
		(mid 6.992493 -281.476196)
		(end 6.481826 -281.986736)
		(stroke
			(width 0.2)
			(type default)
		)
		(layer "In1.Cu")
	)
	(gr_line
		(start 7.502906 -279.59939)
		(end 7.502906 -278.786844)
		(stroke
			(width 0.2)
			(type default)
		)
		(layer "In1.Cu")
	)
	(gr_arc
		(start 7.502906 -278.786844)
		(mid 6.992493 -278.27605)
		(end 6.481826 -278.78659)
		(stroke
			(width 0.2)
			(type default)
		)
		(layer "In1.Cu")
	)
	(gr_line
		(start 7.502906 -231.148636)
		(end 7.502906 -230.33609)
		(stroke
			(width 0.2)
			(type default)
		)
		(layer "In1.Cu")
	)
	(gr_arc
		(start 7.502906 -230.33609)
		(mid 6.992493 -229.825296)
		(end 6.481826 -230.335836)
		(stroke
			(width 0.2)
			(type default)
		)
		(layer "In1.Cu")
	)
	(gr_line
		(start 7.502906 -227.948744)
		(end 7.502906 -227.136198)
		(stroke
			(width 0.2)
			(type default)
		)
		(layer "In1.Cu")
	)
	(gr_arc
		(start 7.502906 -227.136198)
		(mid 6.992493 -226.625404)
		(end 6.481826 -227.135944)
		(stroke
			(width 0.2)
			(type default)
		)
		(layer "In1.Cu")
	)
	(gr_line
		(start 7.502906 -224.710498)
		(end 7.502906 -223.897952)
		(stroke
			(width 0.2)
			(type default)
		)
		(layer "In1.Cu")
	)
	(gr_arc
		(start 7.502906 -223.897952)
		(mid 6.992493 -223.387158)
		(end 6.481826 -223.897698)
		(stroke
			(width 0.2)
			(type default)
		)
		(layer "In1.Cu")
	)
	(gr_line
		(start 7.502906 -221.497906)
		(end 7.502906 -220.685106)
		(stroke
			(width 0.2)
			(type default)
		)
		(layer "In1.Cu")
	)
	(gr_arc
		(start 7.502906 -220.685106)
		(mid 6.992366 -220.174566)
		(end 6.481826 -220.685106)
		(stroke
			(width 0.2)
			(type default)
		)
		(layer "In1.Cu")
	)
	(gr_line
		(start 7.502906 -218.298014)
		(end 7.502906 -217.485468)
		(stroke
			(width 0.2)
			(type default)
		)
		(layer "In1.Cu")
	)
	(gr_arc
		(start 7.502906 -217.485468)
		(mid 6.992493 -216.974674)
		(end 6.481826 -217.485214)
		(stroke
			(width 0.2)
			(type default)
		)
		(layer "In1.Cu")
	)
	(gr_line
		(start 7.502906 -215.097868)
		(end 7.502906 -214.285322)
		(stroke
			(width 0.2)
			(type default)
		)
		(layer "In1.Cu")
	)
	(gr_arc
		(start 7.502906 -214.285322)
		(mid 6.992493 -213.774528)
		(end 6.481826 -214.285068)
		(stroke
			(width 0.2)
			(type default)
		)
		(layer "In1.Cu")
	)
	(gr_line
		(start 7.502906 -211.948776)
		(end 7.502906 -211.13623)
		(stroke
			(width 0.2)
			(type default)
		)
		(layer "In1.Cu")
	)
	(gr_arc
		(start 7.502906 -211.13623)
		(mid 6.992493 -210.625436)
		(end 6.481826 -211.135976)
		(stroke
			(width 0.2)
			(type default)
		)
		(layer "In1.Cu")
	)
	(gr_line
		(start 7.502906 -208.74863)
		(end 7.502906 -207.936084)
		(stroke
			(width 0.2)
			(type default)
		)
		(layer "In1.Cu")
	)
	(gr_arc
		(start 7.502906 -207.936084)
		(mid 6.992493 -207.42529)
		(end 6.481826 -207.93583)
		(stroke
			(width 0.2)
			(type default)
		)
		(layer "In1.Cu")
	)
	(gr_line
		(start 7.502906 -205.548738)
		(end 7.502906 -204.736192)
		(stroke
			(width 0.2)
			(type default)
		)
		(layer "In1.Cu")
	)
	(gr_arc
		(start 7.502906 -204.736192)
		(mid 6.992493 -204.225398)
		(end 6.481826 -204.735938)
		(stroke
			(width 0.2)
			(type default)
		)
		(layer "In1.Cu")
	)
	(gr_line
		(start 7.502906 -202.348592)
		(end 7.502906 -201.536046)
		(stroke
			(width 0.2)
			(type default)
		)
		(layer "In1.Cu")
	)
	(gr_arc
		(start 7.502906 -201.536046)
		(mid 6.992493 -201.025252)
		(end 6.481826 -201.535792)
		(stroke
			(width 0.2)
			(type default)
		)
		(layer "In1.Cu")
	)
	(gr_line
		(start 7.502906 -196.748654)
		(end 7.502906 -195.936108)
		(stroke
			(width 0.2)
			(type default)
		)
		(layer "In1.Cu")
	)
	(gr_arc
		(start 7.502906 -195.936108)
		(mid 6.992493 -195.425314)
		(end 6.481826 -195.935854)
		(stroke
			(width 0.2)
			(type default)
		)
		(layer "In1.Cu")
	)
	(gr_line
		(start 7.502906 -193.548762)
		(end 7.502906 -192.736216)
		(stroke
			(width 0.2)
			(type default)
		)
		(layer "In1.Cu")
	)
	(gr_arc
		(start 7.502906 -192.736216)
		(mid 6.992493 -192.225422)
		(end 6.481826 -192.735962)
		(stroke
			(width 0.2)
			(type default)
		)
		(layer "In1.Cu")
	)
	(gr_line
		(start 7.502906 -185.548778)
		(end 7.502906 -184.736232)
		(stroke
			(width 0.2)
			(type default)
		)
		(layer "In1.Cu")
	)
	(gr_arc
		(start 7.502906 -184.736232)
		(mid 6.992493 -184.225438)
		(end 6.481826 -184.735978)
		(stroke
			(width 0.2)
			(type default)
		)
		(layer "In1.Cu")
	)
	(gr_line
		(start 7.502906 -182.348632)
		(end 7.502906 -181.536086)
		(stroke
			(width 0.2)
			(type default)
		)
		(layer "In1.Cu")
	)
	(gr_arc
		(start 7.502906 -181.536086)
		(mid 6.992493 -181.025292)
		(end 6.481826 -181.535832)
		(stroke
			(width 0.2)
			(type default)
		)
		(layer "In1.Cu")
	)
	(gr_line
		(start 7.502906 -179.19954)
		(end 7.502906 -178.386994)
		(stroke
			(width 0.2)
			(type default)
		)
		(layer "In1.Cu")
	)
	(gr_arc
		(start 7.502906 -178.386994)
		(mid 6.992493 -177.8762)
		(end 6.481826 -178.38674)
		(stroke
			(width 0.2)
			(type default)
		)
		(layer "In1.Cu")
	)
	(gr_line
		(start 7.502906 -175.999394)
		(end 7.502906 -175.186848)
		(stroke
			(width 0.2)
			(type default)
		)
		(layer "In1.Cu")
	)
	(gr_arc
		(start 7.502906 -175.186848)
		(mid 6.992493 -174.676054)
		(end 6.481826 -175.186594)
		(stroke
			(width 0.2)
			(type default)
		)
		(layer "In1.Cu")
	)
	(gr_line
		(start 7.502906 -172.799502)
		(end 7.502906 -171.986956)
		(stroke
			(width 0.2)
			(type default)
		)
		(layer "In1.Cu")
	)
	(gr_arc
		(start 7.502906 -171.986956)
		(mid 6.992493 -171.476162)
		(end 6.481826 -171.986702)
		(stroke
			(width 0.2)
			(type default)
		)
		(layer "In1.Cu")
	)
	(gr_line
		(start 7.502906 -169.59961)
		(end 7.502906 -168.787064)
		(stroke
			(width 0.2)
			(type default)
		)
		(layer "In1.Cu")
	)
	(gr_arc
		(start 7.502906 -168.787064)
		(mid 6.992493 -168.27627)
		(end 6.481826 -168.78681)
		(stroke
			(width 0.2)
			(type default)
		)
		(layer "In1.Cu")
	)
	(gr_line
		(start 7.502906 -163.199572)
		(end 7.502906 -162.387026)
		(stroke
			(width 0.2)
			(type default)
		)
		(layer "In1.Cu")
	)
	(gr_arc
		(start 7.502906 -162.387026)
		(mid 6.992493 -161.876232)
		(end 6.481826 -162.386772)
		(stroke
			(width 0.2)
			(type default)
		)
		(layer "In1.Cu")
	)
	(gr_line
		(start 7.502906 -159.999426)
		(end 7.502906 -159.18688)
		(stroke
			(width 0.2)
			(type default)
		)
		(layer "In1.Cu")
	)
	(gr_arc
		(start 7.502906 -159.18688)
		(mid 6.992493 -158.676086)
		(end 6.481826 -159.186626)
		(stroke
			(width 0.2)
			(type default)
		)
		(layer "In1.Cu")
	)
	(gr_line
		(start 7.502906 -156.786834)
		(end 7.502906 -155.974288)
		(stroke
			(width 0.2)
			(type default)
		)
		(layer "In1.Cu")
	)
	(gr_arc
		(start 7.502906 -155.974288)
		(mid 6.992493 -155.463494)
		(end 6.481826 -155.974034)
		(stroke
			(width 0.2)
			(type default)
		)
		(layer "In1.Cu")
	)
	(gr_line
		(start 7.502906 -153.599388)
		(end 7.502906 -152.786842)
		(stroke
			(width 0.2)
			(type default)
		)
		(layer "In1.Cu")
	)
	(gr_arc
		(start 7.502906 -152.786842)
		(mid 6.992493 -152.276048)
		(end 6.481826 -152.786588)
		(stroke
			(width 0.2)
			(type default)
		)
		(layer "In1.Cu")
	)
	(gr_arc
		(start 7.874 -379.2474)
		(mid 7.945842 -379.217642)
		(end 7.9756 -379.1458)
		(stroke
			(width 0.2)
			(type default)
		)
		(layer "In1.Cu")
	)
	(gr_line
		(start 7.874 -377.7234)
		(end 6.5532 -377.7234)
		(stroke
			(width 0.2)
			(type default)
		)
		(layer "In1.Cu")
	)
	(gr_line
		(start 7.9756 -379.1458)
		(end 7.9756 -377.825)
		(stroke
			(width 0.2)
			(type default)
		)
		(layer "In1.Cu")
	)
	(gr_arc
		(start 7.9756 -377.825)
		(mid 7.945842 -377.753158)
		(end 7.874 -377.7234)
		(stroke
			(width 0.2)
			(type default)
		)
		(layer "In1.Cu")
	)
	(gr_arc
		(start 8.0391 -384.7592)
		(mid 8.068858 -384.831042)
		(end 8.1407 -384.8608)
		(stroke
			(width 0.2)
			(type default)
		)
		(layer "In1.Cu")
	)
	(gr_line
		(start 8.0391 -383.4384)
		(end 8.0391 -384.7592)
		(stroke
			(width 0.2)
			(type default)
		)
		(layer "In1.Cu")
	)
	(gr_line
		(start 8.1407 -384.8608)
		(end 9.4361 -384.8608)
		(stroke
			(width 0.2)
			(type default)
		)
		(layer "In1.Cu")
	)
	(gr_arc
		(start 8.1407 -383.3368)
		(mid 8.068858 -383.366558)
		(end 8.0391 -383.4384)
		(stroke
			(width 0.2)
			(type default)
		)
		(layer "In1.Cu")
	)
	(gr_line
		(start 8.382254 -386.113782)
		(end 9.1948 -386.113782)
		(stroke
			(width 0.2)
			(type default)
		)
		(layer "In1.Cu")
	)
	(gr_arc
		(start 8.382254 -385.092702)
		(mid 7.871714 -385.603242)
		(end 8.382254 -386.113782)
		(stroke
			(width 0.2)
			(type default)
		)
		(layer "In1.Cu")
	)
	(gr_arc
		(start 8.5852 -452.1327)
		(mid 8.657042 -452.102942)
		(end 8.6868 -452.0311)
		(stroke
			(width 0.2)
			(type default)
		)
		(layer "In1.Cu")
	)
	(gr_line
		(start 8.5852 -450.6341)
		(end 7.2644 -450.6341)
		(stroke
			(width 0.2)
			(type default)
		)
		(layer "In1.Cu")
	)
	(gr_line
		(start 8.6868 -452.0311)
		(end 8.6868 -450.7357)
		(stroke
			(width 0.2)
			(type default)
		)
		(layer "In1.Cu")
	)
	(gr_arc
		(start 8.6868 -450.7357)
		(mid 8.657042 -450.663858)
		(end 8.5852 -450.6341)
		(stroke
			(width 0.2)
			(type default)
		)
		(layer "In1.Cu")
	)
	(gr_arc
		(start 9.1948 -386.113782)
		(mid 9.705594 -385.603369)
		(end 9.195054 -385.092702)
		(stroke
			(width 0.2)
			(type default)
		)
		(layer "In1.Cu")
	)
	(gr_line
		(start 9.195054 -385.092702)
		(end 8.382254 -385.092702)
		(stroke
			(width 0.2)
			(type default)
		)
		(layer "In1.Cu")
	)
	(gr_arc
		(start 9.4361 -384.8608)
		(mid 9.507942 -384.831042)
		(end 9.5377 -384.7592)
		(stroke
			(width 0.2)
			(type default)
		)
		(layer "In1.Cu")
	)
	(gr_line
		(start 9.4361 -383.3368)
		(end 8.1407 -383.3368)
		(stroke
			(width 0.2)
			(type default)
		)
		(layer "In1.Cu")
	)
	(gr_line
		(start 9.5377 -384.7592)
		(end 9.5377 -383.4384)
		(stroke
			(width 0.2)
			(type default)
		)
		(layer "In1.Cu")
	)
	(gr_arc
		(start 9.5377 -383.4384)
		(mid 9.507942 -383.366558)
		(end 9.4361 -383.3368)
		(stroke
			(width 0.2)
			(type default)
		)
		(layer "In1.Cu")
	)
	(gr_arc
		(start 13.632688 -426.503592)
		(mid 13.662446 -426.575434)
		(end 13.734288 -426.605192)
		(stroke
			(width 0.2)
			(type default)
		)
		(layer "In1.Cu")
	)
	(gr_line
		(start 13.632688 -425.182792)
		(end 13.632688 -426.503592)
		(stroke
			(width 0.2)
			(type default)
		)
		(layer "In1.Cu")
	)
	(gr_line
		(start 13.734288 -426.605192)
		(end 15.029688 -426.605192)
		(stroke
			(width 0.2)
			(type default)
		)
		(layer "In1.Cu")
	)
	(gr_arc
		(start 13.734288 -425.081192)
		(mid 13.662446 -425.11095)
		(end 13.632688 -425.182792)
		(stroke
			(width 0.2)
			(type default)
		)
		(layer "In1.Cu")
	)
	(gr_arc
		(start 15.029688 -426.605192)
		(mid 15.10153 -426.575434)
		(end 15.131288 -426.503592)
		(stroke
			(width 0.2)
			(type default)
		)
		(layer "In1.Cu")
	)
	(gr_line
		(start 15.029688 -425.081192)
		(end 13.734288 -425.081192)
		(stroke
			(width 0.2)
			(type default)
		)
		(layer "In1.Cu")
	)
	(gr_line
		(start 15.131288 -426.503592)
		(end 15.131288 -425.182792)
		(stroke
			(width 0.2)
			(type default)
		)
		(layer "In1.Cu")
	)
	(gr_arc
		(start 15.131288 -425.182792)
		(mid 15.10153 -425.11095)
		(end 15.029688 -425.081192)
		(stroke
			(width 0.2)
			(type default)
		)
		(layer "In1.Cu")
	)
	(gr_arc
		(start 16.76146 -445.415924)
		(mid 17.271873 -445.926718)
		(end 17.78254 -445.416178)
		(stroke
			(width 0.2)
			(type default)
		)
		(layer "In1.Cu")
	)
	(gr_line
		(start 16.76146 -444.603378)
		(end 16.76146 -445.415924)
		(stroke
			(width 0.2)
			(type default)
		)
		(layer "In1.Cu")
	)
	(gr_arc
		(start 16.76146 -342.415876)
		(mid 17.271873 -342.92667)
		(end 17.78254 -342.41613)
		(stroke
			(width 0.2)
			(type default)
		)
		(layer "In1.Cu")
	)
	(gr_line
		(start 16.76146 -341.60333)
		(end 16.76146 -342.415876)
		(stroke
			(width 0.2)
			(type default)
		)
		(layer "In1.Cu")
	)
	(gr_arc
		(start 16.76146 -239.415828)
		(mid 17.271873 -239.926622)
		(end 17.78254 -239.416082)
		(stroke
			(width 0.2)
			(type default)
		)
		(layer "In1.Cu")
	)
	(gr_line
		(start 16.76146 -238.603282)
		(end 16.76146 -239.415828)
		(stroke
			(width 0.2)
			(type default)
		)
		(layer "In1.Cu")
	)
	(gr_arc
		(start 16.76146 -136.41578)
		(mid 17.271873 -136.926574)
		(end 17.78254 -136.416034)
		(stroke
			(width 0.2)
			(type default)
		)
		(layer "In1.Cu")
	)
	(gr_line
		(start 16.76146 -135.603234)
		(end 16.76146 -136.41578)
		(stroke
			(width 0.2)
			(type default)
		)
		(layer "In1.Cu")
	)
	(gr_arc
		(start 16.76146 -33.415986)
		(mid 17.272 -33.926526)
		(end 17.78254 -33.415986)
		(stroke
			(width 0.2)
			(type default)
		)
		(layer "In1.Cu")
	)
	(gr_line
		(start 16.76146 -32.603186)
		(end 16.76146 -33.415986)
		(stroke
			(width 0.2)
			(type default)
		)
		(layer "In1.Cu")
	)
	(gr_line
		(start 17.78254 -445.416178)
		(end 17.78254 -444.603378)
		(stroke
			(width 0.2)
			(type default)
		)
		(layer "In1.Cu")
	)
	(gr_arc
		(start 17.78254 -444.603378)
		(mid 17.272 -444.092838)
		(end 16.76146 -444.603378)
		(stroke
			(width 0.2)
			(type default)
		)
		(layer "In1.Cu")
	)
	(gr_line
		(start 17.78254 -342.41613)
		(end 17.78254 -341.60333)
		(stroke
			(width 0.2)
			(type default)
		)
		(layer "In1.Cu")
	)
	(gr_arc
		(start 17.78254 -341.60333)
		(mid 17.272 -341.09279)
		(end 16.76146 -341.60333)
		(stroke
			(width 0.2)
			(type default)
		)
		(layer "In1.Cu")
	)
	(gr_line
		(start 17.78254 -239.416082)
		(end 17.78254 -238.603282)
		(stroke
			(width 0.2)
			(type default)
		)
		(layer "In1.Cu")
	)
	(gr_arc
		(start 17.78254 -238.603282)
		(mid 17.272 -238.092742)
		(end 16.76146 -238.603282)
		(stroke
			(width 0.2)
			(type default)
		)
		(layer "In1.Cu")
	)
	(gr_line
		(start 17.78254 -136.416034)
		(end 17.78254 -135.603234)
		(stroke
			(width 0.2)
			(type default)
		)
		(layer "In1.Cu")
	)
	(gr_arc
		(start 17.78254 -135.603234)
		(mid 17.272 -135.092694)
		(end 16.76146 -135.603234)
		(stroke
			(width 0.2)
			(type default)
		)
		(layer "In1.Cu")
	)
	(gr_line
		(start 17.78254 -33.415986)
		(end 17.78254 -32.60344)
		(stroke
			(width 0.2)
			(type default)
		)
		(layer "In1.Cu")
	)
	(gr_arc
		(start 17.78254 -32.60344)
		(mid 17.272127 -32.092646)
		(end 16.76146 -32.603186)
		(stroke
			(width 0.2)
			(type default)
		)
		(layer "In1.Cu")
	)
	(gr_line
		(start 18.60677 -445.955928)
		(end 18.607024 -445.956182)
		(stroke
			(width 0.2)
			(type default)
		)
		(layer "In1.Cu")
	)
	(gr_line
		(start 18.60677 -444.063882)
		(end 18.60677 -445.955928)
		(stroke
			(width 0.2)
			(type default)
		)
		(layer "In1.Cu")
	)
	(gr_line
		(start 18.60677 -342.95588)
		(end 18.607024 -342.956134)
		(stroke
			(width 0.2)
			(type default)
		)
		(layer "In1.Cu")
	)
	(gr_line
		(start 18.60677 -341.063834)
		(end 18.60677 -342.95588)
		(stroke
			(width 0.2)
			(type default)
		)
		(layer "In1.Cu")
	)
	(gr_line
		(start 18.60677 -239.955832)
		(end 18.607024 -239.956086)
		(stroke
			(width 0.2)
			(type default)
		)
		(layer "In1.Cu")
	)
	(gr_line
		(start 18.60677 -238.063786)
		(end 18.60677 -239.955832)
		(stroke
			(width 0.2)
			(type default)
		)
		(layer "In1.Cu")
	)
	(gr_line
		(start 18.60677 -136.955784)
		(end 18.607024 -136.956038)
		(stroke
			(width 0.2)
			(type default)
		)
		(layer "In1.Cu")
	)
	(gr_line
		(start 18.60677 -135.063738)
		(end 18.60677 -136.955784)
		(stroke
			(width 0.2)
			(type default)
		)
		(layer "In1.Cu")
	)
	(gr_line
		(start 18.60677 -33.955736)
		(end 18.607024 -33.95599)
		(stroke
			(width 0.2)
			(type default)
		)
		(layer "In1.Cu")
	)
	(gr_line
		(start 18.60677 -32.06369)
		(end 18.60677 -33.955736)
		(stroke
			(width 0.2)
			(type default)
		)
		(layer "In1.Cu")
	)
	(gr_line
		(start 18.607024 -445.956182)
		(end 20.61337 -445.956182)
		(stroke
			(width 0.2)
			(type default)
		)
		(layer "In1.Cu")
	)
	(gr_line
		(start 18.607024 -342.956134)
		(end 20.61337 -342.956134)
		(stroke
			(width 0.2)
			(type default)
		)
		(layer "In1.Cu")
	)
	(gr_line
		(start 18.607024 -239.956086)
		(end 20.61337 -239.956086)
		(stroke
			(width 0.2)
			(type default)
		)
		(layer "In1.Cu")
	)
	(gr_line
		(start 18.607024 -136.956038)
		(end 20.61337 -136.956038)
		(stroke
			(width 0.2)
			(type default)
		)
		(layer "In1.Cu")
	)
	(gr_line
		(start 18.607024 -33.95599)
		(end 20.61337 -33.95599)
		(stroke
			(width 0.2)
			(type default)
		)
		(layer "In1.Cu")
	)
	(gr_line
		(start 20.61337 -445.956182)
		(end 20.61337 -444.063882)
		(stroke
			(width 0.2)
			(type default)
		)
		(layer "In1.Cu")
	)
	(gr_line
		(start 20.61337 -444.063882)
		(end 18.60677 -444.063882)
		(stroke
			(width 0.2)
			(type default)
		)
		(layer "In1.Cu")
	)
	(gr_line
		(start 20.61337 -342.956134)
		(end 20.61337 -341.063834)
		(stroke
			(width 0.2)
			(type default)
		)
		(layer "In1.Cu")
	)
	(gr_line
		(start 20.61337 -341.063834)
		(end 18.60677 -341.063834)
		(stroke
			(width 0.2)
			(type default)
		)
		(layer "In1.Cu")
	)
	(gr_line
		(start 20.61337 -239.956086)
		(end 20.61337 -238.063786)
		(stroke
			(width 0.2)
			(type default)
		)
		(layer "In1.Cu")
	)
	(gr_line
		(start 20.61337 -238.063786)
		(end 18.60677 -238.063786)
		(stroke
			(width 0.2)
			(type default)
		)
		(layer "In1.Cu")
	)
	(gr_line
		(start 20.61337 -136.956038)
		(end 20.61337 -135.063738)
		(stroke
			(width 0.2)
			(type default)
		)
		(layer "In1.Cu")
	)
	(gr_line
		(start 20.61337 -135.063738)
		(end 18.60677 -135.063738)
		(stroke
			(width 0.2)
			(type default)
		)
		(layer "In1.Cu")
	)
	(gr_line
		(start 20.61337 -33.95599)
		(end 20.61337 -32.06369)
		(stroke
			(width 0.2)
			(type default)
		)
		(layer "In1.Cu")
	)
	(gr_line
		(start 20.61337 -32.06369)
		(end 18.60677 -32.06369)
		(stroke
			(width 0.2)
			(type default)
		)
		(layer "In1.Cu")
	)
	(gr_line
		(start 21.796756 -454.355962)
		(end 21.79701 -454.356216)
		(stroke
			(width 0.2)
			(type default)
		)
		(layer "In1.Cu")
	)
	(gr_line
		(start 21.796756 -452.463916)
		(end 21.796756 -454.355962)
		(stroke
			(width 0.2)
			(type default)
		)
		(layer "In1.Cu")
	)
	(gr_line
		(start 21.796756 -451.955916)
		(end 21.79701 -451.95617)
		(stroke
			(width 0.2)
			(type default)
		)
		(layer "In1.Cu")
	)
	(gr_line
		(start 21.796756 -450.06387)
		(end 21.796756 -451.955916)
		(stroke
			(width 0.2)
			(type default)
		)
		(layer "In1.Cu")
	)
	(gr_line
		(start 21.796756 -449.55587)
		(end 21.79701 -449.556124)
		(stroke
			(width 0.2)
			(type default)
		)
		(layer "In1.Cu")
	)
	(gr_line
		(start 21.796756 -447.664078)
		(end 21.796756 -449.55587)
		(stroke
			(width 0.2)
			(type default)
		)
		(layer "In1.Cu")
	)
	(gr_line
		(start 21.796756 -439.15584)
		(end 21.79701 -439.156094)
		(stroke
			(width 0.2)
			(type default)
		)
		(layer "In1.Cu")
	)
	(gr_line
		(start 21.796756 -437.264048)
		(end 21.796756 -439.15584)
		(stroke
			(width 0.2)
			(type default)
		)
		(layer "In1.Cu")
	)
	(gr_line
		(start 21.796756 -436.756048)
		(end 21.79701 -436.756302)
		(stroke
			(width 0.2)
			(type default)
		)
		(layer "In1.Cu")
	)
	(gr_line
		(start 21.796756 -434.864002)
		(end 21.796756 -436.756048)
		(stroke
			(width 0.2)
			(type default)
		)
		(layer "In1.Cu")
	)
	(gr_line
		(start 21.796756 -434.356002)
		(end 21.79701 -434.356256)
		(stroke
			(width 0.2)
			(type default)
		)
		(layer "In1.Cu")
	)
	(gr_line
		(start 21.796756 -432.463956)
		(end 21.796756 -434.356002)
		(stroke
			(width 0.2)
			(type default)
		)
		(layer "In1.Cu")
	)
	(gr_line
		(start 21.796756 -431.955956)
		(end 21.79701 -431.95621)
		(stroke
			(width 0.2)
			(type default)
		)
		(layer "In1.Cu")
	)
	(gr_line
		(start 21.796756 -430.06391)
		(end 21.796756 -431.955956)
		(stroke
			(width 0.2)
			(type default)
		)
		(layer "In1.Cu")
	)
	(gr_line
		(start 21.796756 -429.55591)
		(end 21.79701 -429.556164)
		(stroke
			(width 0.2)
			(type default)
		)
		(layer "In1.Cu")
	)
	(gr_line
		(start 21.796756 -427.663864)
		(end 21.796756 -429.55591)
		(stroke
			(width 0.2)
			(type default)
		)
		(layer "In1.Cu")
	)
	(gr_line
		(start 21.796756 -427.155864)
		(end 21.79701 -427.156118)
		(stroke
			(width 0.2)
			(type default)
		)
		(layer "In1.Cu")
	)
	(gr_line
		(start 21.796756 -425.263818)
		(end 21.796756 -427.155864)
		(stroke
			(width 0.2)
			(type default)
		)
		(layer "In1.Cu")
	)
	(gr_line
		(start 21.796756 -351.355914)
		(end 21.79701 -351.356168)
		(stroke
			(width 0.2)
			(type default)
		)
		(layer "In1.Cu")
	)
	(gr_line
		(start 21.796756 -349.463868)
		(end 21.796756 -351.355914)
		(stroke
			(width 0.2)
			(type default)
		)
		(layer "In1.Cu")
	)
	(gr_line
		(start 21.796756 -348.955868)
		(end 21.79701 -348.956122)
		(stroke
			(width 0.2)
			(type default)
		)
		(layer "In1.Cu")
	)
	(gr_line
		(start 21.796756 -347.063822)
		(end 21.796756 -348.955868)
		(stroke
			(width 0.2)
			(type default)
		)
		(layer "In1.Cu")
	)
	(gr_line
		(start 21.796756 -346.555822)
		(end 21.79701 -346.556076)
		(stroke
			(width 0.2)
			(type default)
		)
		(layer "In1.Cu")
	)
	(gr_line
		(start 21.796756 -344.663776)
		(end 21.796756 -346.555822)
		(stroke
			(width 0.2)
			(type default)
		)
		(layer "In1.Cu")
	)
	(gr_line
		(start 21.796756 -336.155792)
		(end 21.79701 -336.156046)
		(stroke
			(width 0.2)
			(type default)
		)
		(layer "In1.Cu")
	)
	(gr_line
		(start 21.796756 -334.264)
		(end 21.796756 -336.155792)
		(stroke
			(width 0.2)
			(type default)
		)
		(layer "In1.Cu")
	)
	(gr_line
		(start 21.796756 -333.756)
		(end 21.79701 -333.756254)
		(stroke
			(width 0.2)
			(type default)
		)
		(layer "In1.Cu")
	)
	(gr_line
		(start 21.796756 -331.863954)
		(end 21.796756 -333.756)
		(stroke
			(width 0.2)
			(type default)
		)
		(layer "In1.Cu")
	)
	(gr_line
		(start 21.796756 -331.355954)
		(end 21.79701 -331.356208)
		(stroke
			(width 0.2)
			(type default)
		)
		(layer "In1.Cu")
	)
	(gr_line
		(start 21.796756 -329.463908)
		(end 21.796756 -331.355954)
		(stroke
			(width 0.2)
			(type default)
		)
		(layer "In1.Cu")
	)
	(gr_line
		(start 21.796756 -328.955908)
		(end 21.79701 -328.956162)
		(stroke
			(width 0.2)
			(type default)
		)
		(layer "In1.Cu")
	)
	(gr_line
		(start 21.796756 -327.063862)
		(end 21.796756 -328.955908)
		(stroke
			(width 0.2)
			(type default)
		)
		(layer "In1.Cu")
	)
	(gr_line
		(start 21.796756 -326.555862)
		(end 21.79701 -326.556116)
		(stroke
			(width 0.2)
			(type default)
		)
		(layer "In1.Cu")
	)
	(gr_line
		(start 21.796756 -324.663816)
		(end 21.796756 -326.555862)
		(stroke
			(width 0.2)
			(type default)
		)
		(layer "In1.Cu")
	)
	(gr_line
		(start 21.796756 -324.155816)
		(end 21.79701 -324.15607)
		(stroke
			(width 0.2)
			(type default)
		)
		(layer "In1.Cu")
	)
	(gr_line
		(start 21.796756 -322.264024)
		(end 21.796756 -324.155816)
		(stroke
			(width 0.2)
			(type default)
		)
		(layer "In1.Cu")
	)
	(gr_line
		(start 21.796756 -248.355866)
		(end 21.79701 -248.35612)
		(stroke
			(width 0.2)
			(type default)
		)
		(layer "In1.Cu")
	)
	(gr_line
		(start 21.796756 -246.46382)
		(end 21.796756 -248.355866)
		(stroke
			(width 0.2)
			(type default)
		)
		(layer "In1.Cu")
	)
	(gr_line
		(start 21.796756 -245.95582)
		(end 21.79701 -245.956074)
		(stroke
			(width 0.2)
			(type default)
		)
		(layer "In1.Cu")
	)
	(gr_line
		(start 21.796756 -244.063774)
		(end 21.796756 -245.95582)
		(stroke
			(width 0.2)
			(type default)
		)
		(layer "In1.Cu")
	)
	(gr_line
		(start 21.796756 -243.555774)
		(end 21.79701 -243.556028)
		(stroke
			(width 0.2)
			(type default)
		)
		(layer "In1.Cu")
	)
	(gr_line
		(start 21.796756 -241.663982)
		(end 21.796756 -243.555774)
		(stroke
			(width 0.2)
			(type default)
		)
		(layer "In1.Cu")
	)
	(gr_line
		(start 21.796756 -233.155744)
		(end 21.79701 -233.155998)
		(stroke
			(width 0.2)
			(type default)
		)
		(layer "In1.Cu")
	)
	(gr_line
		(start 21.796756 -231.263952)
		(end 21.796756 -233.155744)
		(stroke
			(width 0.2)
			(type default)
		)
		(layer "In1.Cu")
	)
	(gr_line
		(start 21.796756 -230.755952)
		(end 21.79701 -230.756206)
		(stroke
			(width 0.2)
			(type default)
		)
		(layer "In1.Cu")
	)
	(gr_line
		(start 21.796756 -228.863906)
		(end 21.796756 -230.755952)
		(stroke
			(width 0.2)
			(type default)
		)
		(layer "In1.Cu")
	)
	(gr_line
		(start 21.796756 -228.355906)
		(end 21.79701 -228.35616)
		(stroke
			(width 0.2)
			(type default)
		)
		(layer "In1.Cu")
	)
	(gr_line
		(start 21.796756 -226.46386)
		(end 21.796756 -228.355906)
		(stroke
			(width 0.2)
			(type default)
		)
		(layer "In1.Cu")
	)
	(gr_line
		(start 21.796756 -225.95586)
		(end 21.79701 -225.956114)
		(stroke
			(width 0.2)
			(type default)
		)
		(layer "In1.Cu")
	)
	(gr_line
		(start 21.796756 -224.063814)
		(end 21.796756 -225.95586)
		(stroke
			(width 0.2)
			(type default)
		)
		(layer "In1.Cu")
	)
	(gr_line
		(start 21.796756 -223.555814)
		(end 21.79701 -223.556068)
		(stroke
			(width 0.2)
			(type default)
		)
		(layer "In1.Cu")
	)
	(gr_line
		(start 21.796756 -221.663768)
		(end 21.796756 -223.555814)
		(stroke
			(width 0.2)
			(type default)
		)
		(layer "In1.Cu")
	)
	(gr_line
		(start 21.796756 -221.155768)
		(end 21.79701 -221.156022)
		(stroke
			(width 0.2)
			(type default)
		)
		(layer "In1.Cu")
	)
	(gr_line
		(start 21.796756 -219.263722)
		(end 21.796756 -221.155768)
		(stroke
			(width 0.2)
			(type default)
		)
		(layer "In1.Cu")
	)
	(gr_line
		(start 21.796756 -145.355818)
		(end 21.79701 -145.356072)
		(stroke
			(width 0.2)
			(type default)
		)
		(layer "In1.Cu")
	)
	(gr_line
		(start 21.796756 -143.463772)
		(end 21.796756 -145.355818)
		(stroke
			(width 0.2)
			(type default)
		)
		(layer "In1.Cu")
	)
	(gr_line
		(start 21.796756 -142.955772)
		(end 21.79701 -142.956026)
		(stroke
			(width 0.2)
			(type default)
		)
		(layer "In1.Cu")
	)
	(gr_line
		(start 21.796756 -141.063726)
		(end 21.796756 -142.955772)
		(stroke
			(width 0.2)
			(type default)
		)
		(layer "In1.Cu")
	)
	(gr_line
		(start 21.796756 -140.555726)
		(end 21.79701 -140.55598)
		(stroke
			(width 0.2)
			(type default)
		)
		(layer "In1.Cu")
	)
	(gr_line
		(start 21.796756 -138.66368)
		(end 21.796756 -140.555726)
		(stroke
			(width 0.2)
			(type default)
		)
		(layer "In1.Cu")
	)
	(gr_line
		(start 21.796756 -130.155696)
		(end 21.79701 -130.15595)
		(stroke
			(width 0.2)
			(type default)
		)
		(layer "In1.Cu")
	)
	(gr_line
		(start 21.796756 -128.263904)
		(end 21.796756 -130.155696)
		(stroke
			(width 0.2)
			(type default)
		)
		(layer "In1.Cu")
	)
	(gr_line
		(start 21.796756 -127.755904)
		(end 21.79701 -127.756158)
		(stroke
			(width 0.2)
			(type default)
		)
		(layer "In1.Cu")
	)
	(gr_line
		(start 21.796756 -125.863858)
		(end 21.796756 -127.755904)
		(stroke
			(width 0.2)
			(type default)
		)
		(layer "In1.Cu")
	)
	(gr_line
		(start 21.796756 -125.355858)
		(end 21.79701 -125.356112)
		(stroke
			(width 0.2)
			(type default)
		)
		(layer "In1.Cu")
	)
	(gr_line
		(start 21.796756 -123.463812)
		(end 21.796756 -125.355858)
		(stroke
			(width 0.2)
			(type default)
		)
		(layer "In1.Cu")
	)
	(gr_line
		(start 21.796756 -122.955812)
		(end 21.79701 -122.956066)
		(stroke
			(width 0.2)
			(type default)
		)
		(layer "In1.Cu")
	)
	(gr_line
		(start 21.796756 -121.063766)
		(end 21.796756 -122.955812)
		(stroke
			(width 0.2)
			(type default)
		)
		(layer "In1.Cu")
	)
	(gr_line
		(start 21.796756 -120.555766)
		(end 21.79701 -120.55602)
		(stroke
			(width 0.2)
			(type default)
		)
		(layer "In1.Cu")
	)
	(gr_line
		(start 21.796756 -118.66372)
		(end 21.796756 -120.555766)
		(stroke
			(width 0.2)
			(type default)
		)
		(layer "In1.Cu")
	)
	(gr_line
		(start 21.796756 -118.15572)
		(end 21.79701 -118.155974)
		(stroke
			(width 0.2)
			(type default)
		)
		(layer "In1.Cu")
	)
	(gr_line
		(start 21.796756 -116.263928)
		(end 21.796756 -118.15572)
		(stroke
			(width 0.2)
			(type default)
		)
		(layer "In1.Cu")
	)
	(gr_line
		(start 21.796756 -42.35577)
		(end 21.79701 -42.356024)
		(stroke
			(width 0.2)
			(type default)
		)
		(layer "In1.Cu")
	)
	(gr_line
		(start 21.796756 -40.463724)
		(end 21.796756 -42.35577)
		(stroke
			(width 0.2)
			(type default)
		)
		(layer "In1.Cu")
	)
	(gr_line
		(start 21.796756 -39.955724)
		(end 21.79701 -39.955978)
		(stroke
			(width 0.2)
			(type default)
		)
		(layer "In1.Cu")
	)
	(gr_line
		(start 21.796756 -38.063678)
		(end 21.796756 -39.955724)
		(stroke
			(width 0.2)
			(type default)
		)
		(layer "In1.Cu")
	)
	(gr_line
		(start 21.796756 -37.555678)
		(end 21.79701 -37.555932)
		(stroke
			(width 0.2)
			(type default)
		)
		(layer "In1.Cu")
	)
	(gr_line
		(start 21.796756 -35.663886)
		(end 21.796756 -37.555678)
		(stroke
			(width 0.2)
			(type default)
		)
		(layer "In1.Cu")
	)
	(gr_line
		(start 21.796756 -27.155648)
		(end 21.79701 -27.155902)
		(stroke
			(width 0.2)
			(type default)
		)
		(layer "In1.Cu")
	)
	(gr_line
		(start 21.796756 -25.263856)
		(end 21.796756 -27.155648)
		(stroke
			(width 0.2)
			(type default)
		)
		(layer "In1.Cu")
	)
	(gr_line
		(start 21.796756 -24.755856)
		(end 21.79701 -24.75611)
		(stroke
			(width 0.2)
			(type default)
		)
		(layer "In1.Cu")
	)
	(gr_line
		(start 21.796756 -22.86381)
		(end 21.796756 -24.755856)
		(stroke
			(width 0.2)
			(type default)
		)
		(layer "In1.Cu")
	)
	(gr_line
		(start 21.796756 -22.35581)
		(end 21.79701 -22.356064)
		(stroke
			(width 0.2)
			(type default)
		)
		(layer "In1.Cu")
	)
	(gr_line
		(start 21.796756 -20.463764)
		(end 21.796756 -22.35581)
		(stroke
			(width 0.2)
			(type default)
		)
		(layer "In1.Cu")
	)
	(gr_line
		(start 21.796756 -19.955764)
		(end 21.79701 -19.956018)
		(stroke
			(width 0.2)
			(type default)
		)
		(layer "In1.Cu")
	)
	(gr_line
		(start 21.796756 -18.063718)
		(end 21.796756 -19.955764)
		(stroke
			(width 0.2)
			(type default)
		)
		(layer "In1.Cu")
	)
	(gr_line
		(start 21.796756 -17.555718)
		(end 21.79701 -17.555972)
		(stroke
			(width 0.2)
			(type default)
		)
		(layer "In1.Cu")
	)
	(gr_line
		(start 21.796756 -15.663672)
		(end 21.796756 -17.555718)
		(stroke
			(width 0.2)
			(type default)
		)
		(layer "In1.Cu")
	)
	(gr_line
		(start 21.796756 -15.155672)
		(end 21.79701 -15.155926)
		(stroke
			(width 0.2)
			(type default)
		)
		(layer "In1.Cu")
	)
	(gr_line
		(start 21.796756 -13.26388)
		(end 21.796756 -15.155672)
		(stroke
			(width 0.2)
			(type default)
		)
		(layer "In1.Cu")
	)
	(gr_line
		(start 21.79701 -454.356216)
		(end 23.803356 -454.356216)
		(stroke
			(width 0.2)
			(type default)
		)
		(layer "In1.Cu")
	)
	(gr_line
		(start 21.79701 -451.95617)
		(end 23.803356 -451.95617)
		(stroke
			(width 0.2)
			(type default)
		)
		(layer "In1.Cu")
	)
	(gr_line
		(start 21.79701 -449.556124)
		(end 23.803356 -449.556124)
		(stroke
			(width 0.2)
			(type default)
		)
		(layer "In1.Cu")
	)
	(gr_line
		(start 21.79701 -439.156094)
		(end 23.803356 -439.156094)
		(stroke
			(width 0.2)
			(type default)
		)
		(layer "In1.Cu")
	)
	(gr_line
		(start 21.79701 -436.756302)
		(end 23.803356 -436.756302)
		(stroke
			(width 0.2)
			(type default)
		)
		(layer "In1.Cu")
	)
	(gr_line
		(start 21.79701 -434.356256)
		(end 23.803356 -434.356256)
		(stroke
			(width 0.2)
			(type default)
		)
		(layer "In1.Cu")
	)
	(gr_line
		(start 21.79701 -431.95621)
		(end 23.803356 -431.95621)
		(stroke
			(width 0.2)
			(type default)
		)
		(layer "In1.Cu")
	)
	(gr_line
		(start 21.79701 -429.556164)
		(end 23.803356 -429.556164)
		(stroke
			(width 0.2)
			(type default)
		)
		(layer "In1.Cu")
	)
	(gr_line
		(start 21.79701 -427.156118)
		(end 23.803356 -427.156118)
		(stroke
			(width 0.2)
			(type default)
		)
		(layer "In1.Cu")
	)
	(gr_line
		(start 21.79701 -351.356168)
		(end 23.803356 -351.356168)
		(stroke
			(width 0.2)
			(type default)
		)
		(layer "In1.Cu")
	)
	(gr_line
		(start 21.79701 -348.956122)
		(end 23.803356 -348.956122)
		(stroke
			(width 0.2)
			(type default)
		)
		(layer "In1.Cu")
	)
	(gr_line
		(start 21.79701 -346.556076)
		(end 23.803356 -346.556076)
		(stroke
			(width 0.2)
			(type default)
		)
		(layer "In1.Cu")
	)
	(gr_line
		(start 21.79701 -336.156046)
		(end 23.803356 -336.156046)
		(stroke
			(width 0.2)
			(type default)
		)
		(layer "In1.Cu")
	)
	(gr_line
		(start 21.79701 -333.756254)
		(end 23.803356 -333.756254)
		(stroke
			(width 0.2)
			(type default)
		)
		(layer "In1.Cu")
	)
	(gr_line
		(start 21.79701 -331.356208)
		(end 23.803356 -331.356208)
		(stroke
			(width 0.2)
			(type default)
		)
		(layer "In1.Cu")
	)
	(gr_line
		(start 21.79701 -328.956162)
		(end 23.803356 -328.956162)
		(stroke
			(width 0.2)
			(type default)
		)
		(layer "In1.Cu")
	)
	(gr_line
		(start 21.79701 -326.556116)
		(end 23.803356 -326.556116)
		(stroke
			(width 0.2)
			(type default)
		)
		(layer "In1.Cu")
	)
	(gr_line
		(start 21.79701 -324.15607)
		(end 23.803356 -324.15607)
		(stroke
			(width 0.2)
			(type default)
		)
		(layer "In1.Cu")
	)
	(gr_line
		(start 21.79701 -248.35612)
		(end 23.803356 -248.35612)
		(stroke
			(width 0.2)
			(type default)
		)
		(layer "In1.Cu")
	)
	(gr_line
		(start 21.79701 -245.956074)
		(end 23.803356 -245.956074)
		(stroke
			(width 0.2)
			(type default)
		)
		(layer "In1.Cu")
	)
	(gr_line
		(start 21.79701 -243.556028)
		(end 23.803356 -243.556028)
		(stroke
			(width 0.2)
			(type default)
		)
		(layer "In1.Cu")
	)
	(gr_line
		(start 21.79701 -233.155998)
		(end 23.803356 -233.155998)
		(stroke
			(width 0.2)
			(type default)
		)
		(layer "In1.Cu")
	)
	(gr_line
		(start 21.79701 -230.756206)
		(end 23.803356 -230.756206)
		(stroke
			(width 0.2)
			(type default)
		)
		(layer "In1.Cu")
	)
	(gr_line
		(start 21.79701 -228.35616)
		(end 23.803356 -228.35616)
		(stroke
			(width 0.2)
			(type default)
		)
		(layer "In1.Cu")
	)
	(gr_line
		(start 21.79701 -225.956114)
		(end 23.803356 -225.956114)
		(stroke
			(width 0.2)
			(type default)
		)
		(layer "In1.Cu")
	)
	(gr_line
		(start 21.79701 -223.556068)
		(end 23.803356 -223.556068)
		(stroke
			(width 0.2)
			(type default)
		)
		(layer "In1.Cu")
	)
	(gr_line
		(start 21.79701 -221.156022)
		(end 23.803356 -221.156022)
		(stroke
			(width 0.2)
			(type default)
		)
		(layer "In1.Cu")
	)
	(gr_line
		(start 21.79701 -145.356072)
		(end 23.803356 -145.356072)
		(stroke
			(width 0.2)
			(type default)
		)
		(layer "In1.Cu")
	)
	(gr_line
		(start 21.79701 -142.956026)
		(end 23.803356 -142.956026)
		(stroke
			(width 0.2)
			(type default)
		)
		(layer "In1.Cu")
	)
	(gr_line
		(start 21.79701 -140.55598)
		(end 23.803356 -140.55598)
		(stroke
			(width 0.2)
			(type default)
		)
		(layer "In1.Cu")
	)
	(gr_line
		(start 21.79701 -130.15595)
		(end 23.803356 -130.15595)
		(stroke
			(width 0.2)
			(type default)
		)
		(layer "In1.Cu")
	)
	(gr_line
		(start 21.79701 -127.756158)
		(end 23.803356 -127.756158)
		(stroke
			(width 0.2)
			(type default)
		)
		(layer "In1.Cu")
	)
	(gr_line
		(start 21.79701 -125.356112)
		(end 23.803356 -125.356112)
		(stroke
			(width 0.2)
			(type default)
		)
		(layer "In1.Cu")
	)
	(gr_line
		(start 21.79701 -122.956066)
		(end 23.803356 -122.956066)
		(stroke
			(width 0.2)
			(type default)
		)
		(layer "In1.Cu")
	)
	(gr_line
		(start 21.79701 -120.55602)
		(end 23.803356 -120.55602)
		(stroke
			(width 0.2)
			(type default)
		)
		(layer "In1.Cu")
	)
	(gr_line
		(start 21.79701 -118.155974)
		(end 23.803356 -118.155974)
		(stroke
			(width 0.2)
			(type default)
		)
		(layer "In1.Cu")
	)
	(gr_line
		(start 21.79701 -42.356024)
		(end 23.803356 -42.356024)
		(stroke
			(width 0.2)
			(type default)
		)
		(layer "In1.Cu")
	)
	(gr_line
		(start 21.79701 -39.955978)
		(end 23.803356 -39.955978)
		(stroke
			(width 0.2)
			(type default)
		)
		(layer "In1.Cu")
	)
	(gr_line
		(start 21.79701 -37.555932)
		(end 23.803356 -37.555932)
		(stroke
			(width 0.2)
			(type default)
		)
		(layer "In1.Cu")
	)
	(gr_line
		(start 21.79701 -27.155902)
		(end 23.803356 -27.155902)
		(stroke
			(width 0.2)
			(type default)
		)
		(layer "In1.Cu")
	)
	(gr_line
		(start 21.79701 -24.75611)
		(end 23.803356 -24.75611)
		(stroke
			(width 0.2)
			(type default)
		)
		(layer "In1.Cu")
	)
	(gr_line
		(start 21.79701 -22.356064)
		(end 23.803356 -22.356064)
		(stroke
			(width 0.2)
			(type default)
		)
		(layer "In1.Cu")
	)
	(gr_line
		(start 21.79701 -19.956018)
		(end 23.803356 -19.956018)
		(stroke
			(width 0.2)
			(type default)
		)
		(layer "In1.Cu")
	)
	(gr_line
		(start 21.79701 -17.555972)
		(end 23.803356 -17.555972)
		(stroke
			(width 0.2)
			(type default)
		)
		(layer "In1.Cu")
	)
	(gr_line
		(start 21.79701 -15.155926)
		(end 23.803356 -15.155926)
		(stroke
			(width 0.2)
			(type default)
		)
		(layer "In1.Cu")
	)
	(gr_line
		(start 23.803356 -454.356216)
		(end 23.803356 -452.463916)
		(stroke
			(width 0.2)
			(type default)
		)
		(layer "In1.Cu")
	)
	(gr_line
		(start 23.803356 -452.463916)
		(end 21.796756 -452.463916)
		(stroke
			(width 0.2)
			(type default)
		)
		(layer "In1.Cu")
	)
	(gr_line
		(start 23.803356 -451.95617)
		(end 23.803356 -450.06387)
		(stroke
			(width 0.2)
			(type default)
		)
		(layer "In1.Cu")
	)
	(gr_line
		(start 23.803356 -450.06387)
		(end 21.796756 -450.06387)
		(stroke
			(width 0.2)
			(type default)
		)
		(layer "In1.Cu")
	)
	(gr_line
		(start 23.803356 -449.556124)
		(end 23.803356 -447.664078)
		(stroke
			(width 0.2)
			(type default)
		)
		(layer "In1.Cu")
	)
	(gr_line
		(start 23.803356 -447.664078)
		(end 21.796756 -447.664078)
		(stroke
			(width 0.2)
			(type default)
		)
		(layer "In1.Cu")
	)
	(gr_line
		(start 23.803356 -439.156094)
		(end 23.803356 -437.264048)
		(stroke
			(width 0.2)
			(type default)
		)
		(layer "In1.Cu")
	)
	(gr_line
		(start 23.803356 -437.264048)
		(end 21.796756 -437.264048)
		(stroke
			(width 0.2)
			(type default)
		)
		(layer "In1.Cu")
	)
	(gr_line
		(start 23.803356 -436.756302)
		(end 23.803356 -434.864002)
		(stroke
			(width 0.2)
			(type default)
		)
		(layer "In1.Cu")
	)
	(gr_line
		(start 23.803356 -434.864002)
		(end 21.796756 -434.864002)
		(stroke
			(width 0.2)
			(type default)
		)
		(layer "In1.Cu")
	)
	(gr_line
		(start 23.803356 -434.356256)
		(end 23.803356 -432.463956)
		(stroke
			(width 0.2)
			(type default)
		)
		(layer "In1.Cu")
	)
	(gr_line
		(start 23.803356 -432.463956)
		(end 21.796756 -432.463956)
		(stroke
			(width 0.2)
			(type default)
		)
		(layer "In1.Cu")
	)
	(gr_line
		(start 23.803356 -431.95621)
		(end 23.803356 -430.06391)
		(stroke
			(width 0.2)
			(type default)
		)
		(layer "In1.Cu")
	)
	(gr_line
		(start 23.803356 -430.06391)
		(end 21.796756 -430.06391)
		(stroke
			(width 0.2)
			(type default)
		)
		(layer "In1.Cu")
	)
	(gr_line
		(start 23.803356 -429.556164)
		(end 23.803356 -427.663864)
		(stroke
			(width 0.2)
			(type default)
		)
		(layer "In1.Cu")
	)
	(gr_line
		(start 23.803356 -427.663864)
		(end 21.796756 -427.663864)
		(stroke
			(width 0.2)
			(type default)
		)
		(layer "In1.Cu")
	)
	(gr_line
		(start 23.803356 -427.156118)
		(end 23.803356 -425.263818)
		(stroke
			(width 0.2)
			(type default)
		)
		(layer "In1.Cu")
	)
	(gr_line
		(start 23.803356 -425.263818)
		(end 21.796756 -425.263818)
		(stroke
			(width 0.2)
			(type default)
		)
		(layer "In1.Cu")
	)
	(gr_line
		(start 23.803356 -351.356168)
		(end 23.803356 -349.463868)
		(stroke
			(width 0.2)
			(type default)
		)
		(layer "In1.Cu")
	)
	(gr_line
		(start 23.803356 -349.463868)
		(end 21.796756 -349.463868)
		(stroke
			(width 0.2)
			(type default)
		)
		(layer "In1.Cu")
	)
	(gr_line
		(start 23.803356 -348.956122)
		(end 23.803356 -347.063822)
		(stroke
			(width 0.2)
			(type default)
		)
		(layer "In1.Cu")
	)
	(gr_line
		(start 23.803356 -347.063822)
		(end 21.796756 -347.063822)
		(stroke
			(width 0.2)
			(type default)
		)
		(layer "In1.Cu")
	)
	(gr_line
		(start 23.803356 -346.556076)
		(end 23.803356 -344.663776)
		(stroke
			(width 0.2)
			(type default)
		)
		(layer "In1.Cu")
	)
	(gr_line
		(start 23.803356 -344.663776)
		(end 21.796756 -344.663776)
		(stroke
			(width 0.2)
			(type default)
		)
		(layer "In1.Cu")
	)
	(gr_line
		(start 23.803356 -336.156046)
		(end 23.803356 -334.264)
		(stroke
			(width 0.2)
			(type default)
		)
		(layer "In1.Cu")
	)
	(gr_line
		(start 23.803356 -334.264)
		(end 21.796756 -334.264)
		(stroke
			(width 0.2)
			(type default)
		)
		(layer "In1.Cu")
	)
	(gr_line
		(start 23.803356 -333.756254)
		(end 23.803356 -331.863954)
		(stroke
			(width 0.2)
			(type default)
		)
		(layer "In1.Cu")
	)
	(gr_line
		(start 23.803356 -331.863954)
		(end 21.796756 -331.863954)
		(stroke
			(width 0.2)
			(type default)
		)
		(layer "In1.Cu")
	)
	(gr_line
		(start 23.803356 -331.356208)
		(end 23.803356 -329.463908)
		(stroke
			(width 0.2)
			(type default)
		)
		(layer "In1.Cu")
	)
	(gr_line
		(start 23.803356 -329.463908)
		(end 21.796756 -329.463908)
		(stroke
			(width 0.2)
			(type default)
		)
		(layer "In1.Cu")
	)
	(gr_line
		(start 23.803356 -328.956162)
		(end 23.803356 -327.063862)
		(stroke
			(width 0.2)
			(type default)
		)
		(layer "In1.Cu")
	)
	(gr_line
		(start 23.803356 -327.063862)
		(end 21.796756 -327.063862)
		(stroke
			(width 0.2)
			(type default)
		)
		(layer "In1.Cu")
	)
	(gr_line
		(start 23.803356 -326.556116)
		(end 23.803356 -324.663816)
		(stroke
			(width 0.2)
			(type default)
		)
		(layer "In1.Cu")
	)
	(gr_line
		(start 23.803356 -324.663816)
		(end 21.796756 -324.663816)
		(stroke
			(width 0.2)
			(type default)
		)
		(layer "In1.Cu")
	)
	(gr_line
		(start 23.803356 -324.15607)
		(end 23.803356 -322.264024)
		(stroke
			(width 0.2)
			(type default)
		)
		(layer "In1.Cu")
	)
	(gr_line
		(start 23.803356 -322.264024)
		(end 21.796756 -322.264024)
		(stroke
			(width 0.2)
			(type default)
		)
		(layer "In1.Cu")
	)
	(gr_line
		(start 23.803356 -248.35612)
		(end 23.803356 -246.46382)
		(stroke
			(width 0.2)
			(type default)
		)
		(layer "In1.Cu")
	)
	(gr_line
		(start 23.803356 -246.46382)
		(end 21.796756 -246.46382)
		(stroke
			(width 0.2)
			(type default)
		)
		(layer "In1.Cu")
	)
	(gr_line
		(start 23.803356 -245.956074)
		(end 23.803356 -244.063774)
		(stroke
			(width 0.2)
			(type default)
		)
		(layer "In1.Cu")
	)
	(gr_line
		(start 23.803356 -244.063774)
		(end 21.796756 -244.063774)
		(stroke
			(width 0.2)
			(type default)
		)
		(layer "In1.Cu")
	)
	(gr_line
		(start 23.803356 -243.556028)
		(end 23.803356 -241.663982)
		(stroke
			(width 0.2)
			(type default)
		)
		(layer "In1.Cu")
	)
	(gr_line
		(start 23.803356 -241.663982)
		(end 21.796756 -241.663982)
		(stroke
			(width 0.2)
			(type default)
		)
		(layer "In1.Cu")
	)
	(gr_line
		(start 23.803356 -233.155998)
		(end 23.803356 -231.263952)
		(stroke
			(width 0.2)
			(type default)
		)
		(layer "In1.Cu")
	)
	(gr_line
		(start 23.803356 -231.263952)
		(end 21.796756 -231.263952)
		(stroke
			(width 0.2)
			(type default)
		)
		(layer "In1.Cu")
	)
	(gr_line
		(start 23.803356 -230.756206)
		(end 23.803356 -228.863906)
		(stroke
			(width 0.2)
			(type default)
		)
		(layer "In1.Cu")
	)
	(gr_line
		(start 23.803356 -228.863906)
		(end 21.796756 -228.863906)
		(stroke
			(width 0.2)
			(type default)
		)
		(layer "In1.Cu")
	)
	(gr_line
		(start 23.803356 -228.35616)
		(end 23.803356 -226.46386)
		(stroke
			(width 0.2)
			(type default)
		)
		(layer "In1.Cu")
	)
	(gr_line
		(start 23.803356 -226.46386)
		(end 21.796756 -226.46386)
		(stroke
			(width 0.2)
			(type default)
		)
		(layer "In1.Cu")
	)
	(gr_line
		(start 23.803356 -225.956114)
		(end 23.803356 -224.063814)
		(stroke
			(width 0.2)
			(type default)
		)
		(layer "In1.Cu")
	)
	(gr_line
		(start 23.803356 -224.063814)
		(end 21.796756 -224.063814)
		(stroke
			(width 0.2)
			(type default)
		)
		(layer "In1.Cu")
	)
	(gr_line
		(start 23.803356 -223.556068)
		(end 23.803356 -221.663768)
		(stroke
			(width 0.2)
			(type default)
		)
		(layer "In1.Cu")
	)
	(gr_line
		(start 23.803356 -221.663768)
		(end 21.796756 -221.663768)
		(stroke
			(width 0.2)
			(type default)
		)
		(layer "In1.Cu")
	)
	(gr_line
		(start 23.803356 -221.156022)
		(end 23.803356 -219.263722)
		(stroke
			(width 0.2)
			(type default)
		)
		(layer "In1.Cu")
	)
	(gr_line
		(start 23.803356 -219.263722)
		(end 21.796756 -219.263722)
		(stroke
			(width 0.2)
			(type default)
		)
		(layer "In1.Cu")
	)
	(gr_line
		(start 23.803356 -145.356072)
		(end 23.803356 -143.463772)
		(stroke
			(width 0.2)
			(type default)
		)
		(layer "In1.Cu")
	)
	(gr_line
		(start 23.803356 -143.463772)
		(end 21.796756 -143.463772)
		(stroke
			(width 0.2)
			(type default)
		)
		(layer "In1.Cu")
	)
	(gr_line
		(start 23.803356 -142.956026)
		(end 23.803356 -141.063726)
		(stroke
			(width 0.2)
			(type default)
		)
		(layer "In1.Cu")
	)
	(gr_line
		(start 23.803356 -141.063726)
		(end 21.796756 -141.063726)
		(stroke
			(width 0.2)
			(type default)
		)
		(layer "In1.Cu")
	)
	(gr_line
		(start 23.803356 -140.55598)
		(end 23.803356 -138.66368)
		(stroke
			(width 0.2)
			(type default)
		)
		(layer "In1.Cu")
	)
	(gr_line
		(start 23.803356 -138.66368)
		(end 21.796756 -138.66368)
		(stroke
			(width 0.2)
			(type default)
		)
		(layer "In1.Cu")
	)
	(gr_line
		(start 23.803356 -130.15595)
		(end 23.803356 -128.263904)
		(stroke
			(width 0.2)
			(type default)
		)
		(layer "In1.Cu")
	)
	(gr_line
		(start 23.803356 -128.263904)
		(end 21.796756 -128.263904)
		(stroke
			(width 0.2)
			(type default)
		)
		(layer "In1.Cu")
	)
	(gr_line
		(start 23.803356 -127.756158)
		(end 23.803356 -125.863858)
		(stroke
			(width 0.2)
			(type default)
		)
		(layer "In1.Cu")
	)
	(gr_line
		(start 23.803356 -125.863858)
		(end 21.796756 -125.863858)
		(stroke
			(width 0.2)
			(type default)
		)
		(layer "In1.Cu")
	)
	(gr_line
		(start 23.803356 -125.356112)
		(end 23.803356 -123.463812)
		(stroke
			(width 0.2)
			(type default)
		)
		(layer "In1.Cu")
	)
	(gr_line
		(start 23.803356 -123.463812)
		(end 21.796756 -123.463812)
		(stroke
			(width 0.2)
			(type default)
		)
		(layer "In1.Cu")
	)
	(gr_line
		(start 23.803356 -122.956066)
		(end 23.803356 -121.063766)
		(stroke
			(width 0.2)
			(type default)
		)
		(layer "In1.Cu")
	)
	(gr_line
		(start 23.803356 -121.063766)
		(end 21.796756 -121.063766)
		(stroke
			(width 0.2)
			(type default)
		)
		(layer "In1.Cu")
	)
	(gr_line
		(start 23.803356 -120.55602)
		(end 23.803356 -118.66372)
		(stroke
			(width 0.2)
			(type default)
		)
		(layer "In1.Cu")
	)
	(gr_line
		(start 23.803356 -118.66372)
		(end 21.796756 -118.66372)
		(stroke
			(width 0.2)
			(type default)
		)
		(layer "In1.Cu")
	)
	(gr_line
		(start 23.803356 -118.155974)
		(end 23.803356 -116.263928)
		(stroke
			(width 0.2)
			(type default)
		)
		(layer "In1.Cu")
	)
	(gr_line
		(start 23.803356 -116.263928)
		(end 21.796756 -116.263928)
		(stroke
			(width 0.2)
			(type default)
		)
		(layer "In1.Cu")
	)
	(gr_line
		(start 23.803356 -42.356024)
		(end 23.803356 -40.463724)
		(stroke
			(width 0.2)
			(type default)
		)
		(layer "In1.Cu")
	)
	(gr_line
		(start 23.803356 -40.463724)
		(end 21.796756 -40.463724)
		(stroke
			(width 0.2)
			(type default)
		)
		(layer "In1.Cu")
	)
	(gr_line
		(start 23.803356 -39.955978)
		(end 23.803356 -38.063678)
		(stroke
			(width 0.2)
			(type default)
		)
		(layer "In1.Cu")
	)
	(gr_line
		(start 23.803356 -38.063678)
		(end 21.796756 -38.063678)
		(stroke
			(width 0.2)
			(type default)
		)
		(layer "In1.Cu")
	)
	(gr_line
		(start 23.803356 -37.555932)
		(end 23.803356 -35.663886)
		(stroke
			(width 0.2)
			(type default)
		)
		(layer "In1.Cu")
	)
	(gr_line
		(start 23.803356 -35.663886)
		(end 21.796756 -35.663886)
		(stroke
			(width 0.2)
			(type default)
		)
		(layer "In1.Cu")
	)
	(gr_line
		(start 23.803356 -27.155902)
		(end 23.803356 -25.263856)
		(stroke
			(width 0.2)
			(type default)
		)
		(layer "In1.Cu")
	)
	(gr_line
		(start 23.803356 -25.263856)
		(end 21.796756 -25.263856)
		(stroke
			(width 0.2)
			(type default)
		)
		(layer "In1.Cu")
	)
	(gr_line
		(start 23.803356 -24.75611)
		(end 23.803356 -22.86381)
		(stroke
			(width 0.2)
			(type default)
		)
		(layer "In1.Cu")
	)
	(gr_line
		(start 23.803356 -22.86381)
		(end 21.796756 -22.86381)
		(stroke
			(width 0.2)
			(type default)
		)
		(layer "In1.Cu")
	)
	(gr_line
		(start 23.803356 -22.356064)
		(end 23.803356 -20.463764)
		(stroke
			(width 0.2)
			(type default)
		)
		(layer "In1.Cu")
	)
	(gr_line
		(start 23.803356 -20.463764)
		(end 21.796756 -20.463764)
		(stroke
			(width 0.2)
			(type default)
		)
		(layer "In1.Cu")
	)
	(gr_line
		(start 23.803356 -19.956018)
		(end 23.803356 -18.063718)
		(stroke
			(width 0.2)
			(type default)
		)
		(layer "In1.Cu")
	)
	(gr_line
		(start 23.803356 -18.063718)
		(end 21.796756 -18.063718)
		(stroke
			(width 0.2)
			(type default)
		)
		(layer "In1.Cu")
	)
	(gr_line
		(start 23.803356 -17.555972)
		(end 23.803356 -15.663672)
		(stroke
			(width 0.2)
			(type default)
		)
		(layer "In1.Cu")
	)
	(gr_line
		(start 23.803356 -15.663672)
		(end 21.796756 -15.663672)
		(stroke
			(width 0.2)
			(type default)
		)
		(layer "In1.Cu")
	)
	(gr_line
		(start 23.803356 -15.155926)
		(end 23.803356 -13.26388)
		(stroke
			(width 0.2)
			(type default)
		)
		(layer "In1.Cu")
	)
	(gr_line
		(start 23.803356 -13.26388)
		(end 21.796756 -13.26388)
		(stroke
			(width 0.2)
			(type default)
		)
		(layer "In1.Cu")
	)
	(gr_arc
		(start 24.66086 -449.168774)
		(mid 25.273 -449.780914)
		(end 25.88514 -449.168774)
		(stroke
			(width 0.2)
			(type default)
		)
		(layer "In1.Cu")
	)
	(gr_line
		(start 24.66086 -448.051174)
		(end 24.66086 -449.168774)
		(stroke
			(width 0.2)
			(type default)
		)
		(layer "In1.Cu")
	)
	(gr_arc
		(start 24.66086 -436.368952)
		(mid 25.273 -436.981092)
		(end 25.88514 -436.368952)
		(stroke
			(width 0.2)
			(type default)
		)
		(layer "In1.Cu")
	)
	(gr_line
		(start 24.66086 -435.251352)
		(end 24.66086 -436.368952)
		(stroke
			(width 0.2)
			(type default)
		)
		(layer "In1.Cu")
	)
	(gr_arc
		(start 24.66086 -431.56886)
		(mid 25.273 -432.181)
		(end 25.88514 -431.56886)
		(stroke
			(width 0.2)
			(type default)
		)
		(layer "In1.Cu")
	)
	(gr_line
		(start 24.66086 -430.45126)
		(end 24.66086 -431.56886)
		(stroke
			(width 0.2)
			(type default)
		)
		(layer "In1.Cu")
	)
	(gr_arc
		(start 24.66086 -426.768768)
		(mid 25.273 -427.380908)
		(end 25.88514 -426.768768)
		(stroke
			(width 0.2)
			(type default)
		)
		(layer "In1.Cu")
	)
	(gr_line
		(start 24.66086 -425.651168)
		(end 24.66086 -426.768768)
		(stroke
			(width 0.2)
			(type default)
		)
		(layer "In1.Cu")
	)
	(gr_arc
		(start 24.66086 -346.168726)
		(mid 25.273 -346.780866)
		(end 25.88514 -346.168726)
		(stroke
			(width 0.2)
			(type default)
		)
		(layer "In1.Cu")
	)
	(gr_line
		(start 24.66086 -345.051126)
		(end 24.66086 -346.168726)
		(stroke
			(width 0.2)
			(type default)
		)
		(layer "In1.Cu")
	)
	(gr_arc
		(start 24.66086 -333.36865)
		(mid 25.272873 -333.981044)
		(end 25.88514 -333.368904)
		(stroke
			(width 0.2)
			(type default)
		)
		(layer "In1.Cu")
	)
	(gr_line
		(start 24.66086 -332.251304)
		(end 24.66086 -333.36865)
		(stroke
			(width 0.2)
			(type default)
		)
		(layer "In1.Cu")
	)
	(gr_arc
		(start 24.66086 -328.568558)
		(mid 25.272873 -329.180952)
		(end 25.88514 -328.568812)
		(stroke
			(width 0.2)
			(type default)
		)
		(layer "In1.Cu")
	)
	(gr_line
		(start 24.66086 -327.451212)
		(end 24.66086 -328.568558)
		(stroke
			(width 0.2)
			(type default)
		)
		(layer "In1.Cu")
	)
	(gr_arc
		(start 24.66086 -323.768466)
		(mid 25.272873 -324.38086)
		(end 25.88514 -323.76872)
		(stroke
			(width 0.2)
			(type default)
		)
		(layer "In1.Cu")
	)
	(gr_line
		(start 24.66086 -322.65112)
		(end 24.66086 -323.768466)
		(stroke
			(width 0.2)
			(type default)
		)
		(layer "In1.Cu")
	)
	(gr_arc
		(start 24.66086 -243.168424)
		(mid 25.272873 -243.780818)
		(end 25.88514 -243.168678)
		(stroke
			(width 0.2)
			(type default)
		)
		(layer "In1.Cu")
	)
	(gr_line
		(start 24.66086 -242.051078)
		(end 24.66086 -243.168424)
		(stroke
			(width 0.2)
			(type default)
		)
		(layer "In1.Cu")
	)
	(gr_arc
		(start 24.66086 -230.368602)
		(mid 25.272873 -230.980996)
		(end 25.88514 -230.368856)
		(stroke
			(width 0.2)
			(type default)
		)
		(layer "In1.Cu")
	)
	(gr_line
		(start 24.66086 -229.251256)
		(end 24.66086 -230.368602)
		(stroke
			(width 0.2)
			(type default)
		)
		(layer "In1.Cu")
	)
	(gr_arc
		(start 24.66086 -225.56851)
		(mid 25.272873 -226.180904)
		(end 25.88514 -225.568764)
		(stroke
			(width 0.2)
			(type default)
		)
		(layer "In1.Cu")
	)
	(gr_line
		(start 24.66086 -224.451164)
		(end 24.66086 -225.56851)
		(stroke
			(width 0.2)
			(type default)
		)
		(layer "In1.Cu")
	)
	(gr_arc
		(start 24.66086 -220.768672)
		(mid 25.273 -221.380812)
		(end 25.88514 -220.768672)
		(stroke
			(width 0.2)
			(type default)
		)
		(layer "In1.Cu")
	)
	(gr_line
		(start 24.66086 -219.651072)
		(end 24.66086 -220.768672)
		(stroke
			(width 0.2)
			(type default)
		)
		(layer "In1.Cu")
	)
	(gr_arc
		(start 24.66086 -140.16863)
		(mid 25.273 -140.78077)
		(end 25.88514 -140.16863)
		(stroke
			(width 0.2)
			(type default)
		)
		(layer "In1.Cu")
	)
	(gr_line
		(start 24.66086 -139.05103)
		(end 24.66086 -140.16863)
		(stroke
			(width 0.2)
			(type default)
		)
		(layer "In1.Cu")
	)
	(gr_arc
		(start 24.66086 -127.368554)
		(mid 25.272873 -127.980948)
		(end 25.88514 -127.368808)
		(stroke
			(width 0.2)
			(type default)
		)
		(layer "In1.Cu")
	)
	(gr_line
		(start 24.66086 -126.251208)
		(end 24.66086 -127.368554)
		(stroke
			(width 0.2)
			(type default)
		)
		(layer "In1.Cu")
	)
	(gr_arc
		(start 24.66086 -122.568462)
		(mid 25.272873 -123.180856)
		(end 25.88514 -122.568716)
		(stroke
			(width 0.2)
			(type default)
		)
		(layer "In1.Cu")
	)
	(gr_line
		(start 24.66086 -121.451116)
		(end 24.66086 -122.568462)
		(stroke
			(width 0.2)
			(type default)
		)
		(layer "In1.Cu")
	)
	(gr_arc
		(start 24.66086 -117.768624)
		(mid 25.273 -118.380764)
		(end 25.88514 -117.768624)
		(stroke
			(width 0.2)
			(type default)
		)
		(layer "In1.Cu")
	)
	(gr_line
		(start 24.66086 -116.651024)
		(end 24.66086 -117.768624)
		(stroke
			(width 0.2)
			(type default)
		)
		(layer "In1.Cu")
	)
	(gr_arc
		(start 24.66086 -37.168328)
		(mid 25.272873 -37.780722)
		(end 25.88514 -37.168582)
		(stroke
			(width 0.2)
			(type default)
		)
		(layer "In1.Cu")
	)
	(gr_line
		(start 24.66086 -36.050982)
		(end 24.66086 -37.168328)
		(stroke
			(width 0.2)
			(type default)
		)
		(layer "In1.Cu")
	)
	(gr_arc
		(start 24.66086 -24.368506)
		(mid 25.272873 -24.9809)
		(end 25.88514 -24.36876)
		(stroke
			(width 0.2)
			(type default)
		)
		(layer "In1.Cu")
	)
	(gr_line
		(start 24.66086 -23.25116)
		(end 24.66086 -24.368506)
		(stroke
			(width 0.2)
			(type default)
		)
		(layer "In1.Cu")
	)
	(gr_arc
		(start 24.66086 -19.568414)
		(mid 25.272873 -20.180808)
		(end 25.88514 -19.568668)
		(stroke
			(width 0.2)
			(type default)
		)
		(layer "In1.Cu")
	)
	(gr_line
		(start 24.66086 -18.451068)
		(end 24.66086 -19.568414)
		(stroke
			(width 0.2)
			(type default)
		)
		(layer "In1.Cu")
	)
	(gr_arc
		(start 24.66086 -14.793976)
		(mid 25.273 -15.406116)
		(end 25.88514 -14.793976)
		(stroke
			(width 0.2)
			(type default)
		)
		(layer "In1.Cu")
	)
	(gr_line
		(start 24.66086 -13.676376)
		(end 24.66086 -14.793976)
		(stroke
			(width 0.2)
			(type default)
		)
		(layer "In1.Cu")
	)
	(gr_line
		(start 25.88514 -449.168774)
		(end 25.88514 -448.051428)
		(stroke
			(width 0.2)
			(type default)
		)
		(layer "In1.Cu")
	)
	(gr_arc
		(start 25.88514 -448.051428)
		(mid 25.273127 -447.439034)
		(end 24.66086 -448.051174)
		(stroke
			(width 0.2)
			(type default)
		)
		(layer "In1.Cu")
	)
	(gr_line
		(start 25.88514 -436.368952)
		(end 25.88514 -435.251606)
		(stroke
			(width 0.2)
			(type default)
		)
		(layer "In1.Cu")
	)
	(gr_arc
		(start 25.88514 -435.251606)
		(mid 25.273127 -434.639212)
		(end 24.66086 -435.251352)
		(stroke
			(width 0.2)
			(type default)
		)
		(layer "In1.Cu")
	)
	(gr_line
		(start 25.88514 -431.56886)
		(end 25.88514 -430.451514)
		(stroke
			(width 0.2)
			(type default)
		)
		(layer "In1.Cu")
	)
	(gr_arc
		(start 25.88514 -430.451514)
		(mid 25.273127 -429.83912)
		(end 24.66086 -430.45126)
		(stroke
			(width 0.2)
			(type default)
		)
		(layer "In1.Cu")
	)
	(gr_line
		(start 25.88514 -426.768768)
		(end 25.88514 -425.651422)
		(stroke
			(width 0.2)
			(type default)
		)
		(layer "In1.Cu")
	)
	(gr_arc
		(start 25.88514 -425.651422)
		(mid 25.273127 -425.039028)
		(end 24.66086 -425.651168)
		(stroke
			(width 0.2)
			(type default)
		)
		(layer "In1.Cu")
	)
	(gr_line
		(start 25.88514 -346.168726)
		(end 25.88514 -345.05138)
		(stroke
			(width 0.2)
			(type default)
		)
		(layer "In1.Cu")
	)
	(gr_arc
		(start 25.88514 -345.05138)
		(mid 25.273127 -344.438986)
		(end 24.66086 -345.051126)
		(stroke
			(width 0.2)
			(type default)
		)
		(layer "In1.Cu")
	)
	(gr_line
		(start 25.88514 -333.368904)
		(end 25.88514 -332.251304)
		(stroke
			(width 0.2)
			(type default)
		)
		(layer "In1.Cu")
	)
	(gr_arc
		(start 25.88514 -332.251304)
		(mid 25.273 -331.639164)
		(end 24.66086 -332.251304)
		(stroke
			(width 0.2)
			(type default)
		)
		(layer "In1.Cu")
	)
	(gr_line
		(start 25.88514 -328.568812)
		(end 25.88514 -327.451212)
		(stroke
			(width 0.2)
			(type default)
		)
		(layer "In1.Cu")
	)
	(gr_arc
		(start 25.88514 -327.451212)
		(mid 25.273 -326.839072)
		(end 24.66086 -327.451212)
		(stroke
			(width 0.2)
			(type default)
		)
		(layer "In1.Cu")
	)
	(gr_line
		(start 25.88514 -323.76872)
		(end 25.88514 -322.65112)
		(stroke
			(width 0.2)
			(type default)
		)
		(layer "In1.Cu")
	)
	(gr_arc
		(start 25.88514 -322.65112)
		(mid 25.273 -322.03898)
		(end 24.66086 -322.65112)
		(stroke
			(width 0.2)
			(type default)
		)
		(layer "In1.Cu")
	)
	(gr_line
		(start 25.88514 -243.168678)
		(end 25.88514 -242.051078)
		(stroke
			(width 0.2)
			(type default)
		)
		(layer "In1.Cu")
	)
	(gr_arc
		(start 25.88514 -242.051078)
		(mid 25.273 -241.438938)
		(end 24.66086 -242.051078)
		(stroke
			(width 0.2)
			(type default)
		)
		(layer "In1.Cu")
	)
	(gr_line
		(start 25.88514 -230.368856)
		(end 25.88514 -229.251256)
		(stroke
			(width 0.2)
			(type default)
		)
		(layer "In1.Cu")
	)
	(gr_arc
		(start 25.88514 -229.251256)
		(mid 25.273 -228.639116)
		(end 24.66086 -229.251256)
		(stroke
			(width 0.2)
			(type default)
		)
		(layer "In1.Cu")
	)
	(gr_line
		(start 25.88514 -225.568764)
		(end 25.88514 -224.451164)
		(stroke
			(width 0.2)
			(type default)
		)
		(layer "In1.Cu")
	)
	(gr_arc
		(start 25.88514 -224.451164)
		(mid 25.273 -223.839024)
		(end 24.66086 -224.451164)
		(stroke
			(width 0.2)
			(type default)
		)
		(layer "In1.Cu")
	)
	(gr_line
		(start 25.88514 -220.768672)
		(end 25.88514 -219.651326)
		(stroke
			(width 0.2)
			(type default)
		)
		(layer "In1.Cu")
	)
	(gr_arc
		(start 25.88514 -219.651326)
		(mid 25.273127 -219.038932)
		(end 24.66086 -219.651072)
		(stroke
			(width 0.2)
			(type default)
		)
		(layer "In1.Cu")
	)
	(gr_line
		(start 25.88514 -140.16863)
		(end 25.88514 -139.051284)
		(stroke
			(width 0.2)
			(type default)
		)
		(layer "In1.Cu")
	)
	(gr_arc
		(start 25.88514 -139.051284)
		(mid 25.273127 -138.43889)
		(end 24.66086 -139.05103)
		(stroke
			(width 0.2)
			(type default)
		)
		(layer "In1.Cu")
	)
	(gr_line
		(start 25.88514 -127.368808)
		(end 25.88514 -126.251208)
		(stroke
			(width 0.2)
			(type default)
		)
		(layer "In1.Cu")
	)
	(gr_arc
		(start 25.88514 -126.251208)
		(mid 25.273 -125.639068)
		(end 24.66086 -126.251208)
		(stroke
			(width 0.2)
			(type default)
		)
		(layer "In1.Cu")
	)
	(gr_line
		(start 25.88514 -122.568716)
		(end 25.88514 -121.451116)
		(stroke
			(width 0.2)
			(type default)
		)
		(layer "In1.Cu")
	)
	(gr_arc
		(start 25.88514 -121.451116)
		(mid 25.273 -120.838976)
		(end 24.66086 -121.451116)
		(stroke
			(width 0.2)
			(type default)
		)
		(layer "In1.Cu")
	)
	(gr_line
		(start 25.88514 -117.768624)
		(end 25.88514 -116.651278)
		(stroke
			(width 0.2)
			(type default)
		)
		(layer "In1.Cu")
	)
	(gr_arc
		(start 25.88514 -116.651278)
		(mid 25.273127 -116.038884)
		(end 24.66086 -116.651024)
		(stroke
			(width 0.2)
			(type default)
		)
		(layer "In1.Cu")
	)
	(gr_line
		(start 25.88514 -37.168582)
		(end 25.88514 -36.050982)
		(stroke
			(width 0.2)
			(type default)
		)
		(layer "In1.Cu")
	)
	(gr_arc
		(start 25.88514 -36.050982)
		(mid 25.273 -35.438842)
		(end 24.66086 -36.050982)
		(stroke
			(width 0.2)
			(type default)
		)
		(layer "In1.Cu")
	)
	(gr_line
		(start 25.88514 -24.36876)
		(end 25.88514 -23.25116)
		(stroke
			(width 0.2)
			(type default)
		)
		(layer "In1.Cu")
	)
	(gr_arc
		(start 25.88514 -23.25116)
		(mid 25.273 -22.63902)
		(end 24.66086 -23.25116)
		(stroke
			(width 0.2)
			(type default)
		)
		(layer "In1.Cu")
	)
	(gr_line
		(start 25.88514 -19.568668)
		(end 25.88514 -18.451068)
		(stroke
			(width 0.2)
			(type default)
		)
		(layer "In1.Cu")
	)
	(gr_arc
		(start 25.88514 -18.451068)
		(mid 25.273 -17.838928)
		(end 24.66086 -18.451068)
		(stroke
			(width 0.2)
			(type default)
		)
		(layer "In1.Cu")
	)
	(gr_line
		(start 25.88514 -14.793976)
		(end 25.88514 -13.67663)
		(stroke
			(width 0.2)
			(type default)
		)
		(layer "In1.Cu")
	)
	(gr_arc
		(start 25.88514 -13.67663)
		(mid 25.273127 -13.064236)
		(end 24.66086 -13.676376)
		(stroke
			(width 0.2)
			(type default)
		)
		(layer "In1.Cu")
	)
	(gr_arc
		(start 26.15946 -451.41642)
		(mid 26.67 -451.92696)
		(end 27.18054 -451.41642)
		(stroke
			(width 0.2)
			(type default)
		)
		(layer "In1.Cu")
	)
	(gr_line
		(start 26.15946 -450.60362)
		(end 26.15946 -451.41642)
		(stroke
			(width 0.2)
			(type default)
		)
		(layer "In1.Cu")
	)
	(gr_arc
		(start 26.15946 -438.616344)
		(mid 26.67 -439.126884)
		(end 27.18054 -438.616344)
		(stroke
			(width 0.2)
			(type default)
		)
		(layer "In1.Cu")
	)
	(gr_line
		(start 26.15946 -437.803544)
		(end 26.15946 -438.616344)
		(stroke
			(width 0.2)
			(type default)
		)
		(layer "In1.Cu")
	)
	(gr_arc
		(start 26.15946 -433.816506)
		(mid 26.67 -434.327046)
		(end 27.18054 -433.816506)
		(stroke
			(width 0.2)
			(type default)
		)
		(layer "In1.Cu")
	)
	(gr_line
		(start 26.15946 -433.003706)
		(end 26.15946 -433.816506)
		(stroke
			(width 0.2)
			(type default)
		)
		(layer "In1.Cu")
	)
	(gr_arc
		(start 26.15946 -429.016414)
		(mid 26.67 -429.526954)
		(end 27.18054 -429.016414)
		(stroke
			(width 0.2)
			(type default)
		)
		(layer "In1.Cu")
	)
	(gr_line
		(start 26.15946 -428.203614)
		(end 26.15946 -429.016414)
		(stroke
			(width 0.2)
			(type default)
		)
		(layer "In1.Cu")
	)
	(gr_arc
		(start 26.15946 -348.416118)
		(mid 26.669873 -348.926912)
		(end 27.18054 -348.416372)
		(stroke
			(width 0.2)
			(type default)
		)
		(layer "In1.Cu")
	)
	(gr_line
		(start 26.15946 -347.603572)
		(end 26.15946 -348.416118)
		(stroke
			(width 0.2)
			(type default)
		)
		(layer "In1.Cu")
	)
	(gr_arc
		(start 26.15946 -335.616042)
		(mid 26.669873 -336.126836)
		(end 27.18054 -335.616296)
		(stroke
			(width 0.2)
			(type default)
		)
		(layer "In1.Cu")
	)
	(gr_line
		(start 26.15946 -334.803496)
		(end 26.15946 -335.616042)
		(stroke
			(width 0.2)
			(type default)
		)
		(layer "In1.Cu")
	)
	(gr_arc
		(start 26.15946 -330.816204)
		(mid 26.669873 -331.326998)
		(end 27.18054 -330.816458)
		(stroke
			(width 0.2)
			(type default)
		)
		(layer "In1.Cu")
	)
	(gr_line
		(start 26.15946 -330.003658)
		(end 26.15946 -330.816204)
		(stroke
			(width 0.2)
			(type default)
		)
		(layer "In1.Cu")
	)
	(gr_arc
		(start 26.15946 -326.016112)
		(mid 26.669873 -326.526906)
		(end 27.18054 -326.016366)
		(stroke
			(width 0.2)
			(type default)
		)
		(layer "In1.Cu")
	)
	(gr_line
		(start 26.15946 -325.203566)
		(end 26.15946 -326.016112)
		(stroke
			(width 0.2)
			(type default)
		)
		(layer "In1.Cu")
	)
	(gr_arc
		(start 26.15946 -245.41607)
		(mid 26.669873 -245.926864)
		(end 27.18054 -245.416324)
		(stroke
			(width 0.2)
			(type default)
		)
		(layer "In1.Cu")
	)
	(gr_line
		(start 26.15946 -244.603524)
		(end 26.15946 -245.41607)
		(stroke
			(width 0.2)
			(type default)
		)
		(layer "In1.Cu")
	)
	(gr_arc
		(start 26.15946 -232.615994)
		(mid 26.669873 -233.126788)
		(end 27.18054 -232.616248)
		(stroke
			(width 0.2)
			(type default)
		)
		(layer "In1.Cu")
	)
	(gr_line
		(start 26.15946 -231.803448)
		(end 26.15946 -232.615994)
		(stroke
			(width 0.2)
			(type default)
		)
		(layer "In1.Cu")
	)
	(gr_arc
		(start 26.15946 -227.816156)
		(mid 26.669873 -228.32695)
		(end 27.18054 -227.81641)
		(stroke
			(width 0.2)
			(type default)
		)
		(layer "In1.Cu")
	)
	(gr_line
		(start 26.15946 -227.00361)
		(end 26.15946 -227.816156)
		(stroke
			(width 0.2)
			(type default)
		)
		(layer "In1.Cu")
	)
	(gr_arc
		(start 26.15946 -223.016064)
		(mid 26.669873 -223.526858)
		(end 27.18054 -223.016318)
		(stroke
			(width 0.2)
			(type default)
		)
		(layer "In1.Cu")
	)
	(gr_line
		(start 26.15946 -222.203518)
		(end 26.15946 -223.016064)
		(stroke
			(width 0.2)
			(type default)
		)
		(layer "In1.Cu")
	)
	(gr_arc
		(start 26.15946 -142.416022)
		(mid 26.669873 -142.926816)
		(end 27.18054 -142.416276)
		(stroke
			(width 0.2)
			(type default)
		)
		(layer "In1.Cu")
	)
	(gr_line
		(start 26.15946 -141.603476)
		(end 26.15946 -142.416022)
		(stroke
			(width 0.2)
			(type default)
		)
		(layer "In1.Cu")
	)
	(gr_arc
		(start 26.15946 -129.615946)
		(mid 26.669873 -130.12674)
		(end 27.18054 -129.6162)
		(stroke
			(width 0.2)
			(type default)
		)
		(layer "In1.Cu")
	)
	(gr_line
		(start 26.15946 -128.8034)
		(end 26.15946 -129.615946)
		(stroke
			(width 0.2)
			(type default)
		)
		(layer "In1.Cu")
	)
	(gr_arc
		(start 26.15946 -124.816108)
		(mid 26.669873 -125.326902)
		(end 27.18054 -124.816362)
		(stroke
			(width 0.2)
			(type default)
		)
		(layer "In1.Cu")
	)
	(gr_line
		(start 26.15946 -124.003562)
		(end 26.15946 -124.816108)
		(stroke
			(width 0.2)
			(type default)
		)
		(layer "In1.Cu")
	)
	(gr_arc
		(start 26.15946 -120.016016)
		(mid 26.669873 -120.52681)
		(end 27.18054 -120.01627)
		(stroke
			(width 0.2)
			(type default)
		)
		(layer "In1.Cu")
	)
	(gr_line
		(start 26.15946 -119.20347)
		(end 26.15946 -120.016016)
		(stroke
			(width 0.2)
			(type default)
		)
		(layer "In1.Cu")
	)
	(gr_arc
		(start 26.15946 -39.415974)
		(mid 26.669873 -39.926768)
		(end 27.18054 -39.416228)
		(stroke
			(width 0.2)
			(type default)
		)
		(layer "In1.Cu")
	)
	(gr_line
		(start 26.15946 -38.603428)
		(end 26.15946 -39.415974)
		(stroke
			(width 0.2)
			(type default)
		)
		(layer "In1.Cu")
	)
	(gr_arc
		(start 26.15946 -26.615898)
		(mid 26.669873 -27.126692)
		(end 27.18054 -26.616152)
		(stroke
			(width 0.2)
			(type default)
		)
		(layer "In1.Cu")
	)
	(gr_line
		(start 26.15946 -25.803352)
		(end 26.15946 -26.615898)
		(stroke
			(width 0.2)
			(type default)
		)
		(layer "In1.Cu")
	)
	(gr_arc
		(start 26.15946 -21.81606)
		(mid 26.669873 -22.326854)
		(end 27.18054 -21.816314)
		(stroke
			(width 0.2)
			(type default)
		)
		(layer "In1.Cu")
	)
	(gr_line
		(start 26.15946 -21.003514)
		(end 26.15946 -21.81606)
		(stroke
			(width 0.2)
			(type default)
		)
		(layer "In1.Cu")
	)
	(gr_arc
		(start 26.15946 -17.015968)
		(mid 26.669873 -17.526762)
		(end 27.18054 -17.016222)
		(stroke
			(width 0.2)
			(type default)
		)
		(layer "In1.Cu")
	)
	(gr_line
		(start 26.15946 -16.203422)
		(end 26.15946 -17.015968)
		(stroke
			(width 0.2)
			(type default)
		)
		(layer "In1.Cu")
	)
	(gr_line
		(start 27.18054 -451.41642)
		(end 27.18054 -450.603874)
		(stroke
			(width 0.2)
			(type default)
		)
		(layer "In1.Cu")
	)
	(gr_arc
		(start 27.18054 -450.603874)
		(mid 26.670127 -450.09308)
		(end 26.15946 -450.60362)
		(stroke
			(width 0.2)
			(type default)
		)
		(layer "In1.Cu")
	)
	(gr_line
		(start 27.18054 -438.616344)
		(end 27.18054 -437.803798)
		(stroke
			(width 0.2)
			(type default)
		)
		(layer "In1.Cu")
	)
	(gr_arc
		(start 27.18054 -437.803798)
		(mid 26.670127 -437.293004)
		(end 26.15946 -437.803544)
		(stroke
			(width 0.2)
			(type default)
		)
		(layer "In1.Cu")
	)
	(gr_line
		(start 27.18054 -433.816506)
		(end 27.18054 -433.00396)
		(stroke
			(width 0.2)
			(type default)
		)
		(layer "In1.Cu")
	)
	(gr_arc
		(start 27.18054 -433.00396)
		(mid 26.670127 -432.493166)
		(end 26.15946 -433.003706)
		(stroke
			(width 0.2)
			(type default)
		)
		(layer "In1.Cu")
	)
	(gr_line
		(start 27.18054 -429.016414)
		(end 27.18054 -428.203868)
		(stroke
			(width 0.2)
			(type default)
		)
		(layer "In1.Cu")
	)
	(gr_arc
		(start 27.18054 -428.203868)
		(mid 26.670127 -427.693074)
		(end 26.15946 -428.203614)
		(stroke
			(width 0.2)
			(type default)
		)
		(layer "In1.Cu")
	)
	(gr_line
		(start 27.18054 -348.416372)
		(end 27.18054 -347.603572)
		(stroke
			(width 0.2)
			(type default)
		)
		(layer "In1.Cu")
	)
	(gr_arc
		(start 27.18054 -347.603572)
		(mid 26.67 -347.093032)
		(end 26.15946 -347.603572)
		(stroke
			(width 0.2)
			(type default)
		)
		(layer "In1.Cu")
	)
	(gr_line
		(start 27.18054 -335.616296)
		(end 27.18054 -334.803496)
		(stroke
			(width 0.2)
			(type default)
		)
		(layer "In1.Cu")
	)
	(gr_arc
		(start 27.18054 -334.803496)
		(mid 26.67 -334.292956)
		(end 26.15946 -334.803496)
		(stroke
			(width 0.2)
			(type default)
		)
		(layer "In1.Cu")
	)
	(gr_line
		(start 27.18054 -330.816458)
		(end 27.18054 -330.003658)
		(stroke
			(width 0.2)
			(type default)
		)
		(layer "In1.Cu")
	)
	(gr_arc
		(start 27.18054 -330.003658)
		(mid 26.67 -329.493118)
		(end 26.15946 -330.003658)
		(stroke
			(width 0.2)
			(type default)
		)
		(layer "In1.Cu")
	)
	(gr_line
		(start 27.18054 -326.016366)
		(end 27.18054 -325.203566)
		(stroke
			(width 0.2)
			(type default)
		)
		(layer "In1.Cu")
	)
	(gr_arc
		(start 27.18054 -325.203566)
		(mid 26.67 -324.693026)
		(end 26.15946 -325.203566)
		(stroke
			(width 0.2)
			(type default)
		)
		(layer "In1.Cu")
	)
	(gr_line
		(start 27.18054 -245.416324)
		(end 27.18054 -244.603524)
		(stroke
			(width 0.2)
			(type default)
		)
		(layer "In1.Cu")
	)
	(gr_arc
		(start 27.18054 -244.603524)
		(mid 26.67 -244.092984)
		(end 26.15946 -244.603524)
		(stroke
			(width 0.2)
			(type default)
		)
		(layer "In1.Cu")
	)
	(gr_line
		(start 27.18054 -232.616248)
		(end 27.18054 -231.803448)
		(stroke
			(width 0.2)
			(type default)
		)
		(layer "In1.Cu")
	)
	(gr_arc
		(start 27.18054 -231.803448)
		(mid 26.67 -231.292908)
		(end 26.15946 -231.803448)
		(stroke
			(width 0.2)
			(type default)
		)
		(layer "In1.Cu")
	)
	(gr_line
		(start 27.18054 -227.81641)
		(end 27.18054 -227.00361)
		(stroke
			(width 0.2)
			(type default)
		)
		(layer "In1.Cu")
	)
	(gr_arc
		(start 27.18054 -227.00361)
		(mid 26.67 -226.49307)
		(end 26.15946 -227.00361)
		(stroke
			(width 0.2)
			(type default)
		)
		(layer "In1.Cu")
	)
	(gr_line
		(start 27.18054 -223.016318)
		(end 27.18054 -222.203518)
		(stroke
			(width 0.2)
			(type default)
		)
		(layer "In1.Cu")
	)
	(gr_arc
		(start 27.18054 -222.203518)
		(mid 26.67 -221.692978)
		(end 26.15946 -222.203518)
		(stroke
			(width 0.2)
			(type default)
		)
		(layer "In1.Cu")
	)
	(gr_line
		(start 27.18054 -142.416276)
		(end 27.18054 -141.603476)
		(stroke
			(width 0.2)
			(type default)
		)
		(layer "In1.Cu")
	)
	(gr_arc
		(start 27.18054 -141.603476)
		(mid 26.67 -141.092936)
		(end 26.15946 -141.603476)
		(stroke
			(width 0.2)
			(type default)
		)
		(layer "In1.Cu")
	)
	(gr_line
		(start 27.18054 -129.6162)
		(end 27.18054 -128.8034)
		(stroke
			(width 0.2)
			(type default)
		)
		(layer "In1.Cu")
	)
	(gr_arc
		(start 27.18054 -128.8034)
		(mid 26.67 -128.29286)
		(end 26.15946 -128.8034)
		(stroke
			(width 0.2)
			(type default)
		)
		(layer "In1.Cu")
	)
	(gr_line
		(start 27.18054 -124.816362)
		(end 27.18054 -124.003562)
		(stroke
			(width 0.2)
			(type default)
		)
		(layer "In1.Cu")
	)
	(gr_arc
		(start 27.18054 -124.003562)
		(mid 26.67 -123.493022)
		(end 26.15946 -124.003562)
		(stroke
			(width 0.2)
			(type default)
		)
		(layer "In1.Cu")
	)
	(gr_line
		(start 27.18054 -120.01627)
		(end 27.18054 -119.20347)
		(stroke
			(width 0.2)
			(type default)
		)
		(layer "In1.Cu")
	)
	(gr_arc
		(start 27.18054 -119.20347)
		(mid 26.67 -118.69293)
		(end 26.15946 -119.20347)
		(stroke
			(width 0.2)
			(type default)
		)
		(layer "In1.Cu")
	)
	(gr_line
		(start 27.18054 -39.416228)
		(end 27.18054 -38.603428)
		(stroke
			(width 0.2)
			(type default)
		)
		(layer "In1.Cu")
	)
	(gr_arc
		(start 27.18054 -38.603428)
		(mid 26.67 -38.092888)
		(end 26.15946 -38.603428)
		(stroke
			(width 0.2)
			(type default)
		)
		(layer "In1.Cu")
	)
	(gr_line
		(start 27.18054 -26.616152)
		(end 27.18054 -25.803352)
		(stroke
			(width 0.2)
			(type default)
		)
		(layer "In1.Cu")
	)
	(gr_arc
		(start 27.18054 -25.803352)
		(mid 26.67 -25.292812)
		(end 26.15946 -25.803352)
		(stroke
			(width 0.2)
			(type default)
		)
		(layer "In1.Cu")
	)
	(gr_line
		(start 27.18054 -21.816314)
		(end 27.18054 -21.003514)
		(stroke
			(width 0.2)
			(type default)
		)
		(layer "In1.Cu")
	)
	(gr_arc
		(start 27.18054 -21.003514)
		(mid 26.67 -20.492974)
		(end 26.15946 -21.003514)
		(stroke
			(width 0.2)
			(type default)
		)
		(layer "In1.Cu")
	)
	(gr_line
		(start 27.18054 -17.016222)
		(end 27.18054 -16.203422)
		(stroke
			(width 0.2)
			(type default)
		)
		(layer "In1.Cu")
	)
	(gr_arc
		(start 27.18054 -16.203422)
		(mid 26.67 -15.692882)
		(end 26.15946 -16.203422)
		(stroke
			(width 0.2)
			(type default)
		)
		(layer "In1.Cu")
	)
	(gr_line
		(start 30.80004 0)
		(end 32.33674 -3.019552)
		(stroke
			(width 1.524)
			(type default)
		)
		(layer "In1.Cu")
	)
	(gr_arc
		(start 30.98546 -136.416542)
		(mid 31.496 -136.927082)
		(end 32.00654 -136.416542)
		(stroke
			(width 0.2)
			(type default)
		)
		(layer "In1.Cu")
	)
	(gr_line
		(start 30.98546 -135.603742)
		(end 30.98546 -136.416542)
		(stroke
			(width 0.2)
			(type default)
		)
		(layer "In1.Cu")
	)
	(gr_arc
		(start 30.98546 -33.415986)
		(mid 31.496 -33.926526)
		(end 32.00654 -33.415986)
		(stroke
			(width 0.2)
			(type default)
		)
		(layer "In1.Cu")
	)
	(gr_line
		(start 30.98546 -32.603186)
		(end 30.98546 -33.415986)
		(stroke
			(width 0.2)
			(type default)
		)
		(layer "In1.Cu")
	)
	(gr_arc
		(start 31.23946 -445.397636)
		(mid 31.75 -445.908176)
		(end 32.26054 -445.397636)
		(stroke
			(width 0.2)
			(type default)
		)
		(layer "In1.Cu")
	)
	(gr_line
		(start 31.23946 -444.584836)
		(end 31.23946 -445.397636)
		(stroke
			(width 0.2)
			(type default)
		)
		(layer "In1.Cu")
	)
	(gr_line
		(start 32.00654 -136.416542)
		(end 32.00654 -135.603996)
		(stroke
			(width 0.2)
			(type default)
		)
		(layer "In1.Cu")
	)
	(gr_arc
		(start 32.00654 -135.603996)
		(mid 31.496127 -135.093202)
		(end 30.98546 -135.603742)
		(stroke
			(width 0.2)
			(type default)
		)
		(layer "In1.Cu")
	)
	(gr_line
		(start 32.00654 -33.415986)
		(end 32.00654 -32.60344)
		(stroke
			(width 0.2)
			(type default)
		)
		(layer "In1.Cu")
	)
	(gr_arc
		(start 32.00654 -32.60344)
		(mid 31.496127 -32.092646)
		(end 30.98546 -32.603186)
		(stroke
			(width 0.2)
			(type default)
		)
		(layer "In1.Cu")
	)
	(gr_line
		(start 32.26054 -445.397636)
		(end 32.26054 -444.58509)
		(stroke
			(width 0.2)
			(type default)
		)
		(layer "In1.Cu")
	)
	(gr_arc
		(start 32.26054 -444.58509)
		(mid 31.750127 -444.074296)
		(end 31.23946 -444.584836)
		(stroke
			(width 0.2)
			(type default)
		)
		(layer "In1.Cu")
	)
	(gr_arc
		(start 32.38246 -342.397334)
		(mid 32.893 -342.907874)
		(end 33.40354 -342.397334)
		(stroke
			(width 0.2)
			(type default)
		)
		(layer "In1.Cu")
	)
	(gr_line
		(start 32.38246 -341.584534)
		(end 32.38246 -342.397334)
		(stroke
			(width 0.2)
			(type default)
		)
		(layer "In1.Cu")
	)
	(gr_arc
		(start 32.500062 -4.500118)
		(mid 34.000186 -6.000242)
		(end 35.500056 -4.500118)
		(stroke
			(width 1.524)
			(type default)
		)
		(layer "In1.Cu")
	)
	(gr_arc
		(start 32.500062 -3.700018)
		(mid 32.458636 -3.350129)
		(end 32.33674 -3.019552)
		(stroke
			(width 1.524)
			(type default)
		)
		(layer "In1.Cu")
	)
	(gr_line
		(start 32.500062 -3.700018)
		(end 32.500062 -4.500118)
		(stroke
			(width 1.524)
			(type default)
		)
		(layer "In1.Cu")
	)
	(gr_line
		(start 33.40354 -342.397334)
		(end 33.40354 -341.584788)
		(stroke
			(width 0.2)
			(type default)
		)
		(layer "In1.Cu")
	)
	(gr_arc
		(start 33.40354 -341.584788)
		(mid 32.893127 -341.073994)
		(end 32.38246 -341.584534)
		(stroke
			(width 0.2)
			(type default)
		)
		(layer "In1.Cu")
	)
	(gr_arc
		(start 34.81959 -489.796328)
		(mid 35.330003 -490.307122)
		(end 35.84067 -489.796582)
		(stroke
			(width 0.2)
			(type default)
		)
		(layer "In1.Cu")
	)
	(gr_line
		(start 34.81959 -488.983782)
		(end 34.81959 -489.796328)
		(stroke
			(width 0.2)
			(type default)
		)
		(layer "In1.Cu")
	)
	(gr_arc
		(start 34.81959 -484.996236)
		(mid 35.330003 -485.50703)
		(end 35.84067 -484.99649)
		(stroke
			(width 0.2)
			(type default)
		)
		(layer "In1.Cu")
	)
	(gr_line
		(start 34.81959 -484.18369)
		(end 34.81959 -484.996236)
		(stroke
			(width 0.2)
			(type default)
		)
		(layer "In1.Cu")
	)
	(gr_arc
		(start 34.81959 -480.196398)
		(mid 35.330003 -480.707192)
		(end 35.84067 -480.196652)
		(stroke
			(width 0.2)
			(type default)
		)
		(layer "In1.Cu")
	)
	(gr_line
		(start 34.81959 -479.383852)
		(end 34.81959 -480.196398)
		(stroke
			(width 0.2)
			(type default)
		)
		(layer "In1.Cu")
	)
	(gr_arc
		(start 34.81959 -467.396322)
		(mid 35.330003 -467.907116)
		(end 35.84067 -467.396576)
		(stroke
			(width 0.2)
			(type default)
		)
		(layer "In1.Cu")
	)
	(gr_line
		(start 34.81959 -466.583776)
		(end 34.81959 -467.396322)
		(stroke
			(width 0.2)
			(type default)
		)
		(layer "In1.Cu")
	)
	(gr_arc
		(start 34.81959 -386.796534)
		(mid 35.33013 -387.307074)
		(end 35.84067 -386.796534)
		(stroke
			(width 0.2)
			(type default)
		)
		(layer "In1.Cu")
	)
	(gr_line
		(start 34.81959 -385.983734)
		(end 34.81959 -386.796534)
		(stroke
			(width 0.2)
			(type default)
		)
		(layer "In1.Cu")
	)
	(gr_arc
		(start 34.81959 -381.996442)
		(mid 35.33013 -382.506982)
		(end 35.84067 -381.996442)
		(stroke
			(width 0.2)
			(type default)
		)
		(layer "In1.Cu")
	)
	(gr_line
		(start 34.81959 -381.183642)
		(end 34.81959 -381.996442)
		(stroke
			(width 0.2)
			(type default)
		)
		(layer "In1.Cu")
	)
	(gr_arc
		(start 34.81959 -377.196604)
		(mid 35.33013 -377.707144)
		(end 35.84067 -377.196604)
		(stroke
			(width 0.2)
			(type default)
		)
		(layer "In1.Cu")
	)
	(gr_line
		(start 34.81959 -376.383804)
		(end 34.81959 -377.196604)
		(stroke
			(width 0.2)
			(type default)
		)
		(layer "In1.Cu")
	)
	(gr_arc
		(start 34.81959 -364.396528)
		(mid 35.33013 -364.907068)
		(end 35.84067 -364.396528)
		(stroke
			(width 0.2)
			(type default)
		)
		(layer "In1.Cu")
	)
	(gr_line
		(start 34.81959 -363.583728)
		(end 34.81959 -364.396528)
		(stroke
			(width 0.2)
			(type default)
		)
		(layer "In1.Cu")
	)
	(gr_arc
		(start 34.81959 -283.796486)
		(mid 35.33013 -284.307026)
		(end 35.84067 -283.796486)
		(stroke
			(width 0.2)
			(type default)
		)
		(layer "In1.Cu")
	)
	(gr_line
		(start 34.81959 -282.983686)
		(end 34.81959 -283.796486)
		(stroke
			(width 0.2)
			(type default)
		)
		(layer "In1.Cu")
	)
	(gr_arc
		(start 34.81959 -278.996394)
		(mid 35.33013 -279.506934)
		(end 35.84067 -278.996394)
		(stroke
			(width 0.2)
			(type default)
		)
		(layer "In1.Cu")
	)
	(gr_line
		(start 34.81959 -278.183594)
		(end 34.81959 -278.996394)
		(stroke
			(width 0.2)
			(type default)
		)
		(layer "In1.Cu")
	)
	(gr_arc
		(start 34.81959 -274.196556)
		(mid 35.33013 -274.707096)
		(end 35.84067 -274.196556)
		(stroke
			(width 0.2)
			(type default)
		)
		(layer "In1.Cu")
	)
	(gr_line
		(start 34.81959 -273.383756)
		(end 34.81959 -274.196556)
		(stroke
			(width 0.2)
			(type default)
		)
		(layer "In1.Cu")
	)
	(gr_arc
		(start 34.81959 -261.39648)
		(mid 35.33013 -261.90702)
		(end 35.84067 -261.39648)
		(stroke
			(width 0.2)
			(type default)
		)
		(layer "In1.Cu")
	)
	(gr_line
		(start 34.81959 -260.58368)
		(end 34.81959 -261.39648)
		(stroke
			(width 0.2)
			(type default)
		)
		(layer "In1.Cu")
	)
	(gr_arc
		(start 34.81959 -180.796438)
		(mid 35.33013 -181.306978)
		(end 35.84067 -180.796438)
		(stroke
			(width 0.2)
			(type default)
		)
		(layer "In1.Cu")
	)
	(gr_line
		(start 34.81959 -179.983638)
		(end 34.81959 -180.796438)
		(stroke
			(width 0.2)
			(type default)
		)
		(layer "In1.Cu")
	)
	(gr_arc
		(start 34.81959 -175.996346)
		(mid 35.33013 -176.506886)
		(end 35.84067 -175.996346)
		(stroke
			(width 0.2)
			(type default)
		)
		(layer "In1.Cu")
	)
	(gr_line
		(start 34.81959 -175.183546)
		(end 34.81959 -175.996346)
		(stroke
			(width 0.2)
			(type default)
		)
		(layer "In1.Cu")
	)
	(gr_arc
		(start 34.81959 -171.196508)
		(mid 35.33013 -171.707048)
		(end 35.84067 -171.196508)
		(stroke
			(width 0.2)
			(type default)
		)
		(layer "In1.Cu")
	)
	(gr_line
		(start 34.81959 -170.383708)
		(end 34.81959 -171.196508)
		(stroke
			(width 0.2)
			(type default)
		)
		(layer "In1.Cu")
	)
	(gr_arc
		(start 34.81959 -158.396432)
		(mid 35.33013 -158.906972)
		(end 35.84067 -158.396432)
		(stroke
			(width 0.2)
			(type default)
		)
		(layer "In1.Cu")
	)
	(gr_line
		(start 34.81959 -157.583632)
		(end 34.81959 -158.396432)
		(stroke
			(width 0.2)
			(type default)
		)
		(layer "In1.Cu")
	)
	(gr_arc
		(start 34.81959 -77.79639)
		(mid 35.33013 -78.30693)
		(end 35.84067 -77.79639)
		(stroke
			(width 0.2)
			(type default)
		)
		(layer "In1.Cu")
	)
	(gr_line
		(start 34.81959 -76.98359)
		(end 34.81959 -77.79639)
		(stroke
			(width 0.2)
			(type default)
		)
		(layer "In1.Cu")
	)
	(gr_arc
		(start 34.81959 -72.996298)
		(mid 35.33013 -73.506838)
		(end 35.84067 -72.996298)
		(stroke
			(width 0.2)
			(type default)
		)
		(layer "In1.Cu")
	)
	(gr_line
		(start 34.81959 -72.183498)
		(end 34.81959 -72.996298)
		(stroke
			(width 0.2)
			(type default)
		)
		(layer "In1.Cu")
	)
	(gr_arc
		(start 34.81959 -68.19646)
		(mid 35.33013 -68.707)
		(end 35.84067 -68.19646)
		(stroke
			(width 0.2)
			(type default)
		)
		(layer "In1.Cu")
	)
	(gr_line
		(start 34.81959 -67.38366)
		(end 34.81959 -68.19646)
		(stroke
			(width 0.2)
			(type default)
		)
		(layer "In1.Cu")
	)
	(gr_arc
		(start 34.81959 -55.396384)
		(mid 35.33013 -55.906924)
		(end 35.84067 -55.396384)
		(stroke
			(width 0.2)
			(type default)
		)
		(layer "In1.Cu")
	)
	(gr_line
		(start 34.81959 -54.583584)
		(end 34.81959 -55.396384)
		(stroke
			(width 0.2)
			(type default)
		)
		(layer "In1.Cu")
	)
	(gr_line
		(start 35.500056 -4.500118)
		(end 35.500056 -3.700018)
		(stroke
			(width 1.524)
			(type default)
		)
		(layer "In1.Cu")
	)
	(gr_arc
		(start 35.663124 -3.019552)
		(mid 35.541364 -3.350145)
		(end 35.500056 -3.700018)
		(stroke
			(width 1.524)
			(type default)
		)
		(layer "In1.Cu")
	)
	(gr_line
		(start 35.663124 -3.019552)
		(end 37.200078 0)
		(stroke
			(width 1.524)
			(type default)
		)
		(layer "In1.Cu")
	)
	(gr_line
		(start 35.84067 -489.796582)
		(end 35.84067 -488.983782)
		(stroke
			(width 0.2)
			(type default)
		)
		(layer "In1.Cu")
	)
	(gr_arc
		(start 35.84067 -488.983782)
		(mid 35.33013 -488.473242)
		(end 34.81959 -488.983782)
		(stroke
			(width 0.2)
			(type default)
		)
		(layer "In1.Cu")
	)
	(gr_line
		(start 35.84067 -484.99649)
		(end 35.84067 -484.18369)
		(stroke
			(width 0.2)
			(type default)
		)
		(layer "In1.Cu")
	)
	(gr_arc
		(start 35.84067 -484.18369)
		(mid 35.33013 -483.67315)
		(end 34.81959 -484.18369)
		(stroke
			(width 0.2)
			(type default)
		)
		(layer "In1.Cu")
	)
	(gr_line
		(start 35.84067 -480.196652)
		(end 35.84067 -479.383852)
		(stroke
			(width 0.2)
			(type default)
		)
		(layer "In1.Cu")
	)
	(gr_arc
		(start 35.84067 -479.383852)
		(mid 35.33013 -478.873312)
		(end 34.81959 -479.383852)
		(stroke
			(width 0.2)
			(type default)
		)
		(layer "In1.Cu")
	)
	(gr_line
		(start 35.84067 -467.396576)
		(end 35.84067 -466.583776)
		(stroke
			(width 0.2)
			(type default)
		)
		(layer "In1.Cu")
	)
	(gr_arc
		(start 35.84067 -466.583776)
		(mid 35.33013 -466.073236)
		(end 34.81959 -466.583776)
		(stroke
			(width 0.2)
			(type default)
		)
		(layer "In1.Cu")
	)
	(gr_line
		(start 35.84067 -386.796534)
		(end 35.84067 -385.983988)
		(stroke
			(width 0.2)
			(type default)
		)
		(layer "In1.Cu")
	)
	(gr_arc
		(start 35.84067 -385.983988)
		(mid 35.330257 -385.473194)
		(end 34.81959 -385.983734)
		(stroke
			(width 0.2)
			(type default)
		)
		(layer "In1.Cu")
	)
	(gr_line
		(start 35.84067 -381.996442)
		(end 35.84067 -381.183896)
		(stroke
			(width 0.2)
			(type default)
		)
		(layer "In1.Cu")
	)
	(gr_arc
		(start 35.84067 -381.183896)
		(mid 35.330257 -380.673102)
		(end 34.81959 -381.183642)
		(stroke
			(width 0.2)
			(type default)
		)
		(layer "In1.Cu")
	)
	(gr_line
		(start 35.84067 -377.196604)
		(end 35.84067 -376.384058)
		(stroke
			(width 0.2)
			(type default)
		)
		(layer "In1.Cu")
	)
	(gr_arc
		(start 35.84067 -376.384058)
		(mid 35.330257 -375.873264)
		(end 34.81959 -376.383804)
		(stroke
			(width 0.2)
			(type default)
		)
		(layer "In1.Cu")
	)
	(gr_line
		(start 35.84067 -364.396528)
		(end 35.84067 -363.583982)
		(stroke
			(width 0.2)
			(type default)
		)
		(layer "In1.Cu")
	)
	(gr_arc
		(start 35.84067 -363.583982)
		(mid 35.330257 -363.073188)
		(end 34.81959 -363.583728)
		(stroke
			(width 0.2)
			(type default)
		)
		(layer "In1.Cu")
	)
	(gr_line
		(start 35.84067 -283.796486)
		(end 35.84067 -282.98394)
		(stroke
			(width 0.2)
			(type default)
		)
		(layer "In1.Cu")
	)
	(gr_arc
		(start 35.84067 -282.98394)
		(mid 35.330257 -282.473146)
		(end 34.81959 -282.983686)
		(stroke
			(width 0.2)
			(type default)
		)
		(layer "In1.Cu")
	)
	(gr_line
		(start 35.84067 -278.996394)
		(end 35.84067 -278.183848)
		(stroke
			(width 0.2)
			(type default)
		)
		(layer "In1.Cu")
	)
	(gr_arc
		(start 35.84067 -278.183848)
		(mid 35.330257 -277.673054)
		(end 34.81959 -278.183594)
		(stroke
			(width 0.2)
			(type default)
		)
		(layer "In1.Cu")
	)
	(gr_line
		(start 35.84067 -274.196556)
		(end 35.84067 -273.38401)
		(stroke
			(width 0.2)
			(type default)
		)
		(layer "In1.Cu")
	)
	(gr_arc
		(start 35.84067 -273.38401)
		(mid 35.330257 -272.873216)
		(end 34.81959 -273.383756)
		(stroke
			(width 0.2)
			(type default)
		)
		(layer "In1.Cu")
	)
	(gr_line
		(start 35.84067 -261.39648)
		(end 35.84067 -260.583934)
		(stroke
			(width 0.2)
			(type default)
		)
		(layer "In1.Cu")
	)
	(gr_arc
		(start 35.84067 -260.583934)
		(mid 35.330257 -260.07314)
		(end 34.81959 -260.58368)
		(stroke
			(width 0.2)
			(type default)
		)
		(layer "In1.Cu")
	)
	(gr_line
		(start 35.84067 -180.796438)
		(end 35.84067 -179.983892)
		(stroke
			(width 0.2)
			(type default)
		)
		(layer "In1.Cu")
	)
	(gr_arc
		(start 35.84067 -179.983892)
		(mid 35.330257 -179.473098)
		(end 34.81959 -179.983638)
		(stroke
			(width 0.2)
			(type default)
		)
		(layer "In1.Cu")
	)
	(gr_line
		(start 35.84067 -175.996346)
		(end 35.84067 -175.1838)
		(stroke
			(width 0.2)
			(type default)
		)
		(layer "In1.Cu")
	)
	(gr_arc
		(start 35.84067 -175.1838)
		(mid 35.330257 -174.673006)
		(end 34.81959 -175.183546)
		(stroke
			(width 0.2)
			(type default)
		)
		(layer "In1.Cu")
	)
	(gr_line
		(start 35.84067 -171.196508)
		(end 35.84067 -170.383962)
		(stroke
			(width 0.2)
			(type default)
		)
		(layer "In1.Cu")
	)
	(gr_arc
		(start 35.84067 -170.383962)
		(mid 35.330257 -169.873168)
		(end 34.81959 -170.383708)
		(stroke
			(width 0.2)
			(type default)
		)
		(layer "In1.Cu")
	)
	(gr_line
		(start 35.84067 -158.396432)
		(end 35.84067 -157.583886)
		(stroke
			(width 0.2)
			(type default)
		)
		(layer "In1.Cu")
	)
	(gr_arc
		(start 35.84067 -157.583886)
		(mid 35.330257 -157.073092)
		(end 34.81959 -157.583632)
		(stroke
			(width 0.2)
			(type default)
		)
		(layer "In1.Cu")
	)
	(gr_line
		(start 35.84067 -77.79639)
		(end 35.84067 -76.983844)
		(stroke
			(width 0.2)
			(type default)
		)
		(layer "In1.Cu")
	)
	(gr_arc
		(start 35.84067 -76.983844)
		(mid 35.330257 -76.47305)
		(end 34.81959 -76.98359)
		(stroke
			(width 0.2)
			(type default)
		)
		(layer "In1.Cu")
	)
	(gr_line
		(start 35.84067 -72.996298)
		(end 35.84067 -72.183752)
		(stroke
			(width 0.2)
			(type default)
		)
		(layer "In1.Cu")
	)
	(gr_arc
		(start 35.84067 -72.183752)
		(mid 35.330257 -71.672958)
		(end 34.81959 -72.183498)
		(stroke
			(width 0.2)
			(type default)
		)
		(layer "In1.Cu")
	)
	(gr_line
		(start 35.84067 -68.19646)
		(end 35.84067 -67.383914)
		(stroke
			(width 0.2)
			(type default)
		)
		(layer "In1.Cu")
	)
	(gr_arc
		(start 35.84067 -67.383914)
		(mid 35.330257 -66.87312)
		(end 34.81959 -67.38366)
		(stroke
			(width 0.2)
			(type default)
		)
		(layer "In1.Cu")
	)
	(gr_line
		(start 35.84067 -55.396384)
		(end 35.84067 -54.583838)
		(stroke
			(width 0.2)
			(type default)
		)
		(layer "In1.Cu")
	)
	(gr_arc
		(start 35.84067 -54.583838)
		(mid 35.330257 -54.073044)
		(end 34.81959 -54.583584)
		(stroke
			(width 0.2)
			(type default)
		)
		(layer "In1.Cu")
	)
	(gr_arc
		(start 36.11499 -492.348774)
		(mid 36.727003 -492.961168)
		(end 37.33927 -492.349028)
		(stroke
			(width 0.2)
			(type default)
		)
		(layer "In1.Cu")
	)
	(gr_line
		(start 36.11499 -491.231428)
		(end 36.11499 -492.348774)
		(stroke
			(width 0.2)
			(type default)
		)
		(layer "In1.Cu")
	)
	(gr_arc
		(start 36.11499 -487.548936)
		(mid 36.72713 -488.161076)
		(end 37.33927 -487.548936)
		(stroke
			(width 0.2)
			(type default)
		)
		(layer "In1.Cu")
	)
	(gr_line
		(start 36.11499 -486.431336)
		(end 36.11499 -487.548936)
		(stroke
			(width 0.2)
			(type default)
		)
		(layer "In1.Cu")
	)
	(gr_arc
		(start 36.11499 -482.74859)
		(mid 36.727003 -483.360984)
		(end 37.33927 -482.748844)
		(stroke
			(width 0.2)
			(type default)
		)
		(layer "In1.Cu")
	)
	(gr_line
		(start 36.11499 -481.631244)
		(end 36.11499 -482.74859)
		(stroke
			(width 0.2)
			(type default)
		)
		(layer "In1.Cu")
	)
	(gr_arc
		(start 36.11499 -469.948768)
		(mid 36.727003 -470.561162)
		(end 37.33927 -469.949022)
		(stroke
			(width 0.2)
			(type default)
		)
		(layer "In1.Cu")
	)
	(gr_line
		(start 36.11499 -468.831422)
		(end 36.11499 -469.948768)
		(stroke
			(width 0.2)
			(type default)
		)
		(layer "In1.Cu")
	)
	(gr_arc
		(start 36.11499 -389.34898)
		(mid 36.72713 -389.96112)
		(end 37.33927 -389.34898)
		(stroke
			(width 0.2)
			(type default)
		)
		(layer "In1.Cu")
	)
	(gr_line
		(start 36.11499 -388.23138)
		(end 36.11499 -389.34898)
		(stroke
			(width 0.2)
			(type default)
		)
		(layer "In1.Cu")
	)
	(gr_arc
		(start 36.11499 -384.548888)
		(mid 36.72713 -385.161028)
		(end 37.33927 -384.548888)
		(stroke
			(width 0.2)
			(type default)
		)
		(layer "In1.Cu")
	)
	(gr_line
		(start 36.11499 -383.431288)
		(end 36.11499 -384.548888)
		(stroke
			(width 0.2)
			(type default)
		)
		(layer "In1.Cu")
	)
	(gr_arc
		(start 36.11499 -379.748796)
		(mid 36.72713 -380.360936)
		(end 37.33927 -379.748796)
		(stroke
			(width 0.2)
			(type default)
		)
		(layer "In1.Cu")
	)
	(gr_line
		(start 36.11499 -378.631196)
		(end 36.11499 -379.748796)
		(stroke
			(width 0.2)
			(type default)
		)
		(layer "In1.Cu")
	)
	(gr_arc
		(start 36.11499 -366.948974)
		(mid 36.72713 -367.561114)
		(end 37.33927 -366.948974)
		(stroke
			(width 0.2)
			(type default)
		)
		(layer "In1.Cu")
	)
	(gr_line
		(start 36.11499 -365.831374)
		(end 36.11499 -366.948974)
		(stroke
			(width 0.2)
			(type default)
		)
		(layer "In1.Cu")
	)
	(gr_arc
		(start 36.11499 -286.348932)
		(mid 36.72713 -286.961072)
		(end 37.33927 -286.348932)
		(stroke
			(width 0.2)
			(type default)
		)
		(layer "In1.Cu")
	)
	(gr_line
		(start 36.11499 -285.231332)
		(end 36.11499 -286.348932)
		(stroke
			(width 0.2)
			(type default)
		)
		(layer "In1.Cu")
	)
	(gr_arc
		(start 36.11499 -281.54884)
		(mid 36.72713 -282.16098)
		(end 37.33927 -281.54884)
		(stroke
			(width 0.2)
			(type default)
		)
		(layer "In1.Cu")
	)
	(gr_line
		(start 36.11499 -280.43124)
		(end 36.11499 -281.54884)
		(stroke
			(width 0.2)
			(type default)
		)
		(layer "In1.Cu")
	)
	(gr_arc
		(start 36.11499 -276.748748)
		(mid 36.72713 -277.360888)
		(end 37.33927 -276.748748)
		(stroke
			(width 0.2)
			(type default)
		)
		(layer "In1.Cu")
	)
	(gr_line
		(start 36.11499 -275.631148)
		(end 36.11499 -276.748748)
		(stroke
			(width 0.2)
			(type default)
		)
		(layer "In1.Cu")
	)
	(gr_arc
		(start 36.11499 -263.948926)
		(mid 36.72713 -264.561066)
		(end 37.33927 -263.948926)
		(stroke
			(width 0.2)
			(type default)
		)
		(layer "In1.Cu")
	)
	(gr_line
		(start 36.11499 -262.831326)
		(end 36.11499 -263.948926)
		(stroke
			(width 0.2)
			(type default)
		)
		(layer "In1.Cu")
	)
	(gr_arc
		(start 36.11499 -183.348884)
		(mid 36.72713 -183.961024)
		(end 37.33927 -183.348884)
		(stroke
			(width 0.2)
			(type default)
		)
		(layer "In1.Cu")
	)
	(gr_line
		(start 36.11499 -182.231284)
		(end 36.11499 -183.348884)
		(stroke
			(width 0.2)
			(type default)
		)
		(layer "In1.Cu")
	)
	(gr_arc
		(start 36.11499 -178.548792)
		(mid 36.72713 -179.160932)
		(end 37.33927 -178.548792)
		(stroke
			(width 0.2)
			(type default)
		)
		(layer "In1.Cu")
	)
	(gr_line
		(start 36.11499 -177.431192)
		(end 36.11499 -178.548792)
		(stroke
			(width 0.2)
			(type default)
		)
		(layer "In1.Cu")
	)
	(gr_arc
		(start 36.11499 -173.7487)
		(mid 36.72713 -174.36084)
		(end 37.33927 -173.7487)
		(stroke
			(width 0.2)
			(type default)
		)
		(layer "In1.Cu")
	)
	(gr_line
		(start 36.11499 -172.6311)
		(end 36.11499 -173.7487)
		(stroke
			(width 0.2)
			(type default)
		)
		(layer "In1.Cu")
	)
	(gr_arc
		(start 36.11499 -160.948878)
		(mid 36.72713 -161.561018)
		(end 37.33927 -160.948878)
		(stroke
			(width 0.2)
			(type default)
		)
		(layer "In1.Cu")
	)
	(gr_line
		(start 36.11499 -159.831278)
		(end 36.11499 -160.948878)
		(stroke
			(width 0.2)
			(type default)
		)
		(layer "In1.Cu")
	)
	(gr_arc
		(start 36.11499 -80.348836)
		(mid 36.72713 -80.960976)
		(end 37.33927 -80.348836)
		(stroke
			(width 0.2)
			(type default)
		)
		(layer "In1.Cu")
	)
	(gr_line
		(start 36.11499 -79.231236)
		(end 36.11499 -80.348836)
		(stroke
			(width 0.2)
			(type default)
		)
		(layer "In1.Cu")
	)
	(gr_arc
		(start 36.11499 -75.548744)
		(mid 36.72713 -76.160884)
		(end 37.33927 -75.548744)
		(stroke
			(width 0.2)
			(type default)
		)
		(layer "In1.Cu")
	)
	(gr_line
		(start 36.11499 -74.431144)
		(end 36.11499 -75.548744)
		(stroke
			(width 0.2)
			(type default)
		)
		(layer "In1.Cu")
	)
	(gr_arc
		(start 36.11499 -70.748652)
		(mid 36.72713 -71.360792)
		(end 37.33927 -70.748652)
		(stroke
			(width 0.2)
			(type default)
		)
		(layer "In1.Cu")
	)
	(gr_line
		(start 36.11499 -69.631052)
		(end 36.11499 -70.748652)
		(stroke
			(width 0.2)
			(type default)
		)
		(layer "In1.Cu")
	)
	(gr_arc
		(start 36.11499 -57.94883)
		(mid 36.72713 -58.56097)
		(end 37.33927 -57.94883)
		(stroke
			(width 0.2)
			(type default)
		)
		(layer "In1.Cu")
	)
	(gr_line
		(start 36.11499 -56.83123)
		(end 36.11499 -57.94883)
		(stroke
			(width 0.2)
			(type default)
		)
		(layer "In1.Cu")
	)
	(gr_line
		(start 37.200078 0)
		(end 262.50011 0)
		(stroke
			(width 1.524)
			(type default)
		)
		(layer "In1.Cu")
	)
	(gr_line
		(start 37.33927 -492.349028)
		(end 37.33927 -491.231428)
		(stroke
			(width 0.2)
			(type default)
		)
		(layer "In1.Cu")
	)
	(gr_arc
		(start 37.33927 -491.231428)
		(mid 36.72713 -490.619288)
		(end 36.11499 -491.231428)
		(stroke
			(width 0.2)
			(type default)
		)
		(layer "In1.Cu")
	)
	(gr_line
		(start 37.33927 -487.548936)
		(end 37.33927 -486.43159)
		(stroke
			(width 0.2)
			(type default)
		)
		(layer "In1.Cu")
	)
	(gr_arc
		(start 37.33927 -486.43159)
		(mid 36.727257 -485.819196)
		(end 36.11499 -486.431336)
		(stroke
			(width 0.2)
			(type default)
		)
		(layer "In1.Cu")
	)
	(gr_line
		(start 37.33927 -482.748844)
		(end 37.33927 -481.631244)
		(stroke
			(width 0.2)
			(type default)
		)
		(layer "In1.Cu")
	)
	(gr_arc
		(start 37.33927 -481.631244)
		(mid 36.72713 -481.019104)
		(end 36.11499 -481.631244)
		(stroke
			(width 0.2)
			(type default)
		)
		(layer "In1.Cu")
	)
	(gr_line
		(start 37.33927 -469.949022)
		(end 37.33927 -468.831422)
		(stroke
			(width 0.2)
			(type default)
		)
		(layer "In1.Cu")
	)
	(gr_arc
		(start 37.33927 -468.831422)
		(mid 36.72713 -468.219282)
		(end 36.11499 -468.831422)
		(stroke
			(width 0.2)
			(type default)
		)
		(layer "In1.Cu")
	)
	(gr_line
		(start 37.33927 -389.34898)
		(end 37.33927 -388.231634)
		(stroke
			(width 0.2)
			(type default)
		)
		(layer "In1.Cu")
	)
	(gr_arc
		(start 37.33927 -388.231634)
		(mid 36.727257 -387.61924)
		(end 36.11499 -388.23138)
		(stroke
			(width 0.2)
			(type default)
		)
		(layer "In1.Cu")
	)
	(gr_line
		(start 37.33927 -384.548888)
		(end 37.33927 -383.431542)
		(stroke
			(width 0.2)
			(type default)
		)
		(layer "In1.Cu")
	)
	(gr_arc
		(start 37.33927 -383.431542)
		(mid 36.727257 -382.819148)
		(end 36.11499 -383.431288)
		(stroke
			(width 0.2)
			(type default)
		)
		(layer "In1.Cu")
	)
	(gr_line
		(start 37.33927 -379.748796)
		(end 37.33927 -378.63145)
		(stroke
			(width 0.2)
			(type default)
		)
		(layer "In1.Cu")
	)
	(gr_arc
		(start 37.33927 -378.63145)
		(mid 36.727257 -378.019056)
		(end 36.11499 -378.631196)
		(stroke
			(width 0.2)
			(type default)
		)
		(layer "In1.Cu")
	)
	(gr_line
		(start 37.33927 -366.948974)
		(end 37.33927 -365.831628)
		(stroke
			(width 0.2)
			(type default)
		)
		(layer "In1.Cu")
	)
	(gr_arc
		(start 37.33927 -365.831628)
		(mid 36.727257 -365.219234)
		(end 36.11499 -365.831374)
		(stroke
			(width 0.2)
			(type default)
		)
		(layer "In1.Cu")
	)
	(gr_line
		(start 37.33927 -286.348932)
		(end 37.33927 -285.231586)
		(stroke
			(width 0.2)
			(type default)
		)
		(layer "In1.Cu")
	)
	(gr_arc
		(start 37.33927 -285.231586)
		(mid 36.727257 -284.619192)
		(end 36.11499 -285.231332)
		(stroke
			(width 0.2)
			(type default)
		)
		(layer "In1.Cu")
	)
	(gr_line
		(start 37.33927 -281.54884)
		(end 37.33927 -280.431494)
		(stroke
			(width 0.2)
			(type default)
		)
		(layer "In1.Cu")
	)
	(gr_arc
		(start 37.33927 -280.431494)
		(mid 36.727257 -279.8191)
		(end 36.11499 -280.43124)
		(stroke
			(width 0.2)
			(type default)
		)
		(layer "In1.Cu")
	)
	(gr_line
		(start 37.33927 -276.748748)
		(end 37.33927 -275.631402)
		(stroke
			(width 0.2)
			(type default)
		)
		(layer "In1.Cu")
	)
	(gr_arc
		(start 37.33927 -275.631402)
		(mid 36.727257 -275.019008)
		(end 36.11499 -275.631148)
		(stroke
			(width 0.2)
			(type default)
		)
		(layer "In1.Cu")
	)
	(gr_line
		(start 37.33927 -263.948926)
		(end 37.33927 -262.83158)
		(stroke
			(width 0.2)
			(type default)
		)
		(layer "In1.Cu")
	)
	(gr_arc
		(start 37.33927 -262.83158)
		(mid 36.727257 -262.219186)
		(end 36.11499 -262.831326)
		(stroke
			(width 0.2)
			(type default)
		)
		(layer "In1.Cu")
	)
	(gr_line
		(start 37.33927 -183.348884)
		(end 37.33927 -182.231538)
		(stroke
			(width 0.2)
			(type default)
		)
		(layer "In1.Cu")
	)
	(gr_arc
		(start 37.33927 -182.231538)
		(mid 36.727257 -181.619144)
		(end 36.11499 -182.231284)
		(stroke
			(width 0.2)
			(type default)
		)
		(layer "In1.Cu")
	)
	(gr_line
		(start 37.33927 -178.548792)
		(end 37.33927 -177.431446)
		(stroke
			(width 0.2)
			(type default)
		)
		(layer "In1.Cu")
	)
	(gr_arc
		(start 37.33927 -177.431446)
		(mid 36.727257 -176.819052)
		(end 36.11499 -177.431192)
		(stroke
			(width 0.2)
			(type default)
		)
		(layer "In1.Cu")
	)
	(gr_line
		(start 37.33927 -173.7487)
		(end 37.33927 -172.631354)
		(stroke
			(width 0.2)
			(type default)
		)
		(layer "In1.Cu")
	)
	(gr_arc
		(start 37.33927 -172.631354)
		(mid 36.727257 -172.01896)
		(end 36.11499 -172.6311)
		(stroke
			(width 0.2)
			(type default)
		)
		(layer "In1.Cu")
	)
	(gr_line
		(start 37.33927 -160.948878)
		(end 37.33927 -159.831532)
		(stroke
			(width 0.2)
			(type default)
		)
		(layer "In1.Cu")
	)
	(gr_arc
		(start 37.33927 -159.831532)
		(mid 36.727257 -159.219138)
		(end 36.11499 -159.831278)
		(stroke
			(width 0.2)
			(type default)
		)
		(layer "In1.Cu")
	)
	(gr_line
		(start 37.33927 -80.348836)
		(end 37.33927 -79.23149)
		(stroke
			(width 0.2)
			(type default)
		)
		(layer "In1.Cu")
	)
	(gr_arc
		(start 37.33927 -79.23149)
		(mid 36.727257 -78.619096)
		(end 36.11499 -79.231236)
		(stroke
			(width 0.2)
			(type default)
		)
		(layer "In1.Cu")
	)
	(gr_line
		(start 37.33927 -75.548744)
		(end 37.33927 -74.431398)
		(stroke
			(width 0.2)
			(type default)
		)
		(layer "In1.Cu")
	)
	(gr_arc
		(start 37.33927 -74.431398)
		(mid 36.727257 -73.819004)
		(end 36.11499 -74.431144)
		(stroke
			(width 0.2)
			(type default)
		)
		(layer "In1.Cu")
	)
	(gr_line
		(start 37.33927 -70.748652)
		(end 37.33927 -69.631306)
		(stroke
			(width 0.2)
			(type default)
		)
		(layer "In1.Cu")
	)
	(gr_arc
		(start 37.33927 -69.631306)
		(mid 36.727257 -69.018912)
		(end 36.11499 -69.631052)
		(stroke
			(width 0.2)
			(type default)
		)
		(layer "In1.Cu")
	)
	(gr_line
		(start 37.33927 -57.94883)
		(end 37.33927 -56.831484)
		(stroke
			(width 0.2)
			(type default)
		)
		(layer "In1.Cu")
	)
	(gr_arc
		(start 37.33927 -56.831484)
		(mid 36.727257 -56.21909)
		(end 36.11499 -56.83123)
		(stroke
			(width 0.2)
			(type default)
		)
		(layer "In1.Cu")
	)
	(gr_line
		(start 38.196774 -492.736124)
		(end 40.203374 -492.736124)
		(stroke
			(width 0.2)
			(type default)
		)
		(layer "In1.Cu")
	)
	(gr_line
		(start 38.196774 -490.844078)
		(end 38.196774 -492.736124)
		(stroke
			(width 0.2)
			(type default)
		)
		(layer "In1.Cu")
	)
	(gr_line
		(start 38.196774 -490.336332)
		(end 40.203374 -490.336332)
		(stroke
			(width 0.2)
			(type default)
		)
		(layer "In1.Cu")
	)
	(gr_line
		(start 38.196774 -488.444032)
		(end 38.196774 -490.336332)
		(stroke
			(width 0.2)
			(type default)
		)
		(layer "In1.Cu")
	)
	(gr_line
		(start 38.196774 -487.936286)
		(end 40.203374 -487.936286)
		(stroke
			(width 0.2)
			(type default)
		)
		(layer "In1.Cu")
	)
	(gr_line
		(start 38.196774 -486.043986)
		(end 38.196774 -487.936286)
		(stroke
			(width 0.2)
			(type default)
		)
		(layer "In1.Cu")
	)
	(gr_line
		(start 38.196774 -485.535986)
		(end 38.197028 -485.53624)
		(stroke
			(width 0.2)
			(type default)
		)
		(layer "In1.Cu")
	)
	(gr_line
		(start 38.196774 -483.64394)
		(end 38.196774 -485.535986)
		(stroke
			(width 0.2)
			(type default)
		)
		(layer "In1.Cu")
	)
	(gr_line
		(start 38.196774 -483.136194)
		(end 40.203374 -483.136194)
		(stroke
			(width 0.2)
			(type default)
		)
		(layer "In1.Cu")
	)
	(gr_line
		(start 38.196774 -481.243894)
		(end 38.196774 -483.136194)
		(stroke
			(width 0.2)
			(type default)
		)
		(layer "In1.Cu")
	)
	(gr_line
		(start 38.196774 -480.736148)
		(end 40.203374 -480.736148)
		(stroke
			(width 0.2)
			(type default)
		)
		(layer "In1.Cu")
	)
	(gr_line
		(start 38.196774 -478.844102)
		(end 38.196774 -480.736148)
		(stroke
			(width 0.2)
			(type default)
		)
		(layer "In1.Cu")
	)
	(gr_line
		(start 38.196774 -470.336118)
		(end 40.203374 -470.336118)
		(stroke
			(width 0.2)
			(type default)
		)
		(layer "In1.Cu")
	)
	(gr_line
		(start 38.196774 -468.444072)
		(end 38.196774 -470.336118)
		(stroke
			(width 0.2)
			(type default)
		)
		(layer "In1.Cu")
	)
	(gr_line
		(start 38.196774 -467.936326)
		(end 40.203374 -467.936326)
		(stroke
			(width 0.2)
			(type default)
		)
		(layer "In1.Cu")
	)
	(gr_line
		(start 38.196774 -466.044026)
		(end 38.196774 -467.936326)
		(stroke
			(width 0.2)
			(type default)
		)
		(layer "In1.Cu")
	)
	(gr_line
		(start 38.196774 -465.53628)
		(end 40.203374 -465.53628)
		(stroke
			(width 0.2)
			(type default)
		)
		(layer "In1.Cu")
	)
	(gr_line
		(start 38.196774 -463.64398)
		(end 38.196774 -465.53628)
		(stroke
			(width 0.2)
			(type default)
		)
		(layer "In1.Cu")
	)
	(gr_line
		(start 38.196774 -389.736076)
		(end 40.203374 -389.736076)
		(stroke
			(width 0.2)
			(type default)
		)
		(layer "In1.Cu")
	)
	(gr_line
		(start 38.196774 -387.84403)
		(end 38.196774 -389.736076)
		(stroke
			(width 0.2)
			(type default)
		)
		(layer "In1.Cu")
	)
	(gr_line
		(start 38.196774 -387.336284)
		(end 40.203374 -387.336284)
		(stroke
			(width 0.2)
			(type default)
		)
		(layer "In1.Cu")
	)
	(gr_line
		(start 38.196774 -385.443984)
		(end 38.196774 -387.336284)
		(stroke
			(width 0.2)
			(type default)
		)
		(layer "In1.Cu")
	)
	(gr_line
		(start 38.196774 -384.936238)
		(end 40.203374 -384.936238)
		(stroke
			(width 0.2)
			(type default)
		)
		(layer "In1.Cu")
	)
	(gr_line
		(start 38.196774 -383.043938)
		(end 38.196774 -384.936238)
		(stroke
			(width 0.2)
			(type default)
		)
		(layer "In1.Cu")
	)
	(gr_line
		(start 38.196774 -382.536192)
		(end 40.203374 -382.536192)
		(stroke
			(width 0.2)
			(type default)
		)
		(layer "In1.Cu")
	)
	(gr_line
		(start 38.196774 -380.643892)
		(end 38.196774 -382.536192)
		(stroke
			(width 0.2)
			(type default)
		)
		(layer "In1.Cu")
	)
	(gr_line
		(start 38.196774 -380.136146)
		(end 40.203374 -380.136146)
		(stroke
			(width 0.2)
			(type default)
		)
		(layer "In1.Cu")
	)
	(gr_line
		(start 38.196774 -378.243846)
		(end 38.196774 -380.136146)
		(stroke
			(width 0.2)
			(type default)
		)
		(layer "In1.Cu")
	)
	(gr_line
		(start 38.196774 -377.7361)
		(end 40.203374 -377.7361)
		(stroke
			(width 0.2)
			(type default)
		)
		(layer "In1.Cu")
	)
	(gr_line
		(start 38.196774 -375.844054)
		(end 38.196774 -377.7361)
		(stroke
			(width 0.2)
			(type default)
		)
		(layer "In1.Cu")
	)
	(gr_line
		(start 38.196774 -367.33607)
		(end 40.203374 -367.33607)
		(stroke
			(width 0.2)
			(type default)
		)
		(layer "In1.Cu")
	)
	(gr_line
		(start 38.196774 -365.444024)
		(end 38.196774 -367.33607)
		(stroke
			(width 0.2)
			(type default)
		)
		(layer "In1.Cu")
	)
	(gr_line
		(start 38.196774 -364.936278)
		(end 40.203374 -364.936278)
		(stroke
			(width 0.2)
			(type default)
		)
		(layer "In1.Cu")
	)
	(gr_line
		(start 38.196774 -363.043978)
		(end 38.196774 -364.936278)
		(stroke
			(width 0.2)
			(type default)
		)
		(layer "In1.Cu")
	)
	(gr_line
		(start 38.196774 -362.536232)
		(end 40.203374 -362.536232)
		(stroke
			(width 0.2)
			(type default)
		)
		(layer "In1.Cu")
	)
	(gr_line
		(start 38.196774 -360.643932)
		(end 38.196774 -362.536232)
		(stroke
			(width 0.2)
			(type default)
		)
		(layer "In1.Cu")
	)
	(gr_line
		(start 38.196774 -286.736028)
		(end 40.203374 -286.736028)
		(stroke
			(width 0.2)
			(type default)
		)
		(layer "In1.Cu")
	)
	(gr_line
		(start 38.196774 -284.843982)
		(end 38.196774 -286.736028)
		(stroke
			(width 0.2)
			(type default)
		)
		(layer "In1.Cu")
	)
	(gr_line
		(start 38.196774 -284.336236)
		(end 40.203374 -284.336236)
		(stroke
			(width 0.2)
			(type default)
		)
		(layer "In1.Cu")
	)
	(gr_line
		(start 38.196774 -282.443936)
		(end 38.196774 -284.336236)
		(stroke
			(width 0.2)
			(type default)
		)
		(layer "In1.Cu")
	)
	(gr_line
		(start 38.196774 -281.93619)
		(end 40.203374 -281.93619)
		(stroke
			(width 0.2)
			(type default)
		)
		(layer "In1.Cu")
	)
	(gr_line
		(start 38.196774 -280.04389)
		(end 38.196774 -281.93619)
		(stroke
			(width 0.2)
			(type default)
		)
		(layer "In1.Cu")
	)
	(gr_line
		(start 38.196774 -279.536144)
		(end 40.203374 -279.536144)
		(stroke
			(width 0.2)
			(type default)
		)
		(layer "In1.Cu")
	)
	(gr_line
		(start 38.196774 -277.643844)
		(end 38.196774 -279.536144)
		(stroke
			(width 0.2)
			(type default)
		)
		(layer "In1.Cu")
	)
	(gr_line
		(start 38.196774 -277.136098)
		(end 40.203374 -277.136098)
		(stroke
			(width 0.2)
			(type default)
		)
		(layer "In1.Cu")
	)
	(gr_line
		(start 38.196774 -275.243798)
		(end 38.196774 -277.136098)
		(stroke
			(width 0.2)
			(type default)
		)
		(layer "In1.Cu")
	)
	(gr_line
		(start 38.196774 -274.736052)
		(end 40.203374 -274.736052)
		(stroke
			(width 0.2)
			(type default)
		)
		(layer "In1.Cu")
	)
	(gr_line
		(start 38.196774 -272.844006)
		(end 38.196774 -274.736052)
		(stroke
			(width 0.2)
			(type default)
		)
		(layer "In1.Cu")
	)
	(gr_line
		(start 38.196774 -264.335768)
		(end 38.197028 -264.336022)
		(stroke
			(width 0.2)
			(type default)
		)
		(layer "In1.Cu")
	)
	(gr_line
		(start 38.196774 -262.443976)
		(end 38.196774 -264.335768)
		(stroke
			(width 0.2)
			(type default)
		)
		(layer "In1.Cu")
	)
	(gr_line
		(start 38.196774 -261.93623)
		(end 40.203374 -261.93623)
		(stroke
			(width 0.2)
			(type default)
		)
		(layer "In1.Cu")
	)
	(gr_line
		(start 38.196774 -260.04393)
		(end 38.196774 -261.93623)
		(stroke
			(width 0.2)
			(type default)
		)
		(layer "In1.Cu")
	)
	(gr_line
		(start 38.196774 -259.536184)
		(end 40.203374 -259.536184)
		(stroke
			(width 0.2)
			(type default)
		)
		(layer "In1.Cu")
	)
	(gr_line
		(start 38.196774 -257.643884)
		(end 38.196774 -259.536184)
		(stroke
			(width 0.2)
			(type default)
		)
		(layer "In1.Cu")
	)
	(gr_line
		(start 38.196774 -183.73598)
		(end 40.203374 -183.73598)
		(stroke
			(width 0.2)
			(type default)
		)
		(layer "In1.Cu")
	)
	(gr_line
		(start 38.196774 -181.843934)
		(end 38.196774 -183.73598)
		(stroke
			(width 0.2)
			(type default)
		)
		(layer "In1.Cu")
	)
	(gr_line
		(start 38.196774 -181.336188)
		(end 40.203374 -181.336188)
		(stroke
			(width 0.2)
			(type default)
		)
		(layer "In1.Cu")
	)
	(gr_line
		(start 38.196774 -179.443888)
		(end 38.196774 -181.336188)
		(stroke
			(width 0.2)
			(type default)
		)
		(layer "In1.Cu")
	)
	(gr_line
		(start 38.196774 -178.936142)
		(end 40.203374 -178.936142)
		(stroke
			(width 0.2)
			(type default)
		)
		(layer "In1.Cu")
	)
	(gr_line
		(start 38.196774 -177.043842)
		(end 38.196774 -178.936142)
		(stroke
			(width 0.2)
			(type default)
		)
		(layer "In1.Cu")
	)
	(gr_line
		(start 38.196774 -176.536096)
		(end 40.203374 -176.536096)
		(stroke
			(width 0.2)
			(type default)
		)
		(layer "In1.Cu")
	)
	(gr_line
		(start 38.196774 -174.643796)
		(end 38.196774 -176.536096)
		(stroke
			(width 0.2)
			(type default)
		)
		(layer "In1.Cu")
	)
	(gr_line
		(start 38.196774 -174.13605)
		(end 40.203374 -174.13605)
		(stroke
			(width 0.2)
			(type default)
		)
		(layer "In1.Cu")
	)
	(gr_line
		(start 38.196774 -172.24375)
		(end 38.196774 -174.13605)
		(stroke
			(width 0.2)
			(type default)
		)
		(layer "In1.Cu")
	)
	(gr_line
		(start 38.196774 -171.736004)
		(end 40.203374 -171.736004)
		(stroke
			(width 0.2)
			(type default)
		)
		(layer "In1.Cu")
	)
	(gr_line
		(start 38.196774 -169.843958)
		(end 38.196774 -171.736004)
		(stroke
			(width 0.2)
			(type default)
		)
		(layer "In1.Cu")
	)
	(gr_line
		(start 38.196774 -161.335974)
		(end 40.203374 -161.335974)
		(stroke
			(width 0.2)
			(type default)
		)
		(layer "In1.Cu")
	)
	(gr_line
		(start 38.196774 -159.443928)
		(end 38.196774 -161.335974)
		(stroke
			(width 0.2)
			(type default)
		)
		(layer "In1.Cu")
	)
	(gr_line
		(start 38.196774 -158.936182)
		(end 40.203374 -158.936182)
		(stroke
			(width 0.2)
			(type default)
		)
		(layer "In1.Cu")
	)
	(gr_line
		(start 38.196774 -157.043882)
		(end 38.196774 -158.936182)
		(stroke
			(width 0.2)
			(type default)
		)
		(layer "In1.Cu")
	)
	(gr_line
		(start 38.196774 -156.536136)
		(end 40.203374 -156.536136)
		(stroke
			(width 0.2)
			(type default)
		)
		(layer "In1.Cu")
	)
	(gr_line
		(start 38.196774 -154.643836)
		(end 38.196774 -156.536136)
		(stroke
			(width 0.2)
			(type default)
		)
		(layer "In1.Cu")
	)
	(gr_line
		(start 38.196774 -80.735932)
		(end 40.203374 -80.735932)
		(stroke
			(width 0.2)
			(type default)
		)
		(layer "In1.Cu")
	)
	(gr_line
		(start 38.196774 -78.843886)
		(end 38.196774 -80.735932)
		(stroke
			(width 0.2)
			(type default)
		)
		(layer "In1.Cu")
	)
	(gr_line
		(start 38.196774 -78.33614)
		(end 40.203374 -78.33614)
		(stroke
			(width 0.2)
			(type default)
		)
		(layer "In1.Cu")
	)
	(gr_line
		(start 38.196774 -76.44384)
		(end 38.196774 -78.33614)
		(stroke
			(width 0.2)
			(type default)
		)
		(layer "In1.Cu")
	)
	(gr_line
		(start 38.196774 -75.936094)
		(end 40.203374 -75.936094)
		(stroke
			(width 0.2)
			(type default)
		)
		(layer "In1.Cu")
	)
	(gr_line
		(start 38.196774 -74.043794)
		(end 38.196774 -75.936094)
		(stroke
			(width 0.2)
			(type default)
		)
		(layer "In1.Cu")
	)
	(gr_line
		(start 38.196774 -73.536048)
		(end 40.203374 -73.536048)
		(stroke
			(width 0.2)
			(type default)
		)
		(layer "In1.Cu")
	)
	(gr_line
		(start 38.196774 -71.643748)
		(end 38.196774 -73.536048)
		(stroke
			(width 0.2)
			(type default)
		)
		(layer "In1.Cu")
	)
	(gr_line
		(start 38.196774 -71.136002)
		(end 40.203374 -71.136002)
		(stroke
			(width 0.2)
			(type default)
		)
		(layer "In1.Cu")
	)
	(gr_line
		(start 38.196774 -69.243702)
		(end 38.196774 -71.136002)
		(stroke
			(width 0.2)
			(type default)
		)
		(layer "In1.Cu")
	)
	(gr_line
		(start 38.196774 -68.735956)
		(end 40.203374 -68.735956)
		(stroke
			(width 0.2)
			(type default)
		)
		(layer "In1.Cu")
	)
	(gr_line
		(start 38.196774 -66.84391)
		(end 38.196774 -68.735956)
		(stroke
			(width 0.2)
			(type default)
		)
		(layer "In1.Cu")
	)
	(gr_line
		(start 38.196774 -58.335926)
		(end 40.203374 -58.335926)
		(stroke
			(width 0.2)
			(type default)
		)
		(layer "In1.Cu")
	)
	(gr_line
		(start 38.196774 -56.44388)
		(end 38.196774 -58.335926)
		(stroke
			(width 0.2)
			(type default)
		)
		(layer "In1.Cu")
	)
	(gr_line
		(start 38.196774 -55.936134)
		(end 40.203374 -55.936134)
		(stroke
			(width 0.2)
			(type default)
		)
		(layer "In1.Cu")
	)
	(gr_line
		(start 38.196774 -54.043834)
		(end 38.196774 -55.936134)
		(stroke
			(width 0.2)
			(type default)
		)
		(layer "In1.Cu")
	)
	(gr_line
		(start 38.196774 -53.536088)
		(end 40.203374 -53.536088)
		(stroke
			(width 0.2)
			(type default)
		)
		(layer "In1.Cu")
	)
	(gr_line
		(start 38.196774 -51.643788)
		(end 38.196774 -53.536088)
		(stroke
			(width 0.2)
			(type default)
		)
		(layer "In1.Cu")
	)
	(gr_line
		(start 38.197028 -485.53624)
		(end 40.203374 -485.53624)
		(stroke
			(width 0.2)
			(type default)
		)
		(layer "In1.Cu")
	)
	(gr_line
		(start 38.197028 -264.336022)
		(end 40.203374 -264.336022)
		(stroke
			(width 0.2)
			(type default)
		)
		(layer "In1.Cu")
	)
	(gr_line
		(start 40.20312 -490.844078)
		(end 38.196774 -490.844078)
		(stroke
			(width 0.2)
			(type default)
		)
		(layer "In1.Cu")
	)
	(gr_line
		(start 40.20312 -488.444032)
		(end 38.196774 -488.444032)
		(stroke
			(width 0.2)
			(type default)
		)
		(layer "In1.Cu")
	)
	(gr_line
		(start 40.20312 -486.043986)
		(end 38.196774 -486.043986)
		(stroke
			(width 0.2)
			(type default)
		)
		(layer "In1.Cu")
	)
	(gr_line
		(start 40.20312 -481.243894)
		(end 38.196774 -481.243894)
		(stroke
			(width 0.2)
			(type default)
		)
		(layer "In1.Cu")
	)
	(gr_line
		(start 40.20312 -478.844102)
		(end 38.196774 -478.844102)
		(stroke
			(width 0.2)
			(type default)
		)
		(layer "In1.Cu")
	)
	(gr_line
		(start 40.20312 -468.444072)
		(end 38.196774 -468.444072)
		(stroke
			(width 0.2)
			(type default)
		)
		(layer "In1.Cu")
	)
	(gr_line
		(start 40.20312 -466.044026)
		(end 38.196774 -466.044026)
		(stroke
			(width 0.2)
			(type default)
		)
		(layer "In1.Cu")
	)
	(gr_line
		(start 40.20312 -463.64398)
		(end 38.196774 -463.64398)
		(stroke
			(width 0.2)
			(type default)
		)
		(layer "In1.Cu")
	)
	(gr_line
		(start 40.20312 -387.84403)
		(end 38.196774 -387.84403)
		(stroke
			(width 0.2)
			(type default)
		)
		(layer "In1.Cu")
	)
	(gr_line
		(start 40.20312 -385.443984)
		(end 38.196774 -385.443984)
		(stroke
			(width 0.2)
			(type default)
		)
		(layer "In1.Cu")
	)
	(gr_line
		(start 40.20312 -383.043938)
		(end 38.196774 -383.043938)
		(stroke
			(width 0.2)
			(type default)
		)
		(layer "In1.Cu")
	)
	(gr_line
		(start 40.20312 -380.643892)
		(end 38.196774 -380.643892)
		(stroke
			(width 0.2)
			(type default)
		)
		(layer "In1.Cu")
	)
	(gr_line
		(start 40.20312 -378.243846)
		(end 38.196774 -378.243846)
		(stroke
			(width 0.2)
			(type default)
		)
		(layer "In1.Cu")
	)
	(gr_line
		(start 40.20312 -375.844054)
		(end 38.196774 -375.844054)
		(stroke
			(width 0.2)
			(type default)
		)
		(layer "In1.Cu")
	)
	(gr_line
		(start 40.20312 -365.444024)
		(end 38.196774 -365.444024)
		(stroke
			(width 0.2)
			(type default)
		)
		(layer "In1.Cu")
	)
	(gr_line
		(start 40.20312 -363.043978)
		(end 38.196774 -363.043978)
		(stroke
			(width 0.2)
			(type default)
		)
		(layer "In1.Cu")
	)
	(gr_line
		(start 40.20312 -360.643932)
		(end 38.196774 -360.643932)
		(stroke
			(width 0.2)
			(type default)
		)
		(layer "In1.Cu")
	)
	(gr_line
		(start 40.20312 -284.843982)
		(end 38.196774 -284.843982)
		(stroke
			(width 0.2)
			(type default)
		)
		(layer "In1.Cu")
	)
	(gr_line
		(start 40.20312 -282.443936)
		(end 38.196774 -282.443936)
		(stroke
			(width 0.2)
			(type default)
		)
		(layer "In1.Cu")
	)
	(gr_line
		(start 40.20312 -280.04389)
		(end 38.196774 -280.04389)
		(stroke
			(width 0.2)
			(type default)
		)
		(layer "In1.Cu")
	)
	(gr_line
		(start 40.20312 -277.643844)
		(end 38.196774 -277.643844)
		(stroke
			(width 0.2)
			(type default)
		)
		(layer "In1.Cu")
	)
	(gr_line
		(start 40.20312 -275.243798)
		(end 38.196774 -275.243798)
		(stroke
			(width 0.2)
			(type default)
		)
		(layer "In1.Cu")
	)
	(gr_line
		(start 40.20312 -272.844006)
		(end 38.196774 -272.844006)
		(stroke
			(width 0.2)
			(type default)
		)
		(layer "In1.Cu")
	)
	(gr_line
		(start 40.20312 -260.04393)
		(end 38.196774 -260.04393)
		(stroke
			(width 0.2)
			(type default)
		)
		(layer "In1.Cu")
	)
	(gr_line
		(start 40.20312 -257.643884)
		(end 38.196774 -257.643884)
		(stroke
			(width 0.2)
			(type default)
		)
		(layer "In1.Cu")
	)
	(gr_line
		(start 40.20312 -181.843934)
		(end 38.196774 -181.843934)
		(stroke
			(width 0.2)
			(type default)
		)
		(layer "In1.Cu")
	)
	(gr_line
		(start 40.20312 -179.443888)
		(end 38.196774 -179.443888)
		(stroke
			(width 0.2)
			(type default)
		)
		(layer "In1.Cu")
	)
	(gr_line
		(start 40.20312 -177.043842)
		(end 38.196774 -177.043842)
		(stroke
			(width 0.2)
			(type default)
		)
		(layer "In1.Cu")
	)
	(gr_line
		(start 40.20312 -174.643796)
		(end 38.196774 -174.643796)
		(stroke
			(width 0.2)
			(type default)
		)
		(layer "In1.Cu")
	)
	(gr_line
		(start 40.20312 -172.24375)
		(end 38.196774 -172.24375)
		(stroke
			(width 0.2)
			(type default)
		)
		(layer "In1.Cu")
	)
	(gr_line
		(start 40.20312 -169.843958)
		(end 38.196774 -169.843958)
		(stroke
			(width 0.2)
			(type default)
		)
		(layer "In1.Cu")
	)
	(gr_line
		(start 40.20312 -159.443928)
		(end 38.196774 -159.443928)
		(stroke
			(width 0.2)
			(type default)
		)
		(layer "In1.Cu")
	)
	(gr_line
		(start 40.20312 -157.043882)
		(end 38.196774 -157.043882)
		(stroke
			(width 0.2)
			(type default)
		)
		(layer "In1.Cu")
	)
	(gr_line
		(start 40.20312 -154.643836)
		(end 38.196774 -154.643836)
		(stroke
			(width 0.2)
			(type default)
		)
		(layer "In1.Cu")
	)
	(gr_line
		(start 40.20312 -78.843886)
		(end 38.196774 -78.843886)
		(stroke
			(width 0.2)
			(type default)
		)
		(layer "In1.Cu")
	)
	(gr_line
		(start 40.20312 -76.44384)
		(end 38.196774 -76.44384)
		(stroke
			(width 0.2)
			(type default)
		)
		(layer "In1.Cu")
	)
	(gr_line
		(start 40.20312 -74.043794)
		(end 38.196774 -74.043794)
		(stroke
			(width 0.2)
			(type default)
		)
		(layer "In1.Cu")
	)
	(gr_line
		(start 40.20312 -71.643748)
		(end 38.196774 -71.643748)
		(stroke
			(width 0.2)
			(type default)
		)
		(layer "In1.Cu")
	)
	(gr_line
		(start 40.20312 -69.243702)
		(end 38.196774 -69.243702)
		(stroke
			(width 0.2)
			(type default)
		)
		(layer "In1.Cu")
	)
	(gr_line
		(start 40.20312 -66.84391)
		(end 38.196774 -66.84391)
		(stroke
			(width 0.2)
			(type default)
		)
		(layer "In1.Cu")
	)
	(gr_line
		(start 40.20312 -56.44388)
		(end 38.196774 -56.44388)
		(stroke
			(width 0.2)
			(type default)
		)
		(layer "In1.Cu")
	)
	(gr_line
		(start 40.20312 -54.043834)
		(end 38.196774 -54.043834)
		(stroke
			(width 0.2)
			(type default)
		)
		(layer "In1.Cu")
	)
	(gr_line
		(start 40.20312 -51.643788)
		(end 38.196774 -51.643788)
		(stroke
			(width 0.2)
			(type default)
		)
		(layer "In1.Cu")
	)
	(gr_line
		(start 40.203374 -492.736124)
		(end 40.203374 -490.844332)
		(stroke
			(width 0.2)
			(type default)
		)
		(layer "In1.Cu")
	)
	(gr_line
		(start 40.203374 -490.844332)
		(end 40.20312 -490.844078)
		(stroke
			(width 0.2)
			(type default)
		)
		(layer "In1.Cu")
	)
	(gr_line
		(start 40.203374 -490.336332)
		(end 40.203374 -488.444286)
		(stroke
			(width 0.2)
			(type default)
		)
		(layer "In1.Cu")
	)
	(gr_line
		(start 40.203374 -488.444286)
		(end 40.20312 -488.444032)
		(stroke
			(width 0.2)
			(type default)
		)
		(layer "In1.Cu")
	)
	(gr_line
		(start 40.203374 -487.936286)
		(end 40.203374 -486.04424)
		(stroke
			(width 0.2)
			(type default)
		)
		(layer "In1.Cu")
	)
	(gr_line
		(start 40.203374 -486.04424)
		(end 40.20312 -486.043986)
		(stroke
			(width 0.2)
			(type default)
		)
		(layer "In1.Cu")
	)
	(gr_line
		(start 40.203374 -485.53624)
		(end 40.203374 -483.64394)
		(stroke
			(width 0.2)
			(type default)
		)
		(layer "In1.Cu")
	)
	(gr_line
		(start 40.203374 -483.64394)
		(end 38.196774 -483.64394)
		(stroke
			(width 0.2)
			(type default)
		)
		(layer "In1.Cu")
	)
	(gr_line
		(start 40.203374 -483.136194)
		(end 40.203374 -481.244148)
		(stroke
			(width 0.2)
			(type default)
		)
		(layer "In1.Cu")
	)
	(gr_line
		(start 40.203374 -481.244148)
		(end 40.20312 -481.243894)
		(stroke
			(width 0.2)
			(type default)
		)
		(layer "In1.Cu")
	)
	(gr_line
		(start 40.203374 -480.736148)
		(end 40.203374 -478.844356)
		(stroke
			(width 0.2)
			(type default)
		)
		(layer "In1.Cu")
	)
	(gr_line
		(start 40.203374 -478.844356)
		(end 40.20312 -478.844102)
		(stroke
			(width 0.2)
			(type default)
		)
		(layer "In1.Cu")
	)
	(gr_line
		(start 40.203374 -470.336118)
		(end 40.203374 -468.444326)
		(stroke
			(width 0.2)
			(type default)
		)
		(layer "In1.Cu")
	)
	(gr_line
		(start 40.203374 -468.444326)
		(end 40.20312 -468.444072)
		(stroke
			(width 0.2)
			(type default)
		)
		(layer "In1.Cu")
	)
	(gr_line
		(start 40.203374 -467.936326)
		(end 40.203374 -466.04428)
		(stroke
			(width 0.2)
			(type default)
		)
		(layer "In1.Cu")
	)
	(gr_line
		(start 40.203374 -466.04428)
		(end 40.20312 -466.044026)
		(stroke
			(width 0.2)
			(type default)
		)
		(layer "In1.Cu")
	)
	(gr_line
		(start 40.203374 -465.53628)
		(end 40.203374 -463.644234)
		(stroke
			(width 0.2)
			(type default)
		)
		(layer "In1.Cu")
	)
	(gr_line
		(start 40.203374 -463.644234)
		(end 40.20312 -463.64398)
		(stroke
			(width 0.2)
			(type default)
		)
		(layer "In1.Cu")
	)
	(gr_line
		(start 40.203374 -389.736076)
		(end 40.203374 -387.844284)
		(stroke
			(width 0.2)
			(type default)
		)
		(layer "In1.Cu")
	)
	(gr_line
		(start 40.203374 -387.844284)
		(end 40.20312 -387.84403)
		(stroke
			(width 0.2)
			(type default)
		)
		(layer "In1.Cu")
	)
	(gr_line
		(start 40.203374 -387.336284)
		(end 40.203374 -385.444238)
		(stroke
			(width 0.2)
			(type default)
		)
		(layer "In1.Cu")
	)
	(gr_line
		(start 40.203374 -385.444238)
		(end 40.20312 -385.443984)
		(stroke
			(width 0.2)
			(type default)
		)
		(layer "In1.Cu")
	)
	(gr_line
		(start 40.203374 -384.936238)
		(end 40.203374 -383.044192)
		(stroke
			(width 0.2)
			(type default)
		)
		(layer "In1.Cu")
	)
	(gr_line
		(start 40.203374 -383.044192)
		(end 40.20312 -383.043938)
		(stroke
			(width 0.2)
			(type default)
		)
		(layer "In1.Cu")
	)
	(gr_line
		(start 40.203374 -382.536192)
		(end 40.203374 -380.644146)
		(stroke
			(width 0.2)
			(type default)
		)
		(layer "In1.Cu")
	)
	(gr_line
		(start 40.203374 -380.644146)
		(end 40.20312 -380.643892)
		(stroke
			(width 0.2)
			(type default)
		)
		(layer "In1.Cu")
	)
	(gr_line
		(start 40.203374 -380.136146)
		(end 40.203374 -378.2441)
		(stroke
			(width 0.2)
			(type default)
		)
		(layer "In1.Cu")
	)
	(gr_line
		(start 40.203374 -378.2441)
		(end 40.20312 -378.243846)
		(stroke
			(width 0.2)
			(type default)
		)
		(layer "In1.Cu")
	)
	(gr_line
		(start 40.203374 -377.7361)
		(end 40.203374 -375.844308)
		(stroke
			(width 0.2)
			(type default)
		)
		(layer "In1.Cu")
	)
	(gr_line
		(start 40.203374 -375.844308)
		(end 40.20312 -375.844054)
		(stroke
			(width 0.2)
			(type default)
		)
		(layer "In1.Cu")
	)
	(gr_line
		(start 40.203374 -367.33607)
		(end 40.203374 -365.444278)
		(stroke
			(width 0.2)
			(type default)
		)
		(layer "In1.Cu")
	)
	(gr_line
		(start 40.203374 -365.444278)
		(end 40.20312 -365.444024)
		(stroke
			(width 0.2)
			(type default)
		)
		(layer "In1.Cu")
	)
	(gr_line
		(start 40.203374 -364.936278)
		(end 40.203374 -363.044232)
		(stroke
			(width 0.2)
			(type default)
		)
		(layer "In1.Cu")
	)
	(gr_line
		(start 40.203374 -363.044232)
		(end 40.20312 -363.043978)
		(stroke
			(width 0.2)
			(type default)
		)
		(layer "In1.Cu")
	)
	(gr_line
		(start 40.203374 -362.536232)
		(end 40.203374 -360.644186)
		(stroke
			(width 0.2)
			(type default)
		)
		(layer "In1.Cu")
	)
	(gr_line
		(start 40.203374 -360.644186)
		(end 40.20312 -360.643932)
		(stroke
			(width 0.2)
			(type default)
		)
		(layer "In1.Cu")
	)
	(gr_line
		(start 40.203374 -286.736028)
		(end 40.203374 -284.844236)
		(stroke
			(width 0.2)
			(type default)
		)
		(layer "In1.Cu")
	)
	(gr_line
		(start 40.203374 -284.844236)
		(end 40.20312 -284.843982)
		(stroke
			(width 0.2)
			(type default)
		)
		(layer "In1.Cu")
	)
	(gr_line
		(start 40.203374 -284.336236)
		(end 40.203374 -282.44419)
		(stroke
			(width 0.2)
			(type default)
		)
		(layer "In1.Cu")
	)
	(gr_line
		(start 40.203374 -282.44419)
		(end 40.20312 -282.443936)
		(stroke
			(width 0.2)
			(type default)
		)
		(layer "In1.Cu")
	)
	(gr_line
		(start 40.203374 -281.93619)
		(end 40.203374 -280.044144)
		(stroke
			(width 0.2)
			(type default)
		)
		(layer "In1.Cu")
	)
	(gr_line
		(start 40.203374 -280.044144)
		(end 40.20312 -280.04389)
		(stroke
			(width 0.2)
			(type default)
		)
		(layer "In1.Cu")
	)
	(gr_line
		(start 40.203374 -279.536144)
		(end 40.203374 -277.644098)
		(stroke
			(width 0.2)
			(type default)
		)
		(layer "In1.Cu")
	)
	(gr_line
		(start 40.203374 -277.644098)
		(end 40.20312 -277.643844)
		(stroke
			(width 0.2)
			(type default)
		)
		(layer "In1.Cu")
	)
	(gr_line
		(start 40.203374 -277.136098)
		(end 40.203374 -275.244052)
		(stroke
			(width 0.2)
			(type default)
		)
		(layer "In1.Cu")
	)
	(gr_line
		(start 40.203374 -275.244052)
		(end 40.20312 -275.243798)
		(stroke
			(width 0.2)
			(type default)
		)
		(layer "In1.Cu")
	)
	(gr_line
		(start 40.203374 -274.736052)
		(end 40.203374 -272.84426)
		(stroke
			(width 0.2)
			(type default)
		)
		(layer "In1.Cu")
	)
	(gr_line
		(start 40.203374 -272.84426)
		(end 40.20312 -272.844006)
		(stroke
			(width 0.2)
			(type default)
		)
		(layer "In1.Cu")
	)
	(gr_line
		(start 40.203374 -264.336022)
		(end 40.203374 -262.443976)
		(stroke
			(width 0.2)
			(type default)
		)
		(layer "In1.Cu")
	)
	(gr_line
		(start 40.203374 -262.443976)
		(end 38.196774 -262.443976)
		(stroke
			(width 0.2)
			(type default)
		)
		(layer "In1.Cu")
	)
	(gr_line
		(start 40.203374 -261.93623)
		(end 40.203374 -260.044184)
		(stroke
			(width 0.2)
			(type default)
		)
		(layer "In1.Cu")
	)
	(gr_line
		(start 40.203374 -260.044184)
		(end 40.20312 -260.04393)
		(stroke
			(width 0.2)
			(type default)
		)
		(layer "In1.Cu")
	)
	(gr_line
		(start 40.203374 -259.536184)
		(end 40.203374 -257.644138)
		(stroke
			(width 0.2)
			(type default)
		)
		(layer "In1.Cu")
	)
	(gr_line
		(start 40.203374 -257.644138)
		(end 40.20312 -257.643884)
		(stroke
			(width 0.2)
			(type default)
		)
		(layer "In1.Cu")
	)
	(gr_line
		(start 40.203374 -183.73598)
		(end 40.203374 -181.844188)
		(stroke
			(width 0.2)
			(type default)
		)
		(layer "In1.Cu")
	)
	(gr_line
		(start 40.203374 -181.844188)
		(end 40.20312 -181.843934)
		(stroke
			(width 0.2)
			(type default)
		)
		(layer "In1.Cu")
	)
	(gr_line
		(start 40.203374 -181.336188)
		(end 40.203374 -179.444142)
		(stroke
			(width 0.2)
			(type default)
		)
		(layer "In1.Cu")
	)
	(gr_line
		(start 40.203374 -179.444142)
		(end 40.20312 -179.443888)
		(stroke
			(width 0.2)
			(type default)
		)
		(layer "In1.Cu")
	)
	(gr_line
		(start 40.203374 -178.936142)
		(end 40.203374 -177.044096)
		(stroke
			(width 0.2)
			(type default)
		)
		(layer "In1.Cu")
	)
	(gr_line
		(start 40.203374 -177.044096)
		(end 40.20312 -177.043842)
		(stroke
			(width 0.2)
			(type default)
		)
		(layer "In1.Cu")
	)
	(gr_line
		(start 40.203374 -176.536096)
		(end 40.203374 -174.64405)
		(stroke
			(width 0.2)
			(type default)
		)
		(layer "In1.Cu")
	)
	(gr_line
		(start 40.203374 -174.64405)
		(end 40.20312 -174.643796)
		(stroke
			(width 0.2)
			(type default)
		)
		(layer "In1.Cu")
	)
	(gr_line
		(start 40.203374 -174.13605)
		(end 40.203374 -172.244004)
		(stroke
			(width 0.2)
			(type default)
		)
		(layer "In1.Cu")
	)
	(gr_line
		(start 40.203374 -172.244004)
		(end 40.20312 -172.24375)
		(stroke
			(width 0.2)
			(type default)
		)
		(layer "In1.Cu")
	)
	(gr_line
		(start 40.203374 -171.736004)
		(end 40.203374 -169.844212)
		(stroke
			(width 0.2)
			(type default)
		)
		(layer "In1.Cu")
	)
	(gr_line
		(start 40.203374 -169.844212)
		(end 40.20312 -169.843958)
		(stroke
			(width 0.2)
			(type default)
		)
		(layer "In1.Cu")
	)
	(gr_line
		(start 40.203374 -161.335974)
		(end 40.203374 -159.444182)
		(stroke
			(width 0.2)
			(type default)
		)
		(layer "In1.Cu")
	)
	(gr_line
		(start 40.203374 -159.444182)
		(end 40.20312 -159.443928)
		(stroke
			(width 0.2)
			(type default)
		)
		(layer "In1.Cu")
	)
	(gr_line
		(start 40.203374 -158.936182)
		(end 40.203374 -157.044136)
		(stroke
			(width 0.2)
			(type default)
		)
		(layer "In1.Cu")
	)
	(gr_line
		(start 40.203374 -157.044136)
		(end 40.20312 -157.043882)
		(stroke
			(width 0.2)
			(type default)
		)
		(layer "In1.Cu")
	)
	(gr_line
		(start 40.203374 -156.536136)
		(end 40.203374 -154.64409)
		(stroke
			(width 0.2)
			(type default)
		)
		(layer "In1.Cu")
	)
	(gr_line
		(start 40.203374 -154.64409)
		(end 40.20312 -154.643836)
		(stroke
			(width 0.2)
			(type default)
		)
		(layer "In1.Cu")
	)
	(gr_line
		(start 40.203374 -80.735932)
		(end 40.203374 -78.84414)
		(stroke
			(width 0.2)
			(type default)
		)
		(layer "In1.Cu")
	)
	(gr_line
		(start 40.203374 -78.84414)
		(end 40.20312 -78.843886)
		(stroke
			(width 0.2)
			(type default)
		)
		(layer "In1.Cu")
	)
	(gr_line
		(start 40.203374 -78.33614)
		(end 40.203374 -76.444094)
		(stroke
			(width 0.2)
			(type default)
		)
		(layer "In1.Cu")
	)
	(gr_line
		(start 40.203374 -76.444094)
		(end 40.20312 -76.44384)
		(stroke
			(width 0.2)
			(type default)
		)
		(layer "In1.Cu")
	)
	(gr_line
		(start 40.203374 -75.936094)
		(end 40.203374 -74.044048)
		(stroke
			(width 0.2)
			(type default)
		)
		(layer "In1.Cu")
	)
	(gr_line
		(start 40.203374 -74.044048)
		(end 40.20312 -74.043794)
		(stroke
			(width 0.2)
			(type default)
		)
		(layer "In1.Cu")
	)
	(gr_line
		(start 40.203374 -73.536048)
		(end 40.203374 -71.644002)
		(stroke
			(width 0.2)
			(type default)
		)
		(layer "In1.Cu")
	)
	(gr_line
		(start 40.203374 -71.644002)
		(end 40.20312 -71.643748)
		(stroke
			(width 0.2)
			(type default)
		)
		(layer "In1.Cu")
	)
	(gr_line
		(start 40.203374 -71.136002)
		(end 40.203374 -69.243956)
		(stroke
			(width 0.2)
			(type default)
		)
		(layer "In1.Cu")
	)
	(gr_line
		(start 40.203374 -69.243956)
		(end 40.20312 -69.243702)
		(stroke
			(width 0.2)
			(type default)
		)
		(layer "In1.Cu")
	)
	(gr_line
		(start 40.203374 -68.735956)
		(end 40.203374 -66.844164)
		(stroke
			(width 0.2)
			(type default)
		)
		(layer "In1.Cu")
	)
	(gr_line
		(start 40.203374 -66.844164)
		(end 40.20312 -66.84391)
		(stroke
			(width 0.2)
			(type default)
		)
		(layer "In1.Cu")
	)
	(gr_line
		(start 40.203374 -58.335926)
		(end 40.203374 -56.444134)
		(stroke
			(width 0.2)
			(type default)
		)
		(layer "In1.Cu")
	)
	(gr_line
		(start 40.203374 -56.444134)
		(end 40.20312 -56.44388)
		(stroke
			(width 0.2)
			(type default)
		)
		(layer "In1.Cu")
	)
	(gr_line
		(start 40.203374 -55.936134)
		(end 40.203374 -54.044088)
		(stroke
			(width 0.2)
			(type default)
		)
		(layer "In1.Cu")
	)
	(gr_line
		(start 40.203374 -54.044088)
		(end 40.20312 -54.043834)
		(stroke
			(width 0.2)
			(type default)
		)
		(layer "In1.Cu")
	)
	(gr_line
		(start 40.203374 -53.536088)
		(end 40.203374 -51.644042)
		(stroke
			(width 0.2)
			(type default)
		)
		(layer "In1.Cu")
	)
	(gr_line
		(start 40.203374 -51.644042)
		(end 40.20312 -51.643788)
		(stroke
			(width 0.2)
			(type default)
		)
		(layer "In1.Cu")
	)
	(gr_line
		(start 41.38676 -473.936314)
		(end 43.39336 -473.936314)
		(stroke
			(width 0.2)
			(type default)
		)
		(layer "In1.Cu")
	)
	(gr_line
		(start 41.38676 -472.044014)
		(end 41.38676 -473.936314)
		(stroke
			(width 0.2)
			(type default)
		)
		(layer "In1.Cu")
	)
	(gr_line
		(start 41.38676 -370.936266)
		(end 43.39336 -370.936266)
		(stroke
			(width 0.2)
			(type default)
		)
		(layer "In1.Cu")
	)
	(gr_line
		(start 41.38676 -369.043966)
		(end 41.38676 -370.936266)
		(stroke
			(width 0.2)
			(type default)
		)
		(layer "In1.Cu")
	)
	(gr_line
		(start 41.38676 -267.936218)
		(end 43.39336 -267.936218)
		(stroke
			(width 0.2)
			(type default)
		)
		(layer "In1.Cu")
	)
	(gr_line
		(start 41.38676 -266.043918)
		(end 41.38676 -267.936218)
		(stroke
			(width 0.2)
			(type default)
		)
		(layer "In1.Cu")
	)
	(gr_line
		(start 41.38676 -164.93617)
		(end 43.39336 -164.93617)
		(stroke
			(width 0.2)
			(type default)
		)
		(layer "In1.Cu")
	)
	(gr_line
		(start 41.38676 -163.04387)
		(end 41.38676 -164.93617)
		(stroke
			(width 0.2)
			(type default)
		)
		(layer "In1.Cu")
	)
	(gr_line
		(start 41.38676 -61.936122)
		(end 43.39336 -61.936122)
		(stroke
			(width 0.2)
			(type default)
		)
		(layer "In1.Cu")
	)
	(gr_line
		(start 41.38676 -60.043822)
		(end 41.38676 -61.936122)
		(stroke
			(width 0.2)
			(type default)
		)
		(layer "In1.Cu")
	)
	(gr_arc
		(start 41.90746 -239.397286)
		(mid 42.418 -239.907826)
		(end 42.92854 -239.397286)
		(stroke
			(width 0.2)
			(type default)
		)
		(layer "In1.Cu")
	)
	(gr_line
		(start 41.90746 -238.584486)
		(end 41.90746 -239.397286)
		(stroke
			(width 0.2)
			(type default)
		)
		(layer "In1.Cu")
	)
	(gr_line
		(start 42.92854 -239.397286)
		(end 42.92854 -238.58474)
		(stroke
			(width 0.2)
			(type default)
		)
		(layer "In1.Cu")
	)
	(gr_arc
		(start 42.92854 -238.58474)
		(mid 42.418127 -238.073946)
		(end 41.90746 -238.584486)
		(stroke
			(width 0.2)
			(type default)
		)
		(layer "In1.Cu")
	)
	(gr_line
		(start 43.393106 -472.044014)
		(end 41.38676 -472.044014)
		(stroke
			(width 0.2)
			(type default)
		)
		(layer "In1.Cu")
	)
	(gr_line
		(start 43.393106 -369.043966)
		(end 41.38676 -369.043966)
		(stroke
			(width 0.2)
			(type default)
		)
		(layer "In1.Cu")
	)
	(gr_line
		(start 43.393106 -266.043918)
		(end 41.38676 -266.043918)
		(stroke
			(width 0.2)
			(type default)
		)
		(layer "In1.Cu")
	)
	(gr_line
		(start 43.393106 -163.04387)
		(end 41.38676 -163.04387)
		(stroke
			(width 0.2)
			(type default)
		)
		(layer "In1.Cu")
	)
	(gr_line
		(start 43.393106 -60.043822)
		(end 41.38676 -60.043822)
		(stroke
			(width 0.2)
			(type default)
		)
		(layer "In1.Cu")
	)
	(gr_line
		(start 43.39336 -473.936314)
		(end 43.39336 -472.044268)
		(stroke
			(width 0.2)
			(type default)
		)
		(layer "In1.Cu")
	)
	(gr_line
		(start 43.39336 -472.044268)
		(end 43.393106 -472.044014)
		(stroke
			(width 0.2)
			(type default)
		)
		(layer "In1.Cu")
	)
	(gr_line
		(start 43.39336 -370.936266)
		(end 43.39336 -369.04422)
		(stroke
			(width 0.2)
			(type default)
		)
		(layer "In1.Cu")
	)
	(gr_line
		(start 43.39336 -369.04422)
		(end 43.393106 -369.043966)
		(stroke
			(width 0.2)
			(type default)
		)
		(layer "In1.Cu")
	)
	(gr_line
		(start 43.39336 -267.936218)
		(end 43.39336 -266.044172)
		(stroke
			(width 0.2)
			(type default)
		)
		(layer "In1.Cu")
	)
	(gr_line
		(start 43.39336 -266.044172)
		(end 43.393106 -266.043918)
		(stroke
			(width 0.2)
			(type default)
		)
		(layer "In1.Cu")
	)
	(gr_line
		(start 43.39336 -164.93617)
		(end 43.39336 -163.044124)
		(stroke
			(width 0.2)
			(type default)
		)
		(layer "In1.Cu")
	)
	(gr_line
		(start 43.39336 -163.044124)
		(end 43.393106 -163.04387)
		(stroke
			(width 0.2)
			(type default)
		)
		(layer "In1.Cu")
	)
	(gr_line
		(start 43.39336 -61.936122)
		(end 43.39336 -60.044076)
		(stroke
			(width 0.2)
			(type default)
		)
		(layer "In1.Cu")
	)
	(gr_line
		(start 43.39336 -60.044076)
		(end 43.393106 -60.043822)
		(stroke
			(width 0.2)
			(type default)
		)
		(layer "In1.Cu")
	)
	(gr_line
		(start 44.9072 -472.300808)
		(end 45.719746 -472.300808)
		(stroke
			(width 0.2)
			(type default)
		)
		(layer "In1.Cu")
	)
	(gr_arc
		(start 44.9072 -471.279728)
		(mid 44.39666 -471.790268)
		(end 44.9072 -472.300808)
		(stroke
			(width 0.2)
			(type default)
		)
		(layer "In1.Cu")
	)
	(gr_line
		(start 44.9072 -369.30076)
		(end 45.72 -369.30076)
		(stroke
			(width 0.2)
			(type default)
		)
		(layer "In1.Cu")
	)
	(gr_line
		(start 44.9072 -266.300712)
		(end 45.72 -266.300712)
		(stroke
			(width 0.2)
			(type default)
		)
		(layer "In1.Cu")
	)
	(gr_line
		(start 44.9072 -163.300664)
		(end 45.72 -163.300664)
		(stroke
			(width 0.2)
			(type default)
		)
		(layer "In1.Cu")
	)
	(gr_line
		(start 44.9072 -60.300616)
		(end 45.72 -60.300616)
		(stroke
			(width 0.2)
			(type default)
		)
		(layer "In1.Cu")
	)
	(gr_arc
		(start 44.907454 -368.27968)
		(mid 44.39666 -368.790093)
		(end 44.9072 -369.30076)
		(stroke
			(width 0.2)
			(type default)
		)
		(layer "In1.Cu")
	)
	(gr_arc
		(start 44.907454 -265.279632)
		(mid 44.39666 -265.790045)
		(end 44.9072 -266.300712)
		(stroke
			(width 0.2)
			(type default)
		)
		(layer "In1.Cu")
	)
	(gr_arc
		(start 44.907454 -162.279584)
		(mid 44.39666 -162.789997)
		(end 44.9072 -163.300664)
		(stroke
			(width 0.2)
			(type default)
		)
		(layer "In1.Cu")
	)
	(gr_arc
		(start 44.907454 -59.279536)
		(mid 44.39666 -59.789949)
		(end 44.9072 -60.300616)
		(stroke
			(width 0.2)
			(type default)
		)
		(layer "In1.Cu")
	)
	(gr_arc
		(start 45.719746 -472.300808)
		(mid 46.23054 -471.790395)
		(end 45.72 -471.279728)
		(stroke
			(width 0.2)
			(type default)
		)
		(layer "In1.Cu")
	)
	(gr_line
		(start 45.72 -471.279728)
		(end 44.9072 -471.279728)
		(stroke
			(width 0.2)
			(type default)
		)
		(layer "In1.Cu")
	)
	(gr_arc
		(start 45.72 -369.30076)
		(mid 46.23054 -368.79022)
		(end 45.72 -368.27968)
		(stroke
			(width 0.2)
			(type default)
		)
		(layer "In1.Cu")
	)
	(gr_line
		(start 45.72 -368.27968)
		(end 44.907454 -368.27968)
		(stroke
			(width 0.2)
			(type default)
		)
		(layer "In1.Cu")
	)
	(gr_arc
		(start 45.72 -266.300712)
		(mid 46.23054 -265.790172)
		(end 45.72 -265.279632)
		(stroke
			(width 0.2)
			(type default)
		)
		(layer "In1.Cu")
	)
	(gr_line
		(start 45.72 -265.279632)
		(end 44.907454 -265.279632)
		(stroke
			(width 0.2)
			(type default)
		)
		(layer "In1.Cu")
	)
	(gr_arc
		(start 45.72 -163.300664)
		(mid 46.23054 -162.790124)
		(end 45.72 -162.279584)
		(stroke
			(width 0.2)
			(type default)
		)
		(layer "In1.Cu")
	)
	(gr_line
		(start 45.72 -162.279584)
		(end 44.907454 -162.279584)
		(stroke
			(width 0.2)
			(type default)
		)
		(layer "In1.Cu")
	)
	(gr_arc
		(start 45.72 -60.300616)
		(mid 46.23054 -59.790076)
		(end 45.72 -59.279536)
		(stroke
			(width 0.2)
			(type default)
		)
		(layer "In1.Cu")
	)
	(gr_line
		(start 45.72 -59.279536)
		(end 44.907454 -59.279536)
		(stroke
			(width 0.2)
			(type default)
		)
		(layer "In1.Cu")
	)
	(gr_arc
		(start 47.87646 -473.392246)
		(mid 48.387 -473.902786)
		(end 48.89754 -473.392246)
		(stroke
			(width 0.2)
			(type default)
		)
		(layer "In1.Cu")
	)
	(gr_line
		(start 47.87646 -472.579446)
		(end 47.87646 -473.392246)
		(stroke
			(width 0.2)
			(type default)
		)
		(layer "In1.Cu")
	)
	(gr_arc
		(start 47.87646 -370.392198)
		(mid 48.387 -370.902738)
		(end 48.89754 -370.392198)
		(stroke
			(width 0.2)
			(type default)
		)
		(layer "In1.Cu")
	)
	(gr_line
		(start 47.87646 -369.579398)
		(end 47.87646 -370.392198)
		(stroke
			(width 0.2)
			(type default)
		)
		(layer "In1.Cu")
	)
	(gr_arc
		(start 47.87646 -267.39215)
		(mid 48.387 -267.90269)
		(end 48.89754 -267.39215)
		(stroke
			(width 0.2)
			(type default)
		)
		(layer "In1.Cu")
	)
	(gr_line
		(start 47.87646 -266.57935)
		(end 47.87646 -267.39215)
		(stroke
			(width 0.2)
			(type default)
		)
		(layer "In1.Cu")
	)
	(gr_arc
		(start 47.87646 -164.392102)
		(mid 48.387 -164.902642)
		(end 48.89754 -164.392102)
		(stroke
			(width 0.2)
			(type default)
		)
		(layer "In1.Cu")
	)
	(gr_line
		(start 47.87646 -163.579302)
		(end 47.87646 -164.392102)
		(stroke
			(width 0.2)
			(type default)
		)
		(layer "In1.Cu")
	)
	(gr_arc
		(start 47.87646 -61.392054)
		(mid 48.387 -61.902594)
		(end 48.89754 -61.392054)
		(stroke
			(width 0.2)
			(type default)
		)
		(layer "In1.Cu")
	)
	(gr_line
		(start 47.87646 -60.579254)
		(end 47.87646 -61.392054)
		(stroke
			(width 0.2)
			(type default)
		)
		(layer "In1.Cu")
	)
	(gr_line
		(start 48.89754 -473.392246)
		(end 48.89754 -472.5797)
		(stroke
			(width 0.2)
			(type default)
		)
		(layer "In1.Cu")
	)
	(gr_arc
		(start 48.89754 -472.5797)
		(mid 48.387127 -472.068906)
		(end 47.87646 -472.579446)
		(stroke
			(width 0.2)
			(type default)
		)
		(layer "In1.Cu")
	)
	(gr_line
		(start 48.89754 -370.392198)
		(end 48.89754 -369.579652)
		(stroke
			(width 0.2)
			(type default)
		)
		(layer "In1.Cu")
	)
	(gr_arc
		(start 48.89754 -369.579652)
		(mid 48.387127 -369.068858)
		(end 47.87646 -369.579398)
		(stroke
			(width 0.2)
			(type default)
		)
		(layer "In1.Cu")
	)
	(gr_line
		(start 48.89754 -267.39215)
		(end 48.89754 -266.579604)
		(stroke
			(width 0.2)
			(type default)
		)
		(layer "In1.Cu")
	)
	(gr_arc
		(start 48.89754 -266.579604)
		(mid 48.387127 -266.06881)
		(end 47.87646 -266.57935)
		(stroke
			(width 0.2)
			(type default)
		)
		(layer "In1.Cu")
	)
	(gr_line
		(start 48.89754 -164.392102)
		(end 48.89754 -163.579556)
		(stroke
			(width 0.2)
			(type default)
		)
		(layer "In1.Cu")
	)
	(gr_arc
		(start 48.89754 -163.579556)
		(mid 48.387127 -163.068762)
		(end 47.87646 -163.579302)
		(stroke
			(width 0.2)
			(type default)
		)
		(layer "In1.Cu")
	)
	(gr_line
		(start 48.89754 -61.392054)
		(end 48.89754 -60.579508)
		(stroke
			(width 0.2)
			(type default)
		)
		(layer "In1.Cu")
	)
	(gr_arc
		(start 48.89754 -60.579508)
		(mid 48.387127 -60.068714)
		(end 47.87646 -60.579254)
		(stroke
			(width 0.2)
			(type default)
		)
		(layer "In1.Cu")
	)
	(gr_arc
		(start 71.87946 -431.9524)
		(mid 72.39 -432.46294)
		(end 72.90054 -431.9524)
		(stroke
			(width 0.2)
			(type default)
		)
		(layer "In1.Cu")
	)
	(gr_line
		(start 71.87946 -431.1396)
		(end 71.87946 -431.9524)
		(stroke
			(width 0.2)
			(type default)
		)
		(layer "In1.Cu")
	)
	(gr_line
		(start 72.90054 -431.9524)
		(end 72.90054 -431.139854)
		(stroke
			(width 0.2)
			(type default)
		)
		(layer "In1.Cu")
	)
	(gr_arc
		(start 72.90054 -431.139854)
		(mid 72.390127 -430.62906)
		(end 71.87946 -431.1396)
		(stroke
			(width 0.2)
			(type default)
		)
		(layer "In1.Cu")
	)
	(gr_line
		(start 74.2696 -430.63414)
		(end 75.0824 -430.63414)
		(stroke
			(width 0.2)
			(type default)
		)
		(layer "In1.Cu")
	)
	(gr_arc
		(start 74.269854 -429.61306)
		(mid 73.75906 -430.123473)
		(end 74.2696 -430.63414)
		(stroke
			(width 0.2)
			(type default)
		)
		(layer "In1.Cu")
	)
	(gr_arc
		(start 75.0824 -430.63414)
		(mid 75.59294 -430.1236)
		(end 75.0824 -429.61306)
		(stroke
			(width 0.2)
			(type default)
		)
		(layer "In1.Cu")
	)
	(gr_line
		(start 75.0824 -429.61306)
		(end 74.269854 -429.61306)
		(stroke
			(width 0.2)
			(type default)
		)
		(layer "In1.Cu")
	)
	(gr_arc
		(start 77.06106 -211.0232)
		(mid 77.091562 -211.096838)
		(end 77.1652 -211.12734)
		(stroke
			(width 0.2)
			(type default)
		)
		(layer "In1.Cu")
	)
	(gr_line
		(start 77.06106 -210.6676)
		(end 77.06106 -211.0232)
		(stroke
			(width 0.2)
			(type default)
		)
		(layer "In1.Cu")
	)
	(gr_arc
		(start 77.06106 -209.9818)
		(mid 77.091562 -210.055438)
		(end 77.1652 -210.08594)
		(stroke
			(width 0.2)
			(type default)
		)
		(layer "In1.Cu")
	)
	(gr_line
		(start 77.06106 -209.6262)
		(end 77.06106 -209.9818)
		(stroke
			(width 0.2)
			(type default)
		)
		(layer "In1.Cu")
	)
	(gr_line
		(start 77.1652 -211.12734)
		(end 77.5208 -211.12734)
		(stroke
			(width 0.2)
			(type default)
		)
		(layer "In1.Cu")
	)
	(gr_arc
		(start 77.1652 -210.56346)
		(mid 77.091562 -210.593962)
		(end 77.06106 -210.6676)
		(stroke
			(width 0.2)
			(type default)
		)
		(layer "In1.Cu")
	)
	(gr_line
		(start 77.1652 -210.08594)
		(end 77.5208 -210.08594)
		(stroke
			(width 0.2)
			(type default)
		)
		(layer "In1.Cu")
	)
	(gr_arc
		(start 77.1652 -209.52206)
		(mid 77.091562 -209.552562)
		(end 77.06106 -209.6262)
		(stroke
			(width 0.2)
			(type default)
		)
		(layer "In1.Cu")
	)
	(gr_arc
		(start 77.21346 -101.9302)
		(mid 77.243962 -102.003838)
		(end 77.3176 -102.03434)
		(stroke
			(width 0.2)
			(type default)
		)
		(layer "In1.Cu")
	)
	(gr_line
		(start 77.21346 -101.5746)
		(end 77.21346 -101.9302)
		(stroke
			(width 0.2)
			(type default)
		)
		(layer "In1.Cu")
	)
	(gr_arc
		(start 77.21346 -100.8888)
		(mid 77.243962 -100.962438)
		(end 77.3176 -100.99294)
		(stroke
			(width 0.2)
			(type default)
		)
		(layer "In1.Cu")
	)
	(gr_line
		(start 77.21346 -100.5332)
		(end 77.21346 -100.8888)
		(stroke
			(width 0.2)
			(type default)
		)
		(layer "In1.Cu")
	)
	(gr_arc
		(start 77.23886 -305.3715)
		(mid 77.269362 -305.445138)
		(end 77.343 -305.47564)
		(stroke
			(width 0.2)
			(type default)
		)
		(layer "In1.Cu")
	)
	(gr_line
		(start 77.23886 -305.0159)
		(end 77.23886 -305.3715)
		(stroke
			(width 0.2)
			(type default)
		)
		(layer "In1.Cu")
	)
	(gr_arc
		(start 77.23886 -304.3301)
		(mid 77.269362 -304.403738)
		(end 77.343 -304.43424)
		(stroke
			(width 0.2)
			(type default)
		)
		(layer "In1.Cu")
	)
	(gr_line
		(start 77.23886 -303.9745)
		(end 77.23886 -304.3301)
		(stroke
			(width 0.2)
			(type default)
		)
		(layer "In1.Cu")
	)
	(gr_line
		(start 77.3176 -102.03434)
		(end 77.6732 -102.03434)
		(stroke
			(width 0.2)
			(type default)
		)
		(layer "In1.Cu")
	)
	(gr_arc
		(start 77.3176 -101.47046)
		(mid 77.243962 -101.500962)
		(end 77.21346 -101.5746)
		(stroke
			(width 0.2)
			(type default)
		)
		(layer "In1.Cu")
	)
	(gr_line
		(start 77.3176 -100.99294)
		(end 77.6732 -100.99294)
		(stroke
			(width 0.2)
			(type default)
		)
		(layer "In1.Cu")
	)
	(gr_arc
		(start 77.3176 -100.42906)
		(mid 77.243962 -100.459562)
		(end 77.21346 -100.5332)
		(stroke
			(width 0.2)
			(type default)
		)
		(layer "In1.Cu")
	)
	(gr_line
		(start 77.343 -305.47564)
		(end 77.6986 -305.47564)
		(stroke
			(width 0.2)
			(type default)
		)
		(layer "In1.Cu")
	)
	(gr_arc
		(start 77.343 -304.91176)
		(mid 77.269362 -304.942262)
		(end 77.23886 -305.0159)
		(stroke
			(width 0.2)
			(type default)
		)
		(layer "In1.Cu")
	)
	(gr_line
		(start 77.343 -304.43424)
		(end 77.6986 -304.43424)
		(stroke
			(width 0.2)
			(type default)
		)
		(layer "In1.Cu")
	)
	(gr_arc
		(start 77.343 -303.87036)
		(mid 77.269362 -303.900862)
		(end 77.23886 -303.9745)
		(stroke
			(width 0.2)
			(type default)
		)
		(layer "In1.Cu")
	)
	(gr_arc
		(start 77.49286 -431.9905)
		(mid 77.523362 -432.064138)
		(end 77.597 -432.09464)
		(stroke
			(width 0.2)
			(type default)
		)
		(layer "In1.Cu")
	)
	(gr_line
		(start 77.49286 -431.6349)
		(end 77.49286 -431.9905)
		(stroke
			(width 0.2)
			(type default)
		)
		(layer "In1.Cu")
	)
	(gr_arc
		(start 77.49286 -430.9491)
		(mid 77.523362 -431.022738)
		(end 77.597 -431.05324)
		(stroke
			(width 0.2)
			(type default)
		)
		(layer "In1.Cu")
	)
	(gr_line
		(start 77.49286 -430.5935)
		(end 77.49286 -430.9491)
		(stroke
			(width 0.2)
			(type default)
		)
		(layer "In1.Cu")
	)
	(gr_arc
		(start 77.5208 -211.12734)
		(mid 77.594438 -211.096838)
		(end 77.62494 -211.0232)
		(stroke
			(width 0.2)
			(type default)
		)
		(layer "In1.Cu")
	)
	(gr_line
		(start 77.5208 -210.56346)
		(end 77.1652 -210.56346)
		(stroke
			(width 0.2)
			(type default)
		)
		(layer "In1.Cu")
	)
	(gr_arc
		(start 77.5208 -210.08594)
		(mid 77.594438 -210.055438)
		(end 77.62494 -209.9818)
		(stroke
			(width 0.2)
			(type default)
		)
		(layer "In1.Cu")
	)
	(gr_line
		(start 77.5208 -209.52206)
		(end 77.1652 -209.52206)
		(stroke
			(width 0.2)
			(type default)
		)
		(layer "In1.Cu")
	)
	(gr_line
		(start 77.597 -432.09464)
		(end 77.9526 -432.09464)
		(stroke
			(width 0.2)
			(type default)
		)
		(layer "In1.Cu")
	)
	(gr_arc
		(start 77.597 -431.53076)
		(mid 77.523362 -431.561262)
		(end 77.49286 -431.6349)
		(stroke
			(width 0.2)
			(type default)
		)
		(layer "In1.Cu")
	)
	(gr_line
		(start 77.597 -431.05324)
		(end 77.9526 -431.05324)
		(stroke
			(width 0.2)
			(type default)
		)
		(layer "In1.Cu")
	)
	(gr_arc
		(start 77.597 -430.48936)
		(mid 77.523362 -430.519862)
		(end 77.49286 -430.5935)
		(stroke
			(width 0.2)
			(type default)
		)
		(layer "In1.Cu")
	)
	(gr_line
		(start 77.62494 -211.0232)
		(end 77.62494 -210.6676)
		(stroke
			(width 0.2)
			(type default)
		)
		(layer "In1.Cu")
	)
	(gr_arc
		(start 77.62494 -210.6676)
		(mid 77.594438 -210.593962)
		(end 77.5208 -210.56346)
		(stroke
			(width 0.2)
			(type default)
		)
		(layer "In1.Cu")
	)
	(gr_line
		(start 77.62494 -209.9818)
		(end 77.62494 -209.6262)
		(stroke
			(width 0.2)
			(type default)
		)
		(layer "In1.Cu")
	)
	(gr_arc
		(start 77.62494 -209.6262)
		(mid 77.594438 -209.552562)
		(end 77.5208 -209.52206)
		(stroke
			(width 0.2)
			(type default)
		)
		(layer "In1.Cu")
	)
	(gr_arc
		(start 77.6732 -102.03434)
		(mid 77.746838 -102.003838)
		(end 77.77734 -101.9302)
		(stroke
			(width 0.2)
			(type default)
		)
		(layer "In1.Cu")
	)
	(gr_line
		(start 77.6732 -101.47046)
		(end 77.3176 -101.47046)
		(stroke
			(width 0.2)
			(type default)
		)
		(layer "In1.Cu")
	)
	(gr_arc
		(start 77.6732 -100.99294)
		(mid 77.746838 -100.962438)
		(end 77.77734 -100.8888)
		(stroke
			(width 0.2)
			(type default)
		)
		(layer "In1.Cu")
	)
	(gr_line
		(start 77.6732 -100.42906)
		(end 77.3176 -100.42906)
		(stroke
			(width 0.2)
			(type default)
		)
		(layer "In1.Cu")
	)
	(gr_arc
		(start 77.6986 -305.47564)
		(mid 77.772238 -305.445138)
		(end 77.80274 -305.3715)
		(stroke
			(width 0.2)
			(type default)
		)
		(layer "In1.Cu")
	)
	(gr_line
		(start 77.6986 -304.91176)
		(end 77.343 -304.91176)
		(stroke
			(width 0.2)
			(type default)
		)
		(layer "In1.Cu")
	)
	(gr_arc
		(start 77.6986 -304.43424)
		(mid 77.772238 -304.403738)
		(end 77.80274 -304.3301)
		(stroke
			(width 0.2)
			(type default)
		)
		(layer "In1.Cu")
	)
	(gr_line
		(start 77.6986 -303.87036)
		(end 77.343 -303.87036)
		(stroke
			(width 0.2)
			(type default)
		)
		(layer "In1.Cu")
	)
	(gr_line
		(start 77.77734 -101.9302)
		(end 77.77734 -101.5746)
		(stroke
			(width 0.2)
			(type default)
		)
		(layer "In1.Cu")
	)
	(gr_arc
		(start 77.77734 -101.5746)
		(mid 77.746838 -101.500962)
		(end 77.6732 -101.47046)
		(stroke
			(width 0.2)
			(type default)
		)
		(layer "In1.Cu")
	)
	(gr_line
		(start 77.77734 -100.8888)
		(end 77.77734 -100.5332)
		(stroke
			(width 0.2)
			(type default)
		)
		(layer "In1.Cu")
	)
	(gr_arc
		(start 77.77734 -100.5332)
		(mid 77.746838 -100.459562)
		(end 77.6732 -100.42906)
		(stroke
			(width 0.2)
			(type default)
		)
		(layer "In1.Cu")
	)
	(gr_line
		(start 77.80274 -305.3715)
		(end 77.80274 -305.0159)
		(stroke
			(width 0.2)
			(type default)
		)
		(layer "In1.Cu")
	)
	(gr_arc
		(start 77.80274 -305.0159)
		(mid 77.772238 -304.942262)
		(end 77.6986 -304.91176)
		(stroke
			(width 0.2)
			(type default)
		)
		(layer "In1.Cu")
	)
	(gr_line
		(start 77.80274 -304.3301)
		(end 77.80274 -303.9745)
		(stroke
			(width 0.2)
			(type default)
		)
		(layer "In1.Cu")
	)
	(gr_arc
		(start 77.80274 -303.9745)
		(mid 77.772238 -303.900862)
		(end 77.6986 -303.87036)
		(stroke
			(width 0.2)
			(type default)
		)
		(layer "In1.Cu")
	)
	(gr_arc
		(start 77.9526 -432.09464)
		(mid 78.026238 -432.064138)
		(end 78.05674 -431.9905)
		(stroke
			(width 0.2)
			(type default)
		)
		(layer "In1.Cu")
	)
	(gr_line
		(start 77.9526 -431.53076)
		(end 77.597 -431.53076)
		(stroke
			(width 0.2)
			(type default)
		)
		(layer "In1.Cu")
	)
	(gr_arc
		(start 77.9526 -431.05324)
		(mid 78.026238 -431.022738)
		(end 78.05674 -430.9491)
		(stroke
			(width 0.2)
			(type default)
		)
		(layer "In1.Cu")
	)
	(gr_line
		(start 77.9526 -430.48936)
		(end 77.597 -430.48936)
		(stroke
			(width 0.2)
			(type default)
		)
		(layer "In1.Cu")
	)
	(gr_line
		(start 78.05674 -431.9905)
		(end 78.05674 -431.6349)
		(stroke
			(width 0.2)
			(type default)
		)
		(layer "In1.Cu")
	)
	(gr_arc
		(start 78.05674 -431.6349)
		(mid 78.026238 -431.561262)
		(end 77.9526 -431.53076)
		(stroke
			(width 0.2)
			(type default)
		)
		(layer "In1.Cu")
	)
	(gr_line
		(start 78.05674 -430.9491)
		(end 78.05674 -430.5935)
		(stroke
			(width 0.2)
			(type default)
		)
		(layer "In1.Cu")
	)
	(gr_arc
		(start 78.05674 -430.5935)
		(mid 78.026238 -430.519862)
		(end 77.9526 -430.48936)
		(stroke
			(width 0.2)
			(type default)
		)
		(layer "In1.Cu")
	)
	(gr_arc
		(start 78.10246 -211.0232)
		(mid 78.132962 -211.096838)
		(end 78.2066 -211.12734)
		(stroke
			(width 0.2)
			(type default)
		)
		(layer "In1.Cu")
	)
	(gr_line
		(start 78.10246 -210.6676)
		(end 78.10246 -211.0232)
		(stroke
			(width 0.2)
			(type default)
		)
		(layer "In1.Cu")
	)
	(gr_arc
		(start 78.10246 -209.9818)
		(mid 78.132962 -210.055438)
		(end 78.2066 -210.08594)
		(stroke
			(width 0.2)
			(type default)
		)
		(layer "In1.Cu")
	)
	(gr_line
		(start 78.10246 -209.6262)
		(end 78.10246 -209.9818)
		(stroke
			(width 0.2)
			(type default)
		)
		(layer "In1.Cu")
	)
	(gr_line
		(start 78.2066 -211.12734)
		(end 78.5622 -211.12734)
		(stroke
			(width 0.2)
			(type default)
		)
		(layer "In1.Cu")
	)
	(gr_arc
		(start 78.2066 -210.56346)
		(mid 78.132962 -210.593962)
		(end 78.10246 -210.6676)
		(stroke
			(width 0.2)
			(type default)
		)
		(layer "In1.Cu")
	)
	(gr_line
		(start 78.2066 -210.08594)
		(end 78.5622 -210.08594)
		(stroke
			(width 0.2)
			(type default)
		)
		(layer "In1.Cu")
	)
	(gr_arc
		(start 78.2066 -209.52206)
		(mid 78.132962 -209.552562)
		(end 78.10246 -209.6262)
		(stroke
			(width 0.2)
			(type default)
		)
		(layer "In1.Cu")
	)
	(gr_arc
		(start 78.28026 -305.3715)
		(mid 78.310762 -305.445138)
		(end 78.3844 -305.47564)
		(stroke
			(width 0.2)
			(type default)
		)
		(layer "In1.Cu")
	)
	(gr_line
		(start 78.28026 -305.0159)
		(end 78.28026 -305.3715)
		(stroke
			(width 0.2)
			(type default)
		)
		(layer "In1.Cu")
	)
	(gr_arc
		(start 78.28026 -304.3301)
		(mid 78.310762 -304.403738)
		(end 78.3844 -304.43424)
		(stroke
			(width 0.2)
			(type default)
		)
		(layer "In1.Cu")
	)
	(gr_line
		(start 78.28026 -303.9745)
		(end 78.28026 -304.3301)
		(stroke
			(width 0.2)
			(type default)
		)
		(layer "In1.Cu")
	)
	(gr_arc
		(start 78.28026 -101.9302)
		(mid 78.310762 -102.003838)
		(end 78.3844 -102.03434)
		(stroke
			(width 0.2)
			(type default)
		)
		(layer "In1.Cu")
	)
	(gr_line
		(start 78.28026 -101.5746)
		(end 78.28026 -101.9302)
		(stroke
			(width 0.2)
			(type default)
		)
		(layer "In1.Cu")
	)
	(gr_arc
		(start 78.28026 -100.8888)
		(mid 78.310762 -100.962438)
		(end 78.3844 -100.99294)
		(stroke
			(width 0.2)
			(type default)
		)
		(layer "In1.Cu")
	)
	(gr_line
		(start 78.28026 -100.5332)
		(end 78.28026 -100.8888)
		(stroke
			(width 0.2)
			(type default)
		)
		(layer "In1.Cu")
	)
	(gr_line
		(start 78.3844 -305.47564)
		(end 78.74 -305.47564)
		(stroke
			(width 0.2)
			(type default)
		)
		(layer "In1.Cu")
	)
	(gr_arc
		(start 78.3844 -304.91176)
		(mid 78.310762 -304.942262)
		(end 78.28026 -305.0159)
		(stroke
			(width 0.2)
			(type default)
		)
		(layer "In1.Cu")
	)
	(gr_line
		(start 78.3844 -304.43424)
		(end 78.74 -304.43424)
		(stroke
			(width 0.2)
			(type default)
		)
		(layer "In1.Cu")
	)
	(gr_arc
		(start 78.3844 -303.87036)
		(mid 78.310762 -303.900862)
		(end 78.28026 -303.9745)
		(stroke
			(width 0.2)
			(type default)
		)
		(layer "In1.Cu")
	)
	(gr_line
		(start 78.3844 -102.03434)
		(end 78.74 -102.03434)
		(stroke
			(width 0.2)
			(type default)
		)
		(layer "In1.Cu")
	)
	(gr_arc
		(start 78.3844 -101.47046)
		(mid 78.310762 -101.500962)
		(end 78.28026 -101.5746)
		(stroke
			(width 0.2)
			(type default)
		)
		(layer "In1.Cu")
	)
	(gr_line
		(start 78.3844 -100.99294)
		(end 78.74 -100.99294)
		(stroke
			(width 0.2)
			(type default)
		)
		(layer "In1.Cu")
	)
	(gr_arc
		(start 78.3844 -100.42906)
		(mid 78.310762 -100.459562)
		(end 78.28026 -100.5332)
		(stroke
			(width 0.2)
			(type default)
		)
		(layer "In1.Cu")
	)
	(gr_arc
		(start 78.53426 -431.9905)
		(mid 78.564762 -432.064138)
		(end 78.6384 -432.09464)
		(stroke
			(width 0.2)
			(type default)
		)
		(layer "In1.Cu")
	)
	(gr_line
		(start 78.53426 -431.6349)
		(end 78.53426 -431.9905)
		(stroke
			(width 0.2)
			(type default)
		)
		(layer "In1.Cu")
	)
	(gr_arc
		(start 78.53426 -430.9491)
		(mid 78.564762 -431.022738)
		(end 78.6384 -431.05324)
		(stroke
			(width 0.2)
			(type default)
		)
		(layer "In1.Cu")
	)
	(gr_line
		(start 78.53426 -430.5935)
		(end 78.53426 -430.9491)
		(stroke
			(width 0.2)
			(type default)
		)
		(layer "In1.Cu")
	)
	(gr_arc
		(start 78.5622 -211.12734)
		(mid 78.635838 -211.096838)
		(end 78.66634 -211.0232)
		(stroke
			(width 0.2)
			(type default)
		)
		(layer "In1.Cu")
	)
	(gr_line
		(start 78.5622 -210.56346)
		(end 78.2066 -210.56346)
		(stroke
			(width 0.2)
			(type default)
		)
		(layer "In1.Cu")
	)
	(gr_arc
		(start 78.5622 -210.08594)
		(mid 78.635838 -210.055438)
		(end 78.66634 -209.9818)
		(stroke
			(width 0.2)
			(type default)
		)
		(layer "In1.Cu")
	)
	(gr_line
		(start 78.5622 -209.52206)
		(end 78.2066 -209.52206)
		(stroke
			(width 0.2)
			(type default)
		)
		(layer "In1.Cu")
	)
	(gr_line
		(start 78.6384 -432.09464)
		(end 78.994 -432.09464)
		(stroke
			(width 0.2)
			(type default)
		)
		(layer "In1.Cu")
	)
	(gr_arc
		(start 78.6384 -431.53076)
		(mid 78.564762 -431.561262)
		(end 78.53426 -431.6349)
		(stroke
			(width 0.2)
			(type default)
		)
		(layer "In1.Cu")
	)
	(gr_line
		(start 78.6384 -431.05324)
		(end 78.994 -431.05324)
		(stroke
			(width 0.2)
			(type default)
		)
		(layer "In1.Cu")
	)
	(gr_arc
		(start 78.6384 -430.48936)
		(mid 78.564762 -430.519862)
		(end 78.53426 -430.5935)
		(stroke
			(width 0.2)
			(type default)
		)
		(layer "In1.Cu")
	)
	(gr_line
		(start 78.66634 -211.0232)
		(end 78.66634 -210.6676)
		(stroke
			(width 0.2)
			(type default)
		)
		(layer "In1.Cu")
	)
	(gr_arc
		(start 78.66634 -210.6676)
		(mid 78.635838 -210.593962)
		(end 78.5622 -210.56346)
		(stroke
			(width 0.2)
			(type default)
		)
		(layer "In1.Cu")
	)
	(gr_line
		(start 78.66634 -209.9818)
		(end 78.66634 -209.6262)
		(stroke
			(width 0.2)
			(type default)
		)
		(layer "In1.Cu")
	)
	(gr_arc
		(start 78.66634 -209.6262)
		(mid 78.635838 -209.552562)
		(end 78.5622 -209.52206)
		(stroke
			(width 0.2)
			(type default)
		)
		(layer "In1.Cu")
	)
	(gr_arc
		(start 78.74 -305.47564)
		(mid 78.813638 -305.445138)
		(end 78.84414 -305.3715)
		(stroke
			(width 0.2)
			(type default)
		)
		(layer "In1.Cu")
	)
	(gr_line
		(start 78.74 -304.91176)
		(end 78.3844 -304.91176)
		(stroke
			(width 0.2)
			(type default)
		)
		(layer "In1.Cu")
	)
	(gr_arc
		(start 78.74 -304.43424)
		(mid 78.813638 -304.403738)
		(end 78.84414 -304.3301)
		(stroke
			(width 0.2)
			(type default)
		)
		(layer "In1.Cu")
	)
	(gr_line
		(start 78.74 -303.87036)
		(end 78.3844 -303.87036)
		(stroke
			(width 0.2)
			(type default)
		)
		(layer "In1.Cu")
	)
	(gr_arc
		(start 78.74 -102.03434)
		(mid 78.813638 -102.003838)
		(end 78.84414 -101.9302)
		(stroke
			(width 0.2)
			(type default)
		)
		(layer "In1.Cu")
	)
	(gr_line
		(start 78.74 -101.47046)
		(end 78.3844 -101.47046)
		(stroke
			(width 0.2)
			(type default)
		)
		(layer "In1.Cu")
	)
	(gr_arc
		(start 78.74 -100.99294)
		(mid 78.813638 -100.962438)
		(end 78.84414 -100.8888)
		(stroke
			(width 0.2)
			(type default)
		)
		(layer "In1.Cu")
	)
	(gr_line
		(start 78.74 -100.42906)
		(end 78.3844 -100.42906)
		(stroke
			(width 0.2)
			(type default)
		)
		(layer "In1.Cu")
	)
	(gr_line
		(start 78.84414 -305.3715)
		(end 78.84414 -305.0159)
		(stroke
			(width 0.2)
			(type default)
		)
		(layer "In1.Cu")
	)
	(gr_arc
		(start 78.84414 -305.0159)
		(mid 78.813638 -304.942262)
		(end 78.74 -304.91176)
		(stroke
			(width 0.2)
			(type default)
		)
		(layer "In1.Cu")
	)
	(gr_line
		(start 78.84414 -304.3301)
		(end 78.84414 -303.9745)
		(stroke
			(width 0.2)
			(type default)
		)
		(layer "In1.Cu")
	)
	(gr_arc
		(start 78.84414 -303.9745)
		(mid 78.813638 -303.900862)
		(end 78.74 -303.87036)
		(stroke
			(width 0.2)
			(type default)
		)
		(layer "In1.Cu")
	)
	(gr_line
		(start 78.84414 -101.9302)
		(end 78.84414 -101.5746)
		(stroke
			(width 0.2)
			(type default)
		)
		(layer "In1.Cu")
	)
	(gr_arc
		(start 78.84414 -101.5746)
		(mid 78.813638 -101.500962)
		(end 78.74 -101.47046)
		(stroke
			(width 0.2)
			(type default)
		)
		(layer "In1.Cu")
	)
	(gr_line
		(start 78.84414 -100.8888)
		(end 78.84414 -100.5332)
		(stroke
			(width 0.2)
			(type default)
		)
		(layer "In1.Cu")
	)
	(gr_arc
		(start 78.84414 -100.5332)
		(mid 78.813638 -100.459562)
		(end 78.74 -100.42906)
		(stroke
			(width 0.2)
			(type default)
		)
		(layer "In1.Cu")
	)
	(gr_arc
		(start 78.994 -432.09464)
		(mid 79.067638 -432.064138)
		(end 79.09814 -431.9905)
		(stroke
			(width 0.2)
			(type default)
		)
		(layer "In1.Cu")
	)
	(gr_line
		(start 78.994 -431.53076)
		(end 78.6384 -431.53076)
		(stroke
			(width 0.2)
			(type default)
		)
		(layer "In1.Cu")
	)
	(gr_arc
		(start 78.994 -431.05324)
		(mid 79.067638 -431.022738)
		(end 79.09814 -430.9491)
		(stroke
			(width 0.2)
			(type default)
		)
		(layer "In1.Cu")
	)
	(gr_line
		(start 78.994 -430.48936)
		(end 78.6384 -430.48936)
		(stroke
			(width 0.2)
			(type default)
		)
		(layer "In1.Cu")
	)
	(gr_line
		(start 79.09814 -431.9905)
		(end 79.09814 -431.6349)
		(stroke
			(width 0.2)
			(type default)
		)
		(layer "In1.Cu")
	)
	(gr_arc
		(start 79.09814 -431.6349)
		(mid 79.067638 -431.561262)
		(end 78.994 -431.53076)
		(stroke
			(width 0.2)
			(type default)
		)
		(layer "In1.Cu")
	)
	(gr_line
		(start 79.09814 -430.9491)
		(end 79.09814 -430.5935)
		(stroke
			(width 0.2)
			(type default)
		)
		(layer "In1.Cu")
	)
	(gr_arc
		(start 79.09814 -430.5935)
		(mid 79.067638 -430.519862)
		(end 78.994 -430.48936)
		(stroke
			(width 0.2)
			(type default)
		)
		(layer "In1.Cu")
	)
	(gr_arc
		(start 83.30946 -431.7111)
		(mid 83.325083 -431.748817)
		(end 83.3628 -431.76444)
		(stroke
			(width 0.2)
			(type default)
		)
		(layer "In1.Cu")
	)
	(gr_line
		(start 83.30946 -431.4571)
		(end 83.30946 -431.7111)
		(stroke
			(width 0.2)
			(type default)
		)
		(layer "In1.Cu")
	)
	(gr_arc
		(start 83.30946 -431.1523)
		(mid 83.325083 -431.190017)
		(end 83.3628 -431.20564)
		(stroke
			(width 0.2)
			(type default)
		)
		(layer "In1.Cu")
	)
	(gr_line
		(start 83.30946 -430.8983)
		(end 83.30946 -431.1523)
		(stroke
			(width 0.2)
			(type default)
		)
		(layer "In1.Cu")
	)
	(gr_line
		(start 83.3628 -431.76444)
		(end 83.566 -431.76444)
		(stroke
			(width 0.2)
			(type default)
		)
		(layer "In1.Cu")
	)
	(gr_arc
		(start 83.3628 -431.40376)
		(mid 83.325083 -431.419383)
		(end 83.30946 -431.4571)
		(stroke
			(width 0.2)
			(type default)
		)
		(layer "In1.Cu")
	)
	(gr_line
		(start 83.3628 -431.20564)
		(end 83.566 -431.20564)
		(stroke
			(width 0.2)
			(type default)
		)
		(layer "In1.Cu")
	)
	(gr_arc
		(start 83.3628 -430.84496)
		(mid 83.325083 -430.860583)
		(end 83.30946 -430.8983)
		(stroke
			(width 0.2)
			(type default)
		)
		(layer "In1.Cu")
	)
	(gr_arc
		(start 83.566 -431.76444)
		(mid 83.603717 -431.748817)
		(end 83.61934 -431.7111)
		(stroke
			(width 0.2)
			(type default)
		)
		(layer "In1.Cu")
	)
	(gr_line
		(start 83.566 -431.40376)
		(end 83.3628 -431.40376)
		(stroke
			(width 0.2)
			(type default)
		)
		(layer "In1.Cu")
	)
	(gr_arc
		(start 83.566 -431.20564)
		(mid 83.603717 -431.190017)
		(end 83.61934 -431.1523)
		(stroke
			(width 0.2)
			(type default)
		)
		(layer "In1.Cu")
	)
	(gr_line
		(start 83.566 -430.84496)
		(end 83.3628 -430.84496)
		(stroke
			(width 0.2)
			(type default)
		)
		(layer "In1.Cu")
	)
	(gr_line
		(start 83.61934 -431.7111)
		(end 83.61934 -431.4571)
		(stroke
			(width 0.2)
			(type default)
		)
		(layer "In1.Cu")
	)
	(gr_arc
		(start 83.61934 -431.4571)
		(mid 83.603717 -431.419383)
		(end 83.566 -431.40376)
		(stroke
			(width 0.2)
			(type default)
		)
		(layer "In1.Cu")
	)
	(gr_line
		(start 83.61934 -431.1523)
		(end 83.61934 -430.8983)
		(stroke
			(width 0.2)
			(type default)
		)
		(layer "In1.Cu")
	)
	(gr_arc
		(start 83.61934 -430.8983)
		(mid 83.603717 -430.860583)
		(end 83.566 -430.84496)
		(stroke
			(width 0.2)
			(type default)
		)
		(layer "In1.Cu")
	)
	(gr_arc
		(start 85.39226 -210.7311)
		(mid 85.407883 -210.768817)
		(end 85.4456 -210.78444)
		(stroke
			(width 0.2)
			(type default)
		)
		(layer "In1.Cu")
	)
	(gr_line
		(start 85.39226 -210.4771)
		(end 85.39226 -210.7311)
		(stroke
			(width 0.2)
			(type default)
		)
		(layer "In1.Cu")
	)
	(gr_arc
		(start 85.39226 -210.1723)
		(mid 85.407883 -210.210017)
		(end 85.4456 -210.22564)
		(stroke
			(width 0.2)
			(type default)
		)
		(layer "In1.Cu")
	)
	(gr_line
		(start 85.39226 -209.9183)
		(end 85.39226 -210.1723)
		(stroke
			(width 0.2)
			(type default)
		)
		(layer "In1.Cu")
	)
	(gr_line
		(start 85.4456 -210.78444)
		(end 85.6488 -210.78444)
		(stroke
			(width 0.2)
			(type default)
		)
		(layer "In1.Cu")
	)
	(gr_arc
		(start 85.4456 -210.42376)
		(mid 85.407883 -210.439383)
		(end 85.39226 -210.4771)
		(stroke
			(width 0.2)
			(type default)
		)
		(layer "In1.Cu")
	)
	(gr_line
		(start 85.4456 -210.22564)
		(end 85.6488 -210.22564)
		(stroke
			(width 0.2)
			(type default)
		)
		(layer "In1.Cu")
	)
	(gr_arc
		(start 85.4456 -209.86496)
		(mid 85.407883 -209.880583)
		(end 85.39226 -209.9183)
		(stroke
			(width 0.2)
			(type default)
		)
		(layer "In1.Cu")
	)
	(gr_arc
		(start 85.57006 -305.0921)
		(mid 85.585683 -305.129817)
		(end 85.6234 -305.14544)
		(stroke
			(width 0.2)
			(type default)
		)
		(layer "In1.Cu")
	)
	(gr_line
		(start 85.57006 -304.8381)
		(end 85.57006 -305.0921)
		(stroke
			(width 0.2)
			(type default)
		)
		(layer "In1.Cu")
	)
	(gr_arc
		(start 85.57006 -304.5333)
		(mid 85.585683 -304.571017)
		(end 85.6234 -304.58664)
		(stroke
			(width 0.2)
			(type default)
		)
		(layer "In1.Cu")
	)
	(gr_line
		(start 85.57006 -304.2793)
		(end 85.57006 -304.5333)
		(stroke
			(width 0.2)
			(type default)
		)
		(layer "In1.Cu")
	)
	(gr_line
		(start 85.6234 -305.14544)
		(end 85.8266 -305.14544)
		(stroke
			(width 0.2)
			(type default)
		)
		(layer "In1.Cu")
	)
	(gr_arc
		(start 85.6234 -304.78476)
		(mid 85.585683 -304.800383)
		(end 85.57006 -304.8381)
		(stroke
			(width 0.2)
			(type default)
		)
		(layer "In1.Cu")
	)
	(gr_line
		(start 85.6234 -304.58664)
		(end 85.8266 -304.58664)
		(stroke
			(width 0.2)
			(type default)
		)
		(layer "In1.Cu")
	)
	(gr_arc
		(start 85.6234 -304.22596)
		(mid 85.585683 -304.241583)
		(end 85.57006 -304.2793)
		(stroke
			(width 0.2)
			(type default)
		)
		(layer "In1.Cu")
	)
	(gr_arc
		(start 85.64626 -101.6508)
		(mid 85.661883 -101.688517)
		(end 85.6996 -101.70414)
		(stroke
			(width 0.2)
			(type default)
		)
		(layer "In1.Cu")
	)
	(gr_line
		(start 85.64626 -101.3968)
		(end 85.64626 -101.6508)
		(stroke
			(width 0.2)
			(type default)
		)
		(layer "In1.Cu")
	)
	(gr_arc
		(start 85.64626 -101.092)
		(mid 85.661883 -101.129717)
		(end 85.6996 -101.14534)
		(stroke
			(width 0.2)
			(type default)
		)
		(layer "In1.Cu")
	)
	(gr_line
		(start 85.64626 -100.838)
		(end 85.64626 -101.092)
		(stroke
			(width 0.2)
			(type default)
		)
		(layer "In1.Cu")
	)
	(gr_arc
		(start 85.6488 -210.78444)
		(mid 85.686517 -210.768817)
		(end 85.70214 -210.7311)
		(stroke
			(width 0.2)
			(type default)
		)
		(layer "In1.Cu")
	)
	(gr_line
		(start 85.6488 -210.42376)
		(end 85.4456 -210.42376)
		(stroke
			(width 0.2)
			(type default)
		)
		(layer "In1.Cu")
	)
	(gr_arc
		(start 85.6488 -210.22564)
		(mid 85.686517 -210.210017)
		(end 85.70214 -210.1723)
		(stroke
			(width 0.2)
			(type default)
		)
		(layer "In1.Cu")
	)
	(gr_line
		(start 85.6488 -209.86496)
		(end 85.4456 -209.86496)
		(stroke
			(width 0.2)
			(type default)
		)
		(layer "In1.Cu")
	)
	(gr_line
		(start 85.6996 -101.70414)
		(end 85.9028 -101.70414)
		(stroke
			(width 0.2)
			(type default)
		)
		(layer "In1.Cu")
	)
	(gr_arc
		(start 85.6996 -101.34346)
		(mid 85.661883 -101.359083)
		(end 85.64626 -101.3968)
		(stroke
			(width 0.2)
			(type default)
		)
		(layer "In1.Cu")
	)
	(gr_line
		(start 85.6996 -101.14534)
		(end 85.9028 -101.14534)
		(stroke
			(width 0.2)
			(type default)
		)
		(layer "In1.Cu")
	)
	(gr_arc
		(start 85.6996 -100.78466)
		(mid 85.661883 -100.800283)
		(end 85.64626 -100.838)
		(stroke
			(width 0.2)
			(type default)
		)
		(layer "In1.Cu")
	)
	(gr_line
		(start 85.70214 -210.7311)
		(end 85.70214 -210.4771)
		(stroke
			(width 0.2)
			(type default)
		)
		(layer "In1.Cu")
	)
	(gr_arc
		(start 85.70214 -210.4771)
		(mid 85.686517 -210.439383)
		(end 85.6488 -210.42376)
		(stroke
			(width 0.2)
			(type default)
		)
		(layer "In1.Cu")
	)
	(gr_line
		(start 85.70214 -210.1723)
		(end 85.70214 -209.9183)
		(stroke
			(width 0.2)
			(type default)
		)
		(layer "In1.Cu")
	)
	(gr_arc
		(start 85.70214 -209.9183)
		(mid 85.686517 -209.880583)
		(end 85.6488 -209.86496)
		(stroke
			(width 0.2)
			(type default)
		)
		(layer "In1.Cu")
	)
	(gr_arc
		(start 85.8266 -305.14544)
		(mid 85.864317 -305.129817)
		(end 85.87994 -305.0921)
		(stroke
			(width 0.2)
			(type default)
		)
		(layer "In1.Cu")
	)
	(gr_line
		(start 85.8266 -304.78476)
		(end 85.6234 -304.78476)
		(stroke
			(width 0.2)
			(type default)
		)
		(layer "In1.Cu")
	)
	(gr_arc
		(start 85.8266 -304.58664)
		(mid 85.864317 -304.571017)
		(end 85.87994 -304.5333)
		(stroke
			(width 0.2)
			(type default)
		)
		(layer "In1.Cu")
	)
	(gr_line
		(start 85.8266 -304.22596)
		(end 85.6234 -304.22596)
		(stroke
			(width 0.2)
			(type default)
		)
		(layer "In1.Cu")
	)
	(gr_line
		(start 85.87994 -305.0921)
		(end 85.87994 -304.8381)
		(stroke
			(width 0.2)
			(type default)
		)
		(layer "In1.Cu")
	)
	(gr_arc
		(start 85.87994 -304.8381)
		(mid 85.864317 -304.800383)
		(end 85.8266 -304.78476)
		(stroke
			(width 0.2)
			(type default)
		)
		(layer "In1.Cu")
	)
	(gr_line
		(start 85.87994 -304.5333)
		(end 85.87994 -304.2793)
		(stroke
			(width 0.2)
			(type default)
		)
		(layer "In1.Cu")
	)
	(gr_arc
		(start 85.87994 -304.2793)
		(mid 85.864317 -304.241583)
		(end 85.8266 -304.22596)
		(stroke
			(width 0.2)
			(type default)
		)
		(layer "In1.Cu")
	)
	(gr_arc
		(start 85.9028 -101.70414)
		(mid 85.940517 -101.688517)
		(end 85.95614 -101.6508)
		(stroke
			(width 0.2)
			(type default)
		)
		(layer "In1.Cu")
	)
	(gr_line
		(start 85.9028 -101.34346)
		(end 85.6996 -101.34346)
		(stroke
			(width 0.2)
			(type default)
		)
		(layer "In1.Cu")
	)
	(gr_arc
		(start 85.9028 -101.14534)
		(mid 85.940517 -101.129717)
		(end 85.95614 -101.092)
		(stroke
			(width 0.2)
			(type default)
		)
		(layer "In1.Cu")
	)
	(gr_line
		(start 85.9028 -100.78466)
		(end 85.6996 -100.78466)
		(stroke
			(width 0.2)
			(type default)
		)
		(layer "In1.Cu")
	)
	(gr_line
		(start 85.95614 -101.6508)
		(end 85.95614 -101.3968)
		(stroke
			(width 0.2)
			(type default)
		)
		(layer "In1.Cu")
	)
	(gr_arc
		(start 85.95614 -101.3968)
		(mid 85.940517 -101.359083)
		(end 85.9028 -101.34346)
		(stroke
			(width 0.2)
			(type default)
		)
		(layer "In1.Cu")
	)
	(gr_line
		(start 85.95614 -101.092)
		(end 85.95614 -100.838)
		(stroke
			(width 0.2)
			(type default)
		)
		(layer "In1.Cu")
	)
	(gr_arc
		(start 85.95614 -100.838)
		(mid 85.940517 -100.800283)
		(end 85.9028 -100.78466)
		(stroke
			(width 0.2)
			(type default)
		)
		(layer "In1.Cu")
	)
	(gr_arc
		(start 86.2076 -441.0456)
		(mid 86.237358 -441.117442)
		(end 86.3092 -441.1472)
		(stroke
			(width 0.2)
			(type default)
		)
		(layer "In1.Cu")
	)
	(gr_line
		(start 86.2076 -439.8264)
		(end 86.2076 -441.0456)
		(stroke
			(width 0.2)
			(type default)
		)
		(layer "In1.Cu")
	)
	(gr_arc
		(start 86.2076 -423.7736)
		(mid 86.237358 -423.845442)
		(end 86.3092 -423.8752)
		(stroke
			(width 0.2)
			(type default)
		)
		(layer "In1.Cu")
	)
	(gr_line
		(start 86.2076 -422.5544)
		(end 86.2076 -423.7736)
		(stroke
			(width 0.2)
			(type default)
		)
		(layer "In1.Cu")
	)
	(gr_arc
		(start 86.2076 -314.4266)
		(mid 86.237358 -314.498442)
		(end 86.3092 -314.5282)
		(stroke
			(width 0.2)
			(type default)
		)
		(layer "In1.Cu")
	)
	(gr_line
		(start 86.2076 -313.2074)
		(end 86.2076 -314.4266)
		(stroke
			(width 0.2)
			(type default)
		)
		(layer "In1.Cu")
	)
	(gr_arc
		(start 86.2076 -220.0656)
		(mid 86.237358 -220.137442)
		(end 86.3092 -220.1672)
		(stroke
			(width 0.2)
			(type default)
		)
		(layer "In1.Cu")
	)
	(gr_line
		(start 86.2076 -218.8464)
		(end 86.2076 -220.0656)
		(stroke
			(width 0.2)
			(type default)
		)
		(layer "In1.Cu")
	)
	(gr_arc
		(start 86.2076 -110.8456)
		(mid 86.237358 -110.917442)
		(end 86.3092 -110.9472)
		(stroke
			(width 0.2)
			(type default)
		)
		(layer "In1.Cu")
	)
	(gr_line
		(start 86.2076 -109.6264)
		(end 86.2076 -110.8456)
		(stroke
			(width 0.2)
			(type default)
		)
		(layer "In1.Cu")
	)
	(gr_arc
		(start 86.2076 -93.5736)
		(mid 86.237358 -93.645442)
		(end 86.3092 -93.6752)
		(stroke
			(width 0.2)
			(type default)
		)
		(layer "In1.Cu")
	)
	(gr_line
		(start 86.2076 -92.3544)
		(end 86.2076 -93.5736)
		(stroke
			(width 0.2)
			(type default)
		)
		(layer "In1.Cu")
	)
	(gr_line
		(start 86.3092 -441.1472)
		(end 87.6808 -441.1472)
		(stroke
			(width 0.2)
			(type default)
		)
		(layer "In1.Cu")
	)
	(gr_arc
		(start 86.3092 -439.7248)
		(mid 86.237358 -439.754558)
		(end 86.2076 -439.8264)
		(stroke
			(width 0.2)
			(type default)
		)
		(layer "In1.Cu")
	)
	(gr_line
		(start 86.3092 -423.8752)
		(end 87.6808 -423.8752)
		(stroke
			(width 0.2)
			(type default)
		)
		(layer "In1.Cu")
	)
	(gr_arc
		(start 86.3092 -422.4528)
		(mid 86.237358 -422.482558)
		(end 86.2076 -422.5544)
		(stroke
			(width 0.2)
			(type default)
		)
		(layer "In1.Cu")
	)
	(gr_line
		(start 86.3092 -314.5282)
		(end 87.6808 -314.5282)
		(stroke
			(width 0.2)
			(type default)
		)
		(layer "In1.Cu")
	)
	(gr_arc
		(start 86.3092 -313.1058)
		(mid 86.237358 -313.135558)
		(end 86.2076 -313.2074)
		(stroke
			(width 0.2)
			(type default)
		)
		(layer "In1.Cu")
	)
	(gr_line
		(start 86.3092 -220.1672)
		(end 87.6808 -220.1672)
		(stroke
			(width 0.2)
			(type default)
		)
		(layer "In1.Cu")
	)
	(gr_arc
		(start 86.3092 -218.7448)
		(mid 86.237358 -218.774558)
		(end 86.2076 -218.8464)
		(stroke
			(width 0.2)
			(type default)
		)
		(layer "In1.Cu")
	)
	(gr_line
		(start 86.3092 -110.9472)
		(end 87.6808 -110.9472)
		(stroke
			(width 0.2)
			(type default)
		)
		(layer "In1.Cu")
	)
	(gr_arc
		(start 86.3092 -109.5248)
		(mid 86.237358 -109.554558)
		(end 86.2076 -109.6264)
		(stroke
			(width 0.2)
			(type default)
		)
		(layer "In1.Cu")
	)
	(gr_line
		(start 86.3092 -93.6752)
		(end 87.6808 -93.6752)
		(stroke
			(width 0.2)
			(type default)
		)
		(layer "In1.Cu")
	)
	(gr_arc
		(start 86.3092 -92.2528)
		(mid 86.237358 -92.282558)
		(end 86.2076 -92.3544)
		(stroke
			(width 0.2)
			(type default)
		)
		(layer "In1.Cu")
	)
	(gr_arc
		(start 87.6808 -441.1472)
		(mid 87.752642 -441.117442)
		(end 87.7824 -441.0456)
		(stroke
			(width 0.2)
			(type default)
		)
		(layer "In1.Cu")
	)
	(gr_line
		(start 87.6808 -439.7248)
		(end 86.3092 -439.7248)
		(stroke
			(width 0.2)
			(type default)
		)
		(layer "In1.Cu")
	)
	(gr_arc
		(start 87.6808 -423.8752)
		(mid 87.752642 -423.845442)
		(end 87.7824 -423.7736)
		(stroke
			(width 0.2)
			(type default)
		)
		(layer "In1.Cu")
	)
	(gr_line
		(start 87.6808 -422.4528)
		(end 86.3092 -422.4528)
		(stroke
			(width 0.2)
			(type default)
		)
		(layer "In1.Cu")
	)
	(gr_arc
		(start 87.6808 -314.5282)
		(mid 87.752642 -314.498442)
		(end 87.7824 -314.4266)
		(stroke
			(width 0.2)
			(type default)
		)
		(layer "In1.Cu")
	)
	(gr_line
		(start 87.6808 -313.1058)
		(end 86.3092 -313.1058)
		(stroke
			(width 0.2)
			(type default)
		)
		(layer "In1.Cu")
	)
	(gr_arc
		(start 87.6808 -220.1672)
		(mid 87.752642 -220.137442)
		(end 87.7824 -220.0656)
		(stroke
			(width 0.2)
			(type default)
		)
		(layer "In1.Cu")
	)
	(gr_line
		(start 87.6808 -218.7448)
		(end 86.3092 -218.7448)
		(stroke
			(width 0.2)
			(type default)
		)
		(layer "In1.Cu")
	)
	(gr_arc
		(start 87.6808 -110.9472)
		(mid 87.752642 -110.917442)
		(end 87.7824 -110.8456)
		(stroke
			(width 0.2)
			(type default)
		)
		(layer "In1.Cu")
	)
	(gr_line
		(start 87.6808 -109.5248)
		(end 86.3092 -109.5248)
		(stroke
			(width 0.2)
			(type default)
		)
		(layer "In1.Cu")
	)
	(gr_arc
		(start 87.6808 -93.6752)
		(mid 87.752642 -93.645442)
		(end 87.7824 -93.5736)
		(stroke
			(width 0.2)
			(type default)
		)
		(layer "In1.Cu")
	)
	(gr_line
		(start 87.6808 -92.2528)
		(end 86.3092 -92.2528)
		(stroke
			(width 0.2)
			(type default)
		)
		(layer "In1.Cu")
	)
	(gr_line
		(start 87.7824 -441.0456)
		(end 87.7824 -439.8264)
		(stroke
			(width 0.2)
			(type default)
		)
		(layer "In1.Cu")
	)
	(gr_arc
		(start 87.7824 -439.8264)
		(mid 87.752642 -439.754558)
		(end 87.6808 -439.7248)
		(stroke
			(width 0.2)
			(type default)
		)
		(layer "In1.Cu")
	)
	(gr_line
		(start 87.7824 -423.7736)
		(end 87.7824 -422.5544)
		(stroke
			(width 0.2)
			(type default)
		)
		(layer "In1.Cu")
	)
	(gr_arc
		(start 87.7824 -422.5544)
		(mid 87.752642 -422.482558)
		(end 87.6808 -422.4528)
		(stroke
			(width 0.2)
			(type default)
		)
		(layer "In1.Cu")
	)
	(gr_line
		(start 87.7824 -314.4266)
		(end 87.7824 -313.2074)
		(stroke
			(width 0.2)
			(type default)
		)
		(layer "In1.Cu")
	)
	(gr_arc
		(start 87.7824 -313.2074)
		(mid 87.752642 -313.135558)
		(end 87.6808 -313.1058)
		(stroke
			(width 0.2)
			(type default)
		)
		(layer "In1.Cu")
	)
	(gr_line
		(start 87.7824 -220.0656)
		(end 87.7824 -218.8464)
		(stroke
			(width 0.2)
			(type default)
		)
		(layer "In1.Cu")
	)
	(gr_arc
		(start 87.7824 -218.8464)
		(mid 87.752642 -218.774558)
		(end 87.6808 -218.7448)
		(stroke
			(width 0.2)
			(type default)
		)
		(layer "In1.Cu")
	)
	(gr_line
		(start 87.7824 -110.8456)
		(end 87.7824 -109.6264)
		(stroke
			(width 0.2)
			(type default)
		)
		(layer "In1.Cu")
	)
	(gr_arc
		(start 87.7824 -109.6264)
		(mid 87.752642 -109.554558)
		(end 87.6808 -109.5248)
		(stroke
			(width 0.2)
			(type default)
		)
		(layer "In1.Cu")
	)
	(gr_line
		(start 87.7824 -93.5736)
		(end 87.7824 -92.3544)
		(stroke
			(width 0.2)
			(type default)
		)
		(layer "In1.Cu")
	)
	(gr_arc
		(start 87.7824 -92.3544)
		(mid 87.752642 -92.282558)
		(end 87.6808 -92.2528)
		(stroke
			(width 0.2)
			(type default)
		)
		(layer "In1.Cu")
	)
	(gr_line
		(start 88.97239 -431.895504)
		(end 90.14079 -431.895504)
		(stroke
			(width 0.2)
			(type default)
		)
		(layer "In1.Cu")
	)
	(gr_line
		(start 88.97239 -430.703736)
		(end 88.97239 -431.895504)
		(stroke
			(width 0.2)
			(type default)
		)
		(layer "In1.Cu")
	)
	(gr_line
		(start 88.97239 -305.277774)
		(end 90.14079 -305.277774)
		(stroke
			(width 0.2)
			(type default)
		)
		(layer "In1.Cu")
	)
	(gr_line
		(start 88.97239 -304.084736)
		(end 88.97239 -305.277774)
		(stroke
			(width 0.2)
			(type default)
		)
		(layer "In1.Cu")
	)
	(gr_line
		(start 88.97239 -210.916266)
		(end 90.14079 -210.916266)
		(stroke
			(width 0.2)
			(type default)
		)
		(layer "In1.Cu")
	)
	(gr_line
		(start 88.97239 -209.72399)
		(end 88.97239 -210.916266)
		(stroke
			(width 0.2)
			(type default)
		)
		(layer "In1.Cu")
	)
	(gr_line
		(start 88.97239 -101.696012)
		(end 90.14079 -101.696012)
		(stroke
			(width 0.2)
			(type default)
		)
		(layer "In1.Cu")
	)
	(gr_line
		(start 88.97239 -100.504244)
		(end 88.97239 -101.696012)
		(stroke
			(width 0.2)
			(type default)
		)
		(layer "In1.Cu")
	)
	(gr_line
		(start 89.88679 -106.60761)
		(end 91.077288 -106.60761)
		(stroke
			(width 0.2)
			(type default)
		)
		(layer "In1.Cu")
	)
	(gr_line
		(start 89.88679 -105.43921)
		(end 89.88679 -106.60761)
		(stroke
			(width 0.2)
			(type default)
		)
		(layer "In1.Cu")
	)
	(gr_line
		(start 89.88806 -97.76079)
		(end 91.07678 -97.76079)
		(stroke
			(width 0.2)
			(type default)
		)
		(layer "In1.Cu")
	)
	(gr_line
		(start 89.88806 -96.59239)
		(end 89.88806 -97.76079)
		(stroke
			(width 0.2)
			(type default)
		)
		(layer "In1.Cu")
	)
	(gr_line
		(start 89.88933 -215.82761)
		(end 91.076526 -215.82761)
		(stroke
			(width 0.2)
			(type default)
		)
		(layer "In1.Cu")
	)
	(gr_line
		(start 89.88933 -214.65921)
		(end 89.88933 -215.82761)
		(stroke
			(width 0.2)
			(type default)
		)
		(layer "In1.Cu")
	)
	(gr_line
		(start 89.889838 -427.958504)
		(end 91.076018 -427.958504)
		(stroke
			(width 0.2)
			(type default)
		)
		(layer "In1.Cu")
	)
	(gr_line
		(start 89.889838 -426.790104)
		(end 89.889838 -427.958504)
		(stroke
			(width 0.2)
			(type default)
		)
		(layer "In1.Cu")
	)
	(gr_line
		(start 89.892632 -436.80761)
		(end 91.076272 -436.80761)
		(stroke
			(width 0.2)
			(type default)
		)
		(layer "In1.Cu")
	)
	(gr_line
		(start 89.892632 -435.63921)
		(end 89.892632 -436.80761)
		(stroke
			(width 0.2)
			(type default)
		)
		(layer "In1.Cu")
	)
	(gr_line
		(start 89.91854 -310.18861)
		(end 91.077288 -310.18861)
		(stroke
			(width 0.2)
			(type default)
		)
		(layer "In1.Cu")
	)
	(gr_line
		(start 89.91854 -309.02021)
		(end 89.91854 -310.18861)
		(stroke
			(width 0.2)
			(type default)
		)
		(layer "In1.Cu")
	)
	(gr_arc
		(start 90.0176 -441.0456)
		(mid 90.047358 -441.117442)
		(end 90.1192 -441.1472)
		(stroke
			(width 0.2)
			(type default)
		)
		(layer "In1.Cu")
	)
	(gr_line
		(start 90.0176 -439.8264)
		(end 90.0176 -441.0456)
		(stroke
			(width 0.2)
			(type default)
		)
		(layer "In1.Cu")
	)
	(gr_arc
		(start 90.0176 -423.7736)
		(mid 90.047358 -423.845442)
		(end 90.1192 -423.8752)
		(stroke
			(width 0.2)
			(type default)
		)
		(layer "In1.Cu")
	)
	(gr_line
		(start 90.0176 -422.5544)
		(end 90.0176 -423.7736)
		(stroke
			(width 0.2)
			(type default)
		)
		(layer "In1.Cu")
	)
	(gr_arc
		(start 90.0176 -314.4266)
		(mid 90.047358 -314.498442)
		(end 90.1192 -314.5282)
		(stroke
			(width 0.2)
			(type default)
		)
		(layer "In1.Cu")
	)
	(gr_line
		(start 90.0176 -313.2074)
		(end 90.0176 -314.4266)
		(stroke
			(width 0.2)
			(type default)
		)
		(layer "In1.Cu")
	)
	(gr_arc
		(start 90.0176 -220.0656)
		(mid 90.047358 -220.137442)
		(end 90.1192 -220.1672)
		(stroke
			(width 0.2)
			(type default)
		)
		(layer "In1.Cu")
	)
	(gr_line
		(start 90.0176 -218.8464)
		(end 90.0176 -220.0656)
		(stroke
			(width 0.2)
			(type default)
		)
		(layer "In1.Cu")
	)
	(gr_arc
		(start 90.0176 -110.8456)
		(mid 90.047358 -110.917442)
		(end 90.1192 -110.9472)
		(stroke
			(width 0.2)
			(type default)
		)
		(layer "In1.Cu")
	)
	(gr_line
		(start 90.0176 -109.6264)
		(end 90.0176 -110.8456)
		(stroke
			(width 0.2)
			(type default)
		)
		(layer "In1.Cu")
	)
	(gr_arc
		(start 90.0176 -93.5736)
		(mid 90.047358 -93.645442)
		(end 90.1192 -93.6752)
		(stroke
			(width 0.2)
			(type default)
		)
		(layer "In1.Cu")
	)
	(gr_line
		(start 90.0176 -92.3544)
		(end 90.0176 -93.5736)
		(stroke
			(width 0.2)
			(type default)
		)
		(layer "In1.Cu")
	)
	(gr_line
		(start 90.1192 -441.1472)
		(end 91.4908 -441.1472)
		(stroke
			(width 0.2)
			(type default)
		)
		(layer "In1.Cu")
	)
	(gr_arc
		(start 90.1192 -439.7248)
		(mid 90.047358 -439.754558)
		(end 90.0176 -439.8264)
		(stroke
			(width 0.2)
			(type default)
		)
		(layer "In1.Cu")
	)
	(gr_line
		(start 90.1192 -423.8752)
		(end 91.4908 -423.8752)
		(stroke
			(width 0.2)
			(type default)
		)
		(layer "In1.Cu")
	)
	(gr_arc
		(start 90.1192 -422.4528)
		(mid 90.047358 -422.482558)
		(end 90.0176 -422.5544)
		(stroke
			(width 0.2)
			(type default)
		)
		(layer "In1.Cu")
	)
	(gr_line
		(start 90.1192 -314.5282)
		(end 91.4908 -314.5282)
		(stroke
			(width 0.2)
			(type default)
		)
		(layer "In1.Cu")
	)
	(gr_arc
		(start 90.1192 -313.1058)
		(mid 90.047358 -313.135558)
		(end 90.0176 -313.2074)
		(stroke
			(width 0.2)
			(type default)
		)
		(layer "In1.Cu")
	)
	(gr_line
		(start 90.1192 -220.1672)
		(end 91.4908 -220.1672)
		(stroke
			(width 0.2)
			(type default)
		)
		(layer "In1.Cu")
	)
	(gr_arc
		(start 90.1192 -218.7448)
		(mid 90.047358 -218.774558)
		(end 90.0176 -218.8464)
		(stroke
			(width 0.2)
			(type default)
		)
		(layer "In1.Cu")
	)
	(gr_line
		(start 90.1192 -110.9472)
		(end 91.4908 -110.9472)
		(stroke
			(width 0.2)
			(type default)
		)
		(layer "In1.Cu")
	)
	(gr_arc
		(start 90.1192 -109.5248)
		(mid 90.047358 -109.554558)
		(end 90.0176 -109.6264)
		(stroke
			(width 0.2)
			(type default)
		)
		(layer "In1.Cu")
	)
	(gr_line
		(start 90.1192 -93.6752)
		(end 91.4908 -93.6752)
		(stroke
			(width 0.2)
			(type default)
		)
		(layer "In1.Cu")
	)
	(gr_arc
		(start 90.1192 -92.2528)
		(mid 90.047358 -92.282558)
		(end 90.0176 -92.3544)
		(stroke
			(width 0.2)
			(type default)
		)
		(layer "In1.Cu")
	)
	(gr_line
		(start 90.14079 -431.895504)
		(end 90.14079 -430.703736)
		(stroke
			(width 0.2)
			(type default)
		)
		(layer "In1.Cu")
	)
	(gr_line
		(start 90.14079 -430.703736)
		(end 88.97239 -430.703736)
		(stroke
			(width 0.2)
			(type default)
		)
		(layer "In1.Cu")
	)
	(gr_line
		(start 90.14079 -305.277774)
		(end 90.14079 -304.084736)
		(stroke
			(width 0.2)
			(type default)
		)
		(layer "In1.Cu")
	)
	(gr_line
		(start 90.14079 -304.084736)
		(end 88.97239 -304.084736)
		(stroke
			(width 0.2)
			(type default)
		)
		(layer "In1.Cu")
	)
	(gr_line
		(start 90.14079 -210.916266)
		(end 90.14079 -209.72399)
		(stroke
			(width 0.2)
			(type default)
		)
		(layer "In1.Cu")
	)
	(gr_line
		(start 90.14079 -209.72399)
		(end 88.97239 -209.72399)
		(stroke
			(width 0.2)
			(type default)
		)
		(layer "In1.Cu")
	)
	(gr_line
		(start 90.14079 -101.696012)
		(end 90.14079 -100.504244)
		(stroke
			(width 0.2)
			(type default)
		)
		(layer "In1.Cu")
	)
	(gr_line
		(start 90.14079 -100.504244)
		(end 88.97239 -100.504244)
		(stroke
			(width 0.2)
			(type default)
		)
		(layer "In1.Cu")
	)
	(gr_line
		(start 91.076018 -427.958504)
		(end 91.076018 -426.790104)
		(stroke
			(width 0.2)
			(type default)
		)
		(layer "In1.Cu")
	)
	(gr_line
		(start 91.076018 -426.790104)
		(end 89.889838 -426.790104)
		(stroke
			(width 0.2)
			(type default)
		)
		(layer "In1.Cu")
	)
	(gr_line
		(start 91.076272 -436.80761)
		(end 91.076272 -435.63921)
		(stroke
			(width 0.2)
			(type default)
		)
		(layer "In1.Cu")
	)
	(gr_line
		(start 91.076272 -435.63921)
		(end 89.892632 -435.63921)
		(stroke
			(width 0.2)
			(type default)
		)
		(layer "In1.Cu")
	)
	(gr_line
		(start 91.076526 -215.82761)
		(end 91.076526 -214.65921)
		(stroke
			(width 0.2)
			(type default)
		)
		(layer "In1.Cu")
	)
	(gr_line
		(start 91.076526 -214.65921)
		(end 89.88933 -214.65921)
		(stroke
			(width 0.2)
			(type default)
		)
		(layer "In1.Cu")
	)
	(gr_line
		(start 91.07678 -97.76079)
		(end 91.07678 -96.59239)
		(stroke
			(width 0.2)
			(type default)
		)
		(layer "In1.Cu")
	)
	(gr_line
		(start 91.07678 -96.59239)
		(end 89.88806 -96.59239)
		(stroke
			(width 0.2)
			(type default)
		)
		(layer "In1.Cu")
	)
	(gr_line
		(start 91.077288 -310.18861)
		(end 91.077288 -309.02021)
		(stroke
			(width 0.2)
			(type default)
		)
		(layer "In1.Cu")
	)
	(gr_line
		(start 91.077288 -309.02021)
		(end 89.91854 -309.02021)
		(stroke
			(width 0.2)
			(type default)
		)
		(layer "In1.Cu")
	)
	(gr_line
		(start 91.077288 -106.60761)
		(end 91.077288 -105.43921)
		(stroke
			(width 0.2)
			(type default)
		)
		(layer "In1.Cu")
	)
	(gr_line
		(start 91.077288 -105.43921)
		(end 89.88679 -105.43921)
		(stroke
			(width 0.2)
			(type default)
		)
		(layer "In1.Cu")
	)
	(gr_arc
		(start 91.4908 -441.1472)
		(mid 91.562642 -441.117442)
		(end 91.5924 -441.0456)
		(stroke
			(width 0.2)
			(type default)
		)
		(layer "In1.Cu")
	)
	(gr_line
		(start 91.4908 -439.7248)
		(end 90.1192 -439.7248)
		(stroke
			(width 0.2)
			(type default)
		)
		(layer "In1.Cu")
	)
	(gr_arc
		(start 91.4908 -423.8752)
		(mid 91.562642 -423.845442)
		(end 91.5924 -423.7736)
		(stroke
			(width 0.2)
			(type default)
		)
		(layer "In1.Cu")
	)
	(gr_line
		(start 91.4908 -422.4528)
		(end 90.1192 -422.4528)
		(stroke
			(width 0.2)
			(type default)
		)
		(layer "In1.Cu")
	)
	(gr_arc
		(start 91.4908 -314.5282)
		(mid 91.562642 -314.498442)
		(end 91.5924 -314.4266)
		(stroke
			(width 0.2)
			(type default)
		)
		(layer "In1.Cu")
	)
	(gr_line
		(start 91.4908 -313.1058)
		(end 90.1192 -313.1058)
		(stroke
			(width 0.2)
			(type default)
		)
		(layer "In1.Cu")
	)
	(gr_arc
		(start 91.4908 -220.1672)
		(mid 91.562642 -220.137442)
		(end 91.5924 -220.0656)
		(stroke
			(width 0.2)
			(type default)
		)
		(layer "In1.Cu")
	)
	(gr_line
		(start 91.4908 -218.7448)
		(end 90.1192 -218.7448)
		(stroke
			(width 0.2)
			(type default)
		)
		(layer "In1.Cu")
	)
	(gr_arc
		(start 91.4908 -110.9472)
		(mid 91.562642 -110.917442)
		(end 91.5924 -110.8456)
		(stroke
			(width 0.2)
			(type default)
		)
		(layer "In1.Cu")
	)
	(gr_line
		(start 91.4908 -109.5248)
		(end 90.1192 -109.5248)
		(stroke
			(width 0.2)
			(type default)
		)
		(layer "In1.Cu")
	)
	(gr_arc
		(start 91.4908 -93.6752)
		(mid 91.562642 -93.645442)
		(end 91.5924 -93.5736)
		(stroke
			(width 0.2)
			(type default)
		)
		(layer "In1.Cu")
	)
	(gr_line
		(start 91.4908 -92.2528)
		(end 90.1192 -92.2528)
		(stroke
			(width 0.2)
			(type default)
		)
		(layer "In1.Cu")
	)
	(gr_line
		(start 91.5924 -441.0456)
		(end 91.5924 -439.8264)
		(stroke
			(width 0.2)
			(type default)
		)
		(layer "In1.Cu")
	)
	(gr_arc
		(start 91.5924 -439.8264)
		(mid 91.562642 -439.754558)
		(end 91.4908 -439.7248)
		(stroke
			(width 0.2)
			(type default)
		)
		(layer "In1.Cu")
	)
	(gr_line
		(start 91.5924 -423.7736)
		(end 91.5924 -422.5544)
		(stroke
			(width 0.2)
			(type default)
		)
		(layer "In1.Cu")
	)
	(gr_arc
		(start 91.5924 -422.5544)
		(mid 91.562642 -422.482558)
		(end 91.4908 -422.4528)
		(stroke
			(width 0.2)
			(type default)
		)
		(layer "In1.Cu")
	)
	(gr_line
		(start 91.5924 -314.4266)
		(end 91.5924 -313.2074)
		(stroke
			(width 0.2)
			(type default)
		)
		(layer "In1.Cu")
	)
	(gr_arc
		(start 91.5924 -313.2074)
		(mid 91.562642 -313.135558)
		(end 91.4908 -313.1058)
		(stroke
			(width 0.2)
			(type default)
		)
		(layer "In1.Cu")
	)
	(gr_line
		(start 91.5924 -220.0656)
		(end 91.5924 -218.8464)
		(stroke
			(width 0.2)
			(type default)
		)
		(layer "In1.Cu")
	)
	(gr_arc
		(start 91.5924 -218.8464)
		(mid 91.562642 -218.774558)
		(end 91.4908 -218.7448)
		(stroke
			(width 0.2)
			(type default)
		)
		(layer "In1.Cu")
	)
	(gr_line
		(start 91.5924 -110.8456)
		(end 91.5924 -109.6264)
		(stroke
			(width 0.2)
			(type default)
		)
		(layer "In1.Cu")
	)
	(gr_arc
		(start 91.5924 -109.6264)
		(mid 91.562642 -109.554558)
		(end 91.4908 -109.5248)
		(stroke
			(width 0.2)
			(type default)
		)
		(layer "In1.Cu")
	)
	(gr_line
		(start 91.5924 -93.5736)
		(end 91.5924 -92.3544)
		(stroke
			(width 0.2)
			(type default)
		)
		(layer "In1.Cu")
	)
	(gr_arc
		(start 91.5924 -92.3544)
		(mid 91.562642 -92.282558)
		(end 91.4908 -92.2528)
		(stroke
			(width 0.2)
			(type default)
		)
		(layer "In1.Cu")
	)
	(gr_line
		(start 91.882722 -427.96079)
		(end 93.074998 -427.96079)
		(stroke
			(width 0.2)
			(type default)
		)
		(layer "In1.Cu")
	)
	(gr_line
		(start 91.882722 -426.79239)
		(end 91.882722 -427.96079)
		(stroke
			(width 0.2)
			(type default)
		)
		(layer "In1.Cu")
	)
	(gr_line
		(start 91.882722 -97.76079)
		(end 93.075252 -97.76079)
		(stroke
			(width 0.2)
			(type default)
		)
		(layer "In1.Cu")
	)
	(gr_line
		(start 91.882722 -96.59239)
		(end 91.882722 -97.76079)
		(stroke
			(width 0.2)
			(type default)
		)
		(layer "In1.Cu")
	)
	(gr_line
		(start 91.882976 -215.82761)
		(end 93.074236 -215.82761)
		(stroke
			(width 0.2)
			(type default)
		)
		(layer "In1.Cu")
	)
	(gr_line
		(start 91.882976 -214.65921)
		(end 91.882976 -215.82761)
		(stroke
			(width 0.2)
			(type default)
		)
		(layer "In1.Cu")
	)
	(gr_line
		(start 91.883484 -106.60761)
		(end 93.074998 -106.60761)
		(stroke
			(width 0.2)
			(type default)
		)
		(layer "In1.Cu")
	)
	(gr_line
		(start 91.883484 -105.43921)
		(end 91.883484 -106.60761)
		(stroke
			(width 0.2)
			(type default)
		)
		(layer "In1.Cu")
	)
	(gr_line
		(start 91.883738 -436.80761)
		(end 93.074744 -436.80761)
		(stroke
			(width 0.2)
			(type default)
		)
		(layer "In1.Cu")
	)
	(gr_line
		(start 91.883738 -435.63921)
		(end 91.883738 -436.80761)
		(stroke
			(width 0.2)
			(type default)
		)
		(layer "In1.Cu")
	)
	(gr_line
		(start 91.883992 -310.18861)
		(end 93.073728 -310.18861)
		(stroke
			(width 0.2)
			(type default)
		)
		(layer "In1.Cu")
	)
	(gr_line
		(start 91.883992 -309.02021)
		(end 91.883992 -310.18861)
		(stroke
			(width 0.2)
			(type default)
		)
		(layer "In1.Cu")
	)
	(gr_line
		(start 93.073728 -310.18861)
		(end 93.073728 -309.02021)
		(stroke
			(width 0.2)
			(type default)
		)
		(layer "In1.Cu")
	)
	(gr_line
		(start 93.073728 -309.02021)
		(end 91.883992 -309.02021)
		(stroke
			(width 0.2)
			(type default)
		)
		(layer "In1.Cu")
	)
	(gr_line
		(start 93.074236 -215.82761)
		(end 93.074236 -214.65921)
		(stroke
			(width 0.2)
			(type default)
		)
		(layer "In1.Cu")
	)
	(gr_line
		(start 93.074236 -214.65921)
		(end 91.882976 -214.65921)
		(stroke
			(width 0.2)
			(type default)
		)
		(layer "In1.Cu")
	)
	(gr_line
		(start 93.074744 -436.80761)
		(end 93.074744 -435.63921)
		(stroke
			(width 0.2)
			(type default)
		)
		(layer "In1.Cu")
	)
	(gr_line
		(start 93.074744 -435.63921)
		(end 91.883738 -435.63921)
		(stroke
			(width 0.2)
			(type default)
		)
		(layer "In1.Cu")
	)
	(gr_line
		(start 93.074998 -427.96079)
		(end 93.074998 -426.79239)
		(stroke
			(width 0.2)
			(type default)
		)
		(layer "In1.Cu")
	)
	(gr_line
		(start 93.074998 -426.79239)
		(end 91.882722 -426.79239)
		(stroke
			(width 0.2)
			(type default)
		)
		(layer "In1.Cu")
	)
	(gr_line
		(start 93.074998 -106.60761)
		(end 93.074998 -105.43921)
		(stroke
			(width 0.2)
			(type default)
		)
		(layer "In1.Cu")
	)
	(gr_line
		(start 93.074998 -105.43921)
		(end 91.883484 -105.43921)
		(stroke
			(width 0.2)
			(type default)
		)
		(layer "In1.Cu")
	)
	(gr_line
		(start 93.075252 -97.76079)
		(end 93.075252 -96.59239)
		(stroke
			(width 0.2)
			(type default)
		)
		(layer "In1.Cu")
	)
	(gr_line
		(start 93.075252 -96.59239)
		(end 91.882722 -96.59239)
		(stroke
			(width 0.2)
			(type default)
		)
		(layer "In1.Cu")
	)
	(gr_arc
		(start 93.5736 -202.7936)
		(mid 93.603358 -202.865442)
		(end 93.6752 -202.8952)
		(stroke
			(width 0.2)
			(type default)
		)
		(layer "In1.Cu")
	)
	(gr_line
		(start 93.5736 -201.5744)
		(end 93.5736 -202.7936)
		(stroke
			(width 0.2)
			(type default)
		)
		(layer "In1.Cu")
	)
	(gr_line
		(start 93.6752 -202.8952)
		(end 95.0468 -202.8952)
		(stroke
			(width 0.2)
			(type default)
		)
		(layer "In1.Cu")
	)
	(gr_arc
		(start 93.6752 -201.4728)
		(mid 93.603358 -201.502558)
		(end 93.5736 -201.5744)
		(stroke
			(width 0.2)
			(type default)
		)
		(layer "In1.Cu")
	)
	(gr_line
		(start 94.382844 -206.98079)
		(end 95.577406 -206.98079)
		(stroke
			(width 0.2)
			(type default)
		)
		(layer "In1.Cu")
	)
	(gr_line
		(start 94.382844 -205.81239)
		(end 94.382844 -206.98079)
		(stroke
			(width 0.2)
			(type default)
		)
		(layer "In1.Cu")
	)
	(gr_line
		(start 94.383098 -301.34179)
		(end 95.576898 -301.34179)
		(stroke
			(width 0.2)
			(type default)
		)
		(layer "In1.Cu")
	)
	(gr_line
		(start 94.383098 -300.17339)
		(end 94.383098 -301.34179)
		(stroke
			(width 0.2)
			(type default)
		)
		(layer "In1.Cu")
	)
	(gr_line
		(start 94.383098 -106.60761)
		(end 95.577152 -106.60761)
		(stroke
			(width 0.2)
			(type default)
		)
		(layer "In1.Cu")
	)
	(gr_line
		(start 94.383098 -105.43921)
		(end 94.383098 -106.60761)
		(stroke
			(width 0.2)
			(type default)
		)
		(layer "In1.Cu")
	)
	(gr_line
		(start 94.383098 -97.76079)
		(end 95.577152 -97.76079)
		(stroke
			(width 0.2)
			(type default)
		)
		(layer "In1.Cu")
	)
	(gr_line
		(start 94.383098 -96.59239)
		(end 94.383098 -97.76079)
		(stroke
			(width 0.2)
			(type default)
		)
		(layer "In1.Cu")
	)
	(gr_line
		(start 94.383352 -215.82761)
		(end 95.576136 -215.82761)
		(stroke
			(width 0.2)
			(type default)
		)
		(layer "In1.Cu")
	)
	(gr_line
		(start 94.383352 -214.65921)
		(end 94.383352 -215.82761)
		(stroke
			(width 0.2)
			(type default)
		)
		(layer "In1.Cu")
	)
	(gr_line
		(start 94.384876 -310.18861)
		(end 95.575628 -310.18861)
		(stroke
			(width 0.2)
			(type default)
		)
		(layer "In1.Cu")
	)
	(gr_line
		(start 94.384876 -309.02021)
		(end 94.384876 -310.18861)
		(stroke
			(width 0.2)
			(type default)
		)
		(layer "In1.Cu")
	)
	(gr_arc
		(start 95.0468 -202.8952)
		(mid 95.118642 -202.865442)
		(end 95.1484 -202.7936)
		(stroke
			(width 0.2)
			(type default)
		)
		(layer "In1.Cu")
	)
	(gr_line
		(start 95.0468 -201.4728)
		(end 93.6752 -201.4728)
		(stroke
			(width 0.2)
			(type default)
		)
		(layer "In1.Cu")
	)
	(gr_line
		(start 95.1484 -202.7936)
		(end 95.1484 -201.5744)
		(stroke
			(width 0.2)
			(type default)
		)
		(layer "In1.Cu")
	)
	(gr_arc
		(start 95.1484 -201.5744)
		(mid 95.118642 -201.502558)
		(end 95.0468 -201.4728)
		(stroke
			(width 0.2)
			(type default)
		)
		(layer "In1.Cu")
	)
	(gr_arc
		(start 95.2246 -314.4266)
		(mid 95.254358 -314.498442)
		(end 95.3262 -314.5282)
		(stroke
			(width 0.2)
			(type default)
		)
		(layer "In1.Cu")
	)
	(gr_line
		(start 95.2246 -313.2074)
		(end 95.2246 -314.4266)
		(stroke
			(width 0.2)
			(type default)
		)
		(layer "In1.Cu")
	)
	(gr_arc
		(start 95.2246 -297.1546)
		(mid 95.254358 -297.226442)
		(end 95.3262 -297.2562)
		(stroke
			(width 0.2)
			(type default)
		)
		(layer "In1.Cu")
	)
	(gr_line
		(start 95.2246 -295.9354)
		(end 95.2246 -297.1546)
		(stroke
			(width 0.2)
			(type default)
		)
		(layer "In1.Cu")
	)
	(gr_arc
		(start 95.2246 -220.0656)
		(mid 95.254358 -220.137442)
		(end 95.3262 -220.1672)
		(stroke
			(width 0.2)
			(type default)
		)
		(layer "In1.Cu")
	)
	(gr_line
		(start 95.2246 -218.8464)
		(end 95.2246 -220.0656)
		(stroke
			(width 0.2)
			(type default)
		)
		(layer "In1.Cu")
	)
	(gr_arc
		(start 95.2246 -110.8456)
		(mid 95.254358 -110.917442)
		(end 95.3262 -110.9472)
		(stroke
			(width 0.2)
			(type default)
		)
		(layer "In1.Cu")
	)
	(gr_line
		(start 95.2246 -109.6264)
		(end 95.2246 -110.8456)
		(stroke
			(width 0.2)
			(type default)
		)
		(layer "In1.Cu")
	)
	(gr_arc
		(start 95.2246 -93.5736)
		(mid 95.254358 -93.645442)
		(end 95.3262 -93.6752)
		(stroke
			(width 0.2)
			(type default)
		)
		(layer "In1.Cu")
	)
	(gr_line
		(start 95.2246 -92.3544)
		(end 95.2246 -93.5736)
		(stroke
			(width 0.2)
			(type default)
		)
		(layer "In1.Cu")
	)
	(gr_line
		(start 95.3262 -314.5282)
		(end 96.6978 -314.5282)
		(stroke
			(width 0.2)
			(type default)
		)
		(layer "In1.Cu")
	)
	(gr_arc
		(start 95.3262 -313.1058)
		(mid 95.254358 -313.135558)
		(end 95.2246 -313.2074)
		(stroke
			(width 0.2)
			(type default)
		)
		(layer "In1.Cu")
	)
	(gr_line
		(start 95.3262 -297.2562)
		(end 96.6978 -297.2562)
		(stroke
			(width 0.2)
			(type default)
		)
		(layer "In1.Cu")
	)
	(gr_arc
		(start 95.3262 -295.8338)
		(mid 95.254358 -295.863558)
		(end 95.2246 -295.9354)
		(stroke
			(width 0.2)
			(type default)
		)
		(layer "In1.Cu")
	)
	(gr_line
		(start 95.3262 -220.1672)
		(end 96.6978 -220.1672)
		(stroke
			(width 0.2)
			(type default)
		)
		(layer "In1.Cu")
	)
	(gr_arc
		(start 95.3262 -218.7448)
		(mid 95.254358 -218.774558)
		(end 95.2246 -218.8464)
		(stroke
			(width 0.2)
			(type default)
		)
		(layer "In1.Cu")
	)
	(gr_line
		(start 95.3262 -110.9472)
		(end 96.6978 -110.9472)
		(stroke
			(width 0.2)
			(type default)
		)
		(layer "In1.Cu")
	)
	(gr_arc
		(start 95.3262 -109.5248)
		(mid 95.254358 -109.554558)
		(end 95.2246 -109.6264)
		(stroke
			(width 0.2)
			(type default)
		)
		(layer "In1.Cu")
	)
	(gr_line
		(start 95.3262 -93.6752)
		(end 96.6978 -93.6752)
		(stroke
			(width 0.2)
			(type default)
		)
		(layer "In1.Cu")
	)
	(gr_arc
		(start 95.3262 -92.2528)
		(mid 95.254358 -92.282558)
		(end 95.2246 -92.3544)
		(stroke
			(width 0.2)
			(type default)
		)
		(layer "In1.Cu")
	)
	(gr_line
		(start 95.575628 -310.18861)
		(end 95.575628 -309.02021)
		(stroke
			(width 0.2)
			(type default)
		)
		(layer "In1.Cu")
	)
	(gr_line
		(start 95.575628 -309.02021)
		(end 94.384876 -309.02021)
		(stroke
			(width 0.2)
			(type default)
		)
		(layer "In1.Cu")
	)
	(gr_line
		(start 95.576136 -215.82761)
		(end 95.576136 -214.65921)
		(stroke
			(width 0.2)
			(type default)
		)
		(layer "In1.Cu")
	)
	(gr_line
		(start 95.576136 -214.65921)
		(end 94.383352 -214.65921)
		(stroke
			(width 0.2)
			(type default)
		)
		(layer "In1.Cu")
	)
	(gr_line
		(start 95.576898 -301.34179)
		(end 95.576898 -300.17339)
		(stroke
			(width 0.2)
			(type default)
		)
		(layer "In1.Cu")
	)
	(gr_line
		(start 95.576898 -300.17339)
		(end 94.383098 -300.17339)
		(stroke
			(width 0.2)
			(type default)
		)
		(layer "In1.Cu")
	)
	(gr_line
		(start 95.577152 -106.60761)
		(end 95.577152 -105.43921)
		(stroke
			(width 0.2)
			(type default)
		)
		(layer "In1.Cu")
	)
	(gr_line
		(start 95.577152 -105.43921)
		(end 94.383098 -105.43921)
		(stroke
			(width 0.2)
			(type default)
		)
		(layer "In1.Cu")
	)
	(gr_line
		(start 95.577152 -97.76079)
		(end 95.577152 -96.59239)
		(stroke
			(width 0.2)
			(type default)
		)
		(layer "In1.Cu")
	)
	(gr_line
		(start 95.577152 -96.59239)
		(end 94.383098 -96.59239)
		(stroke
			(width 0.2)
			(type default)
		)
		(layer "In1.Cu")
	)
	(gr_line
		(start 95.577406 -206.98079)
		(end 95.577406 -205.81239)
		(stroke
			(width 0.2)
			(type default)
		)
		(layer "In1.Cu")
	)
	(gr_line
		(start 95.577406 -205.81239)
		(end 94.382844 -205.81239)
		(stroke
			(width 0.2)
			(type default)
		)
		(layer "In1.Cu")
	)
	(gr_line
		(start 96.383348 -206.98079)
		(end 97.577148 -206.98079)
		(stroke
			(width 0.2)
			(type default)
		)
		(layer "In1.Cu")
	)
	(gr_line
		(start 96.383348 -205.81239)
		(end 96.383348 -206.98079)
		(stroke
			(width 0.2)
			(type default)
		)
		(layer "In1.Cu")
	)
	(gr_line
		(start 96.383348 -106.60761)
		(end 97.577148 -106.60761)
		(stroke
			(width 0.2)
			(type default)
		)
		(layer "In1.Cu")
	)
	(gr_line
		(start 96.383348 -105.43921)
		(end 96.383348 -106.60761)
		(stroke
			(width 0.2)
			(type default)
		)
		(layer "In1.Cu")
	)
	(gr_line
		(start 96.383602 -215.82761)
		(end 97.575878 -215.82761)
		(stroke
			(width 0.2)
			(type default)
		)
		(layer "In1.Cu")
	)
	(gr_line
		(start 96.383602 -214.65921)
		(end 96.383602 -215.82761)
		(stroke
			(width 0.2)
			(type default)
		)
		(layer "In1.Cu")
	)
	(gr_line
		(start 96.383856 -97.76079)
		(end 97.577148 -97.76079)
		(stroke
			(width 0.2)
			(type default)
		)
		(layer "In1.Cu")
	)
	(gr_line
		(start 96.383856 -96.59239)
		(end 96.383856 -97.76079)
		(stroke
			(width 0.2)
			(type default)
		)
		(layer "In1.Cu")
	)
	(gr_line
		(start 96.384364 -310.18861)
		(end 97.575624 -310.18861)
		(stroke
			(width 0.2)
			(type default)
		)
		(layer "In1.Cu")
	)
	(gr_line
		(start 96.384364 -309.02021)
		(end 96.384364 -310.18861)
		(stroke
			(width 0.2)
			(type default)
		)
		(layer "In1.Cu")
	)
	(gr_line
		(start 96.384618 -301.34179)
		(end 97.574862 -301.34179)
		(stroke
			(width 0.2)
			(type default)
		)
		(layer "In1.Cu")
	)
	(gr_line
		(start 96.384618 -300.17339)
		(end 96.384618 -301.34179)
		(stroke
			(width 0.2)
			(type default)
		)
		(layer "In1.Cu")
	)
	(gr_arc
		(start 96.6978 -314.5282)
		(mid 96.769642 -314.498442)
		(end 96.7994 -314.4266)
		(stroke
			(width 0.2)
			(type default)
		)
		(layer "In1.Cu")
	)
	(gr_line
		(start 96.6978 -313.1058)
		(end 95.3262 -313.1058)
		(stroke
			(width 0.2)
			(type default)
		)
		(layer "In1.Cu")
	)
	(gr_arc
		(start 96.6978 -297.2562)
		(mid 96.769642 -297.226442)
		(end 96.7994 -297.1546)
		(stroke
			(width 0.2)
			(type default)
		)
		(layer "In1.Cu")
	)
	(gr_line
		(start 96.6978 -295.8338)
		(end 95.3262 -295.8338)
		(stroke
			(width 0.2)
			(type default)
		)
		(layer "In1.Cu")
	)
	(gr_arc
		(start 96.6978 -220.1672)
		(mid 96.769642 -220.137442)
		(end 96.7994 -220.0656)
		(stroke
			(width 0.2)
			(type default)
		)
		(layer "In1.Cu")
	)
	(gr_line
		(start 96.6978 -218.7448)
		(end 95.3262 -218.7448)
		(stroke
			(width 0.2)
			(type default)
		)
		(layer "In1.Cu")
	)
	(gr_arc
		(start 96.6978 -110.9472)
		(mid 96.769642 -110.917442)
		(end 96.7994 -110.8456)
		(stroke
			(width 0.2)
			(type default)
		)
		(layer "In1.Cu")
	)
	(gr_line
		(start 96.6978 -109.5248)
		(end 95.3262 -109.5248)
		(stroke
			(width 0.2)
			(type default)
		)
		(layer "In1.Cu")
	)
	(gr_arc
		(start 96.6978 -93.6752)
		(mid 96.769642 -93.645442)
		(end 96.7994 -93.5736)
		(stroke
			(width 0.2)
			(type default)
		)
		(layer "In1.Cu")
	)
	(gr_line
		(start 96.6978 -92.2528)
		(end 95.3262 -92.2528)
		(stroke
			(width 0.2)
			(type default)
		)
		(layer "In1.Cu")
	)
	(gr_line
		(start 96.7994 -314.4266)
		(end 96.7994 -313.2074)
		(stroke
			(width 0.2)
			(type default)
		)
		(layer "In1.Cu")
	)
	(gr_arc
		(start 96.7994 -313.2074)
		(mid 96.769642 -313.135558)
		(end 96.6978 -313.1058)
		(stroke
			(width 0.2)
			(type default)
		)
		(layer "In1.Cu")
	)
	(gr_line
		(start 96.7994 -297.1546)
		(end 96.7994 -295.9354)
		(stroke
			(width 0.2)
			(type default)
		)
		(layer "In1.Cu")
	)
	(gr_arc
		(start 96.7994 -295.9354)
		(mid 96.769642 -295.863558)
		(end 96.6978 -295.8338)
		(stroke
			(width 0.2)
			(type default)
		)
		(layer "In1.Cu")
	)
	(gr_line
		(start 96.7994 -220.0656)
		(end 96.7994 -218.8464)
		(stroke
			(width 0.2)
			(type default)
		)
		(layer "In1.Cu")
	)
	(gr_arc
		(start 96.7994 -218.8464)
		(mid 96.769642 -218.774558)
		(end 96.6978 -218.7448)
		(stroke
			(width 0.2)
			(type default)
		)
		(layer "In1.Cu")
	)
	(gr_line
		(start 96.7994 -110.8456)
		(end 96.7994 -109.6264)
		(stroke
			(width 0.2)
			(type default)
		)
		(layer "In1.Cu")
	)
	(gr_arc
		(start 96.7994 -109.6264)
		(mid 96.769642 -109.554558)
		(end 96.6978 -109.5248)
		(stroke
			(width 0.2)
			(type default)
		)
		(layer "In1.Cu")
	)
	(gr_line
		(start 96.7994 -93.5736)
		(end 96.7994 -92.3544)
		(stroke
			(width 0.2)
			(type default)
		)
		(layer "In1.Cu")
	)
	(gr_arc
		(start 96.7994 -92.3544)
		(mid 96.769642 -92.282558)
		(end 96.6978 -92.2528)
		(stroke
			(width 0.2)
			(type default)
		)
		(layer "In1.Cu")
	)
	(gr_arc
		(start 97.3836 -202.7936)
		(mid 97.413358 -202.865442)
		(end 97.4852 -202.8952)
		(stroke
			(width 0.2)
			(type default)
		)
		(layer "In1.Cu")
	)
	(gr_line
		(start 97.3836 -201.5744)
		(end 97.3836 -202.7936)
		(stroke
			(width 0.2)
			(type default)
		)
		(layer "In1.Cu")
	)
	(gr_line
		(start 97.4852 -202.8952)
		(end 98.8568 -202.8952)
		(stroke
			(width 0.2)
			(type default)
		)
		(layer "In1.Cu")
	)
	(gr_arc
		(start 97.4852 -201.4728)
		(mid 97.413358 -201.502558)
		(end 97.3836 -201.5744)
		(stroke
			(width 0.2)
			(type default)
		)
		(layer "In1.Cu")
	)
	(gr_line
		(start 97.574862 -301.34179)
		(end 97.574862 -300.17339)
		(stroke
			(width 0.2)
			(type default)
		)
		(layer "In1.Cu")
	)
	(gr_line
		(start 97.574862 -300.17339)
		(end 96.384618 -300.17339)
		(stroke
			(width 0.2)
			(type default)
		)
		(layer "In1.Cu")
	)
	(gr_line
		(start 97.575624 -310.18861)
		(end 97.575624 -309.02021)
		(stroke
			(width 0.2)
			(type default)
		)
		(layer "In1.Cu")
	)
	(gr_line
		(start 97.575624 -309.02021)
		(end 96.384364 -309.02021)
		(stroke
			(width 0.2)
			(type default)
		)
		(layer "In1.Cu")
	)
	(gr_line
		(start 97.575878 -215.82761)
		(end 97.575878 -214.65921)
		(stroke
			(width 0.2)
			(type default)
		)
		(layer "In1.Cu")
	)
	(gr_line
		(start 97.575878 -214.65921)
		(end 96.383602 -214.65921)
		(stroke
			(width 0.2)
			(type default)
		)
		(layer "In1.Cu")
	)
	(gr_line
		(start 97.577148 -206.98079)
		(end 97.577148 -205.81239)
		(stroke
			(width 0.2)
			(type default)
		)
		(layer "In1.Cu")
	)
	(gr_line
		(start 97.577148 -205.81239)
		(end 96.383348 -205.81239)
		(stroke
			(width 0.2)
			(type default)
		)
		(layer "In1.Cu")
	)
	(gr_line
		(start 97.577148 -106.60761)
		(end 97.577148 -105.43921)
		(stroke
			(width 0.2)
			(type default)
		)
		(layer "In1.Cu")
	)
	(gr_line
		(start 97.577148 -105.43921)
		(end 96.383348 -105.43921)
		(stroke
			(width 0.2)
			(type default)
		)
		(layer "In1.Cu")
	)
	(gr_line
		(start 97.577148 -97.76079)
		(end 97.577148 -96.59239)
		(stroke
			(width 0.2)
			(type default)
		)
		(layer "In1.Cu")
	)
	(gr_line
		(start 97.577148 -96.59239)
		(end 96.383856 -96.59239)
		(stroke
			(width 0.2)
			(type default)
		)
		(layer "In1.Cu")
	)
	(gr_line
		(start 97.81921 -435.395116)
		(end 98.98761 -435.395116)
		(stroke
			(width 0.2)
			(type default)
		)
		(layer "In1.Cu")
	)
	(gr_line
		(start 97.81921 -434.203856)
		(end 97.81921 -435.395116)
		(stroke
			(width 0.2)
			(type default)
		)
		(layer "In1.Cu")
	)
	(gr_line
		(start 97.81921 -433.396898)
		(end 98.98761 -433.396898)
		(stroke
			(width 0.2)
			(type default)
		)
		(layer "In1.Cu")
	)
	(gr_line
		(start 97.81921 -432.202844)
		(end 97.81921 -433.396898)
		(stroke
			(width 0.2)
			(type default)
		)
		(layer "In1.Cu")
	)
	(gr_line
		(start 97.81921 -308.777894)
		(end 98.98761 -308.777894)
		(stroke
			(width 0.2)
			(type default)
		)
		(layer "In1.Cu")
	)
	(gr_line
		(start 97.81921 -307.58638)
		(end 97.81921 -308.777894)
		(stroke
			(width 0.2)
			(type default)
		)
		(layer "In1.Cu")
	)
	(gr_line
		(start 97.81921 -306.777136)
		(end 98.98761 -306.777136)
		(stroke
			(width 0.2)
			(type default)
		)
		(layer "In1.Cu")
	)
	(gr_line
		(start 97.81921 -305.58486)
		(end 97.81921 -306.777136)
		(stroke
			(width 0.2)
			(type default)
		)
		(layer "In1.Cu")
	)
	(gr_line
		(start 97.81921 -210.416648)
		(end 98.98761 -210.416648)
		(stroke
			(width 0.2)
			(type default)
		)
		(layer "In1.Cu")
	)
	(gr_line
		(start 97.81921 -209.222594)
		(end 97.81921 -210.416648)
		(stroke
			(width 0.2)
			(type default)
		)
		(layer "In1.Cu")
	)
	(gr_line
		(start 97.81921 -208.416398)
		(end 98.98761 -208.416398)
		(stroke
			(width 0.2)
			(type default)
		)
		(layer "In1.Cu")
	)
	(gr_line
		(start 97.81921 -207.223106)
		(end 97.81921 -208.416398)
		(stroke
			(width 0.2)
			(type default)
		)
		(layer "In1.Cu")
	)
	(gr_arc
		(start 98.8568 -202.8952)
		(mid 98.928642 -202.865442)
		(end 98.9584 -202.7936)
		(stroke
			(width 0.2)
			(type default)
		)
		(layer "In1.Cu")
	)
	(gr_line
		(start 98.8568 -201.4728)
		(end 97.4852 -201.4728)
		(stroke
			(width 0.2)
			(type default)
		)
		(layer "In1.Cu")
	)
	(gr_line
		(start 98.9584 -202.7936)
		(end 98.9584 -201.5744)
		(stroke
			(width 0.2)
			(type default)
		)
		(layer "In1.Cu")
	)
	(gr_arc
		(start 98.9584 -201.5744)
		(mid 98.928642 -201.502558)
		(end 98.8568 -201.4728)
		(stroke
			(width 0.2)
			(type default)
		)
		(layer "In1.Cu")
	)
	(gr_line
		(start 98.98761 -435.395116)
		(end 98.98761 -434.203856)
		(stroke
			(width 0.2)
			(type default)
		)
		(layer "In1.Cu")
	)
	(gr_line
		(start 98.98761 -434.203856)
		(end 97.81921 -434.203856)
		(stroke
			(width 0.2)
			(type default)
		)
		(layer "In1.Cu")
	)
	(gr_line
		(start 98.98761 -433.396898)
		(end 98.98761 -432.202844)
		(stroke
			(width 0.2)
			(type default)
		)
		(layer "In1.Cu")
	)
	(gr_line
		(start 98.98761 -432.202844)
		(end 97.81921 -432.202844)
		(stroke
			(width 0.2)
			(type default)
		)
		(layer "In1.Cu")
	)
	(gr_line
		(start 98.98761 -308.777894)
		(end 98.98761 -307.58638)
		(stroke
			(width 0.2)
			(type default)
		)
		(layer "In1.Cu")
	)
	(gr_line
		(start 98.98761 -307.58638)
		(end 97.81921 -307.58638)
		(stroke
			(width 0.2)
			(type default)
		)
		(layer "In1.Cu")
	)
	(gr_line
		(start 98.98761 -306.777136)
		(end 98.98761 -305.58486)
		(stroke
			(width 0.2)
			(type default)
		)
		(layer "In1.Cu")
	)
	(gr_line
		(start 98.98761 -305.58486)
		(end 97.81921 -305.58486)
		(stroke
			(width 0.2)
			(type default)
		)
		(layer "In1.Cu")
	)
	(gr_line
		(start 98.98761 -210.416648)
		(end 98.98761 -209.222594)
		(stroke
			(width 0.2)
			(type default)
		)
		(layer "In1.Cu")
	)
	(gr_line
		(start 98.98761 -209.222594)
		(end 97.81921 -209.222594)
		(stroke
			(width 0.2)
			(type default)
		)
		(layer "In1.Cu")
	)
	(gr_line
		(start 98.98761 -208.416398)
		(end 98.98761 -207.223106)
		(stroke
			(width 0.2)
			(type default)
		)
		(layer "In1.Cu")
	)
	(gr_line
		(start 98.98761 -207.223106)
		(end 97.81921 -207.223106)
		(stroke
			(width 0.2)
			(type default)
		)
		(layer "In1.Cu")
	)
	(gr_arc
		(start 99.0346 -314.4266)
		(mid 99.064358 -314.498442)
		(end 99.1362 -314.5282)
		(stroke
			(width 0.2)
			(type default)
		)
		(layer "In1.Cu")
	)
	(gr_line
		(start 99.0346 -313.2074)
		(end 99.0346 -314.4266)
		(stroke
			(width 0.2)
			(type default)
		)
		(layer "In1.Cu")
	)
	(gr_arc
		(start 99.0346 -297.1546)
		(mid 99.064358 -297.226442)
		(end 99.1362 -297.2562)
		(stroke
			(width 0.2)
			(type default)
		)
		(layer "In1.Cu")
	)
	(gr_line
		(start 99.0346 -295.9354)
		(end 99.0346 -297.1546)
		(stroke
			(width 0.2)
			(type default)
		)
		(layer "In1.Cu")
	)
	(gr_arc
		(start 99.0346 -220.0656)
		(mid 99.064358 -220.137442)
		(end 99.1362 -220.1672)
		(stroke
			(width 0.2)
			(type default)
		)
		(layer "In1.Cu")
	)
	(gr_line
		(start 99.0346 -218.8464)
		(end 99.0346 -220.0656)
		(stroke
			(width 0.2)
			(type default)
		)
		(layer "In1.Cu")
	)
	(gr_arc
		(start 99.0346 -110.8456)
		(mid 99.064358 -110.917442)
		(end 99.1362 -110.9472)
		(stroke
			(width 0.2)
			(type default)
		)
		(layer "In1.Cu")
	)
	(gr_line
		(start 99.0346 -109.6264)
		(end 99.0346 -110.8456)
		(stroke
			(width 0.2)
			(type default)
		)
		(layer "In1.Cu")
	)
	(gr_arc
		(start 99.0346 -93.5736)
		(mid 99.064358 -93.645442)
		(end 99.1362 -93.6752)
		(stroke
			(width 0.2)
			(type default)
		)
		(layer "In1.Cu")
	)
	(gr_line
		(start 99.0346 -92.3544)
		(end 99.0346 -93.5736)
		(stroke
			(width 0.2)
			(type default)
		)
		(layer "In1.Cu")
	)
	(gr_line
		(start 99.1362 -314.5282)
		(end 100.5078 -314.5282)
		(stroke
			(width 0.2)
			(type default)
		)
		(layer "In1.Cu")
	)
	(gr_arc
		(start 99.1362 -313.1058)
		(mid 99.064358 -313.135558)
		(end 99.0346 -313.2074)
		(stroke
			(width 0.2)
			(type default)
		)
		(layer "In1.Cu")
	)
	(gr_line
		(start 99.1362 -297.2562)
		(end 100.5078 -297.2562)
		(stroke
			(width 0.2)
			(type default)
		)
		(layer "In1.Cu")
	)
	(gr_arc
		(start 99.1362 -295.8338)
		(mid 99.064358 -295.863558)
		(end 99.0346 -295.9354)
		(stroke
			(width 0.2)
			(type default)
		)
		(layer "In1.Cu")
	)
	(gr_line
		(start 99.1362 -220.1672)
		(end 100.5078 -220.1672)
		(stroke
			(width 0.2)
			(type default)
		)
		(layer "In1.Cu")
	)
	(gr_arc
		(start 99.1362 -218.7448)
		(mid 99.064358 -218.774558)
		(end 99.0346 -218.8464)
		(stroke
			(width 0.2)
			(type default)
		)
		(layer "In1.Cu")
	)
	(gr_line
		(start 99.1362 -110.9472)
		(end 100.5078 -110.9472)
		(stroke
			(width 0.2)
			(type default)
		)
		(layer "In1.Cu")
	)
	(gr_arc
		(start 99.1362 -109.5248)
		(mid 99.064358 -109.554558)
		(end 99.0346 -109.6264)
		(stroke
			(width 0.2)
			(type default)
		)
		(layer "In1.Cu")
	)
	(gr_line
		(start 99.1362 -93.6752)
		(end 100.5078 -93.6752)
		(stroke
			(width 0.2)
			(type default)
		)
		(layer "In1.Cu")
	)
	(gr_arc
		(start 99.1362 -92.2528)
		(mid 99.064358 -92.282558)
		(end 99.0346 -92.3544)
		(stroke
			(width 0.2)
			(type default)
		)
		(layer "In1.Cu")
	)
	(gr_arc
		(start 100.5078 -314.5282)
		(mid 100.579642 -314.498442)
		(end 100.6094 -314.4266)
		(stroke
			(width 0.2)
			(type default)
		)
		(layer "In1.Cu")
	)
	(gr_line
		(start 100.5078 -313.1058)
		(end 99.1362 -313.1058)
		(stroke
			(width 0.2)
			(type default)
		)
		(layer "In1.Cu")
	)
	(gr_arc
		(start 100.5078 -297.2562)
		(mid 100.579642 -297.226442)
		(end 100.6094 -297.1546)
		(stroke
			(width 0.2)
			(type default)
		)
		(layer "In1.Cu")
	)
	(gr_line
		(start 100.5078 -295.8338)
		(end 99.1362 -295.8338)
		(stroke
			(width 0.2)
			(type default)
		)
		(layer "In1.Cu")
	)
	(gr_arc
		(start 100.5078 -220.1672)
		(mid 100.579642 -220.137442)
		(end 100.6094 -220.0656)
		(stroke
			(width 0.2)
			(type default)
		)
		(layer "In1.Cu")
	)
	(gr_line
		(start 100.5078 -218.7448)
		(end 99.1362 -218.7448)
		(stroke
			(width 0.2)
			(type default)
		)
		(layer "In1.Cu")
	)
	(gr_arc
		(start 100.5078 -110.9472)
		(mid 100.579642 -110.917442)
		(end 100.6094 -110.8456)
		(stroke
			(width 0.2)
			(type default)
		)
		(layer "In1.Cu")
	)
	(gr_line
		(start 100.5078 -109.5248)
		(end 99.1362 -109.5248)
		(stroke
			(width 0.2)
			(type default)
		)
		(layer "In1.Cu")
	)
	(gr_arc
		(start 100.5078 -93.6752)
		(mid 100.579642 -93.645442)
		(end 100.6094 -93.5736)
		(stroke
			(width 0.2)
			(type default)
		)
		(layer "In1.Cu")
	)
	(gr_line
		(start 100.5078 -92.2528)
		(end 99.1362 -92.2528)
		(stroke
			(width 0.2)
			(type default)
		)
		(layer "In1.Cu")
	)
	(gr_line
		(start 100.6094 -314.4266)
		(end 100.6094 -313.2074)
		(stroke
			(width 0.2)
			(type default)
		)
		(layer "In1.Cu")
	)
	(gr_arc
		(start 100.6094 -313.2074)
		(mid 100.579642 -313.135558)
		(end 100.5078 -313.1058)
		(stroke
			(width 0.2)
			(type default)
		)
		(layer "In1.Cu")
	)
	(gr_line
		(start 100.6094 -297.1546)
		(end 100.6094 -295.9354)
		(stroke
			(width 0.2)
			(type default)
		)
		(layer "In1.Cu")
	)
	(gr_arc
		(start 100.6094 -295.9354)
		(mid 100.579642 -295.863558)
		(end 100.5078 -295.8338)
		(stroke
			(width 0.2)
			(type default)
		)
		(layer "In1.Cu")
	)
	(gr_line
		(start 100.6094 -220.0656)
		(end 100.6094 -218.8464)
		(stroke
			(width 0.2)
			(type default)
		)
		(layer "In1.Cu")
	)
	(gr_arc
		(start 100.6094 -218.8464)
		(mid 100.579642 -218.774558)
		(end 100.5078 -218.7448)
		(stroke
			(width 0.2)
			(type default)
		)
		(layer "In1.Cu")
	)
	(gr_line
		(start 100.6094 -110.8456)
		(end 100.6094 -109.6264)
		(stroke
			(width 0.2)
			(type default)
		)
		(layer "In1.Cu")
	)
	(gr_arc
		(start 100.6094 -109.6264)
		(mid 100.579642 -109.554558)
		(end 100.5078 -109.5248)
		(stroke
			(width 0.2)
			(type default)
		)
		(layer "In1.Cu")
	)
	(gr_line
		(start 100.6094 -93.5736)
		(end 100.6094 -92.3544)
		(stroke
			(width 0.2)
			(type default)
		)
		(layer "In1.Cu")
	)
	(gr_arc
		(start 100.6094 -92.3544)
		(mid 100.579642 -92.282558)
		(end 100.5078 -92.2528)
		(stroke
			(width 0.2)
			(type default)
		)
		(layer "In1.Cu")
	)
	(gr_arc
		(start 101.9048 -438.3278)
		(mid 101.934558 -438.399642)
		(end 102.0064 -438.4294)
		(stroke
			(width 0.2)
			(type default)
		)
		(layer "In1.Cu")
	)
	(gr_line
		(start 101.9048 -436.9562)
		(end 101.9048 -438.3278)
		(stroke
			(width 0.2)
			(type default)
		)
		(layer "In1.Cu")
	)
	(gr_arc
		(start 101.9048 -434.5178)
		(mid 101.934558 -434.589642)
		(end 102.0064 -434.6194)
		(stroke
			(width 0.2)
			(type default)
		)
		(layer "In1.Cu")
	)
	(gr_line
		(start 101.9048 -433.1462)
		(end 101.9048 -434.5178)
		(stroke
			(width 0.2)
			(type default)
		)
		(layer "In1.Cu")
	)
	(gr_arc
		(start 101.9048 -311.7088)
		(mid 101.934558 -311.780642)
		(end 102.0064 -311.8104)
		(stroke
			(width 0.2)
			(type default)
		)
		(layer "In1.Cu")
	)
	(gr_line
		(start 101.9048 -310.3372)
		(end 101.9048 -311.7088)
		(stroke
			(width 0.2)
			(type default)
		)
		(layer "In1.Cu")
	)
	(gr_arc
		(start 101.9048 -307.8988)
		(mid 101.934558 -307.970642)
		(end 102.0064 -308.0004)
		(stroke
			(width 0.2)
			(type default)
		)
		(layer "In1.Cu")
	)
	(gr_line
		(start 101.9048 -306.5272)
		(end 101.9048 -307.8988)
		(stroke
			(width 0.2)
			(type default)
		)
		(layer "In1.Cu")
	)
	(gr_arc
		(start 101.9048 -209.4738)
		(mid 101.934558 -209.545642)
		(end 102.0064 -209.5754)
		(stroke
			(width 0.2)
			(type default)
		)
		(layer "In1.Cu")
	)
	(gr_line
		(start 101.9048 -208.1022)
		(end 101.9048 -209.4738)
		(stroke
			(width 0.2)
			(type default)
		)
		(layer "In1.Cu")
	)
	(gr_arc
		(start 101.9048 -205.6638)
		(mid 101.934558 -205.735642)
		(end 102.0064 -205.7654)
		(stroke
			(width 0.2)
			(type default)
		)
		(layer "In1.Cu")
	)
	(gr_line
		(start 101.9048 -204.2922)
		(end 101.9048 -205.6638)
		(stroke
			(width 0.2)
			(type default)
		)
		(layer "In1.Cu")
	)
	(gr_line
		(start 102.0064 -438.4294)
		(end 103.2256 -438.4294)
		(stroke
			(width 0.2)
			(type default)
		)
		(layer "In1.Cu")
	)
	(gr_arc
		(start 102.0064 -436.8546)
		(mid 101.934558 -436.884358)
		(end 101.9048 -436.9562)
		(stroke
			(width 0.2)
			(type default)
		)
		(layer "In1.Cu")
	)
	(gr_line
		(start 102.0064 -434.6194)
		(end 103.2256 -434.6194)
		(stroke
			(width 0.2)
			(type default)
		)
		(layer "In1.Cu")
	)
	(gr_arc
		(start 102.0064 -433.0446)
		(mid 101.934558 -433.074358)
		(end 101.9048 -433.1462)
		(stroke
			(width 0.2)
			(type default)
		)
		(layer "In1.Cu")
	)
	(gr_line
		(start 102.0064 -311.8104)
		(end 103.2256 -311.8104)
		(stroke
			(width 0.2)
			(type default)
		)
		(layer "In1.Cu")
	)
	(gr_arc
		(start 102.0064 -310.2356)
		(mid 101.934558 -310.265358)
		(end 101.9048 -310.3372)
		(stroke
			(width 0.2)
			(type default)
		)
		(layer "In1.Cu")
	)
	(gr_line
		(start 102.0064 -308.0004)
		(end 103.2256 -308.0004)
		(stroke
			(width 0.2)
			(type default)
		)
		(layer "In1.Cu")
	)
	(gr_arc
		(start 102.0064 -306.4256)
		(mid 101.934558 -306.455358)
		(end 101.9048 -306.5272)
		(stroke
			(width 0.2)
			(type default)
		)
		(layer "In1.Cu")
	)
	(gr_line
		(start 102.0064 -209.5754)
		(end 103.2256 -209.5754)
		(stroke
			(width 0.2)
			(type default)
		)
		(layer "In1.Cu")
	)
	(gr_arc
		(start 102.0064 -208.0006)
		(mid 101.934558 -208.030358)
		(end 101.9048 -208.1022)
		(stroke
			(width 0.2)
			(type default)
		)
		(layer "In1.Cu")
	)
	(gr_line
		(start 102.0064 -205.7654)
		(end 103.2256 -205.7654)
		(stroke
			(width 0.2)
			(type default)
		)
		(layer "In1.Cu")
	)
	(gr_arc
		(start 102.0064 -204.1906)
		(mid 101.934558 -204.220358)
		(end 101.9048 -204.2922)
		(stroke
			(width 0.2)
			(type default)
		)
		(layer "In1.Cu")
	)
	(gr_arc
		(start 103.2256 -438.4294)
		(mid 103.297442 -438.399642)
		(end 103.3272 -438.3278)
		(stroke
			(width 0.2)
			(type default)
		)
		(layer "In1.Cu")
	)
	(gr_line
		(start 103.2256 -436.8546)
		(end 102.0064 -436.8546)
		(stroke
			(width 0.2)
			(type default)
		)
		(layer "In1.Cu")
	)
	(gr_arc
		(start 103.2256 -434.6194)
		(mid 103.297442 -434.589642)
		(end 103.3272 -434.5178)
		(stroke
			(width 0.2)
			(type default)
		)
		(layer "In1.Cu")
	)
	(gr_line
		(start 103.2256 -433.0446)
		(end 102.0064 -433.0446)
		(stroke
			(width 0.2)
			(type default)
		)
		(layer "In1.Cu")
	)
	(gr_arc
		(start 103.2256 -311.8104)
		(mid 103.297442 -311.780642)
		(end 103.3272 -311.7088)
		(stroke
			(width 0.2)
			(type default)
		)
		(layer "In1.Cu")
	)
	(gr_line
		(start 103.2256 -310.2356)
		(end 102.0064 -310.2356)
		(stroke
			(width 0.2)
			(type default)
		)
		(layer "In1.Cu")
	)
	(gr_arc
		(start 103.2256 -308.0004)
		(mid 103.297442 -307.970642)
		(end 103.3272 -307.8988)
		(stroke
			(width 0.2)
			(type default)
		)
		(layer "In1.Cu")
	)
	(gr_line
		(start 103.2256 -306.4256)
		(end 102.0064 -306.4256)
		(stroke
			(width 0.2)
			(type default)
		)
		(layer "In1.Cu")
	)
	(gr_arc
		(start 103.2256 -209.5754)
		(mid 103.297442 -209.545642)
		(end 103.3272 -209.4738)
		(stroke
			(width 0.2)
			(type default)
		)
		(layer "In1.Cu")
	)
	(gr_line
		(start 103.2256 -208.0006)
		(end 102.0064 -208.0006)
		(stroke
			(width 0.2)
			(type default)
		)
		(layer "In1.Cu")
	)
	(gr_arc
		(start 103.2256 -205.7654)
		(mid 103.297442 -205.735642)
		(end 103.3272 -205.6638)
		(stroke
			(width 0.2)
			(type default)
		)
		(layer "In1.Cu")
	)
	(gr_line
		(start 103.2256 -204.1906)
		(end 102.0064 -204.1906)
		(stroke
			(width 0.2)
			(type default)
		)
		(layer "In1.Cu")
	)
	(gr_line
		(start 103.3272 -438.3278)
		(end 103.3272 -436.9562)
		(stroke
			(width 0.2)
			(type default)
		)
		(layer "In1.Cu")
	)
	(gr_arc
		(start 103.3272 -436.9562)
		(mid 103.297442 -436.884358)
		(end 103.2256 -436.8546)
		(stroke
			(width 0.2)
			(type default)
		)
		(layer "In1.Cu")
	)
	(gr_line
		(start 103.3272 -434.5178)
		(end 103.3272 -433.1462)
		(stroke
			(width 0.2)
			(type default)
		)
		(layer "In1.Cu")
	)
	(gr_arc
		(start 103.3272 -433.1462)
		(mid 103.297442 -433.074358)
		(end 103.2256 -433.0446)
		(stroke
			(width 0.2)
			(type default)
		)
		(layer "In1.Cu")
	)
	(gr_line
		(start 103.3272 -311.7088)
		(end 103.3272 -310.3372)
		(stroke
			(width 0.2)
			(type default)
		)
		(layer "In1.Cu")
	)
	(gr_arc
		(start 103.3272 -310.3372)
		(mid 103.297442 -310.265358)
		(end 103.2256 -310.2356)
		(stroke
			(width 0.2)
			(type default)
		)
		(layer "In1.Cu")
	)
	(gr_line
		(start 103.3272 -307.8988)
		(end 103.3272 -306.5272)
		(stroke
			(width 0.2)
			(type default)
		)
		(layer "In1.Cu")
	)
	(gr_arc
		(start 103.3272 -306.5272)
		(mid 103.297442 -306.455358)
		(end 103.2256 -306.4256)
		(stroke
			(width 0.2)
			(type default)
		)
		(layer "In1.Cu")
	)
	(gr_line
		(start 103.3272 -209.4738)
		(end 103.3272 -208.1022)
		(stroke
			(width 0.2)
			(type default)
		)
		(layer "In1.Cu")
	)
	(gr_arc
		(start 103.3272 -208.1022)
		(mid 103.297442 -208.030358)
		(end 103.2256 -208.0006)
		(stroke
			(width 0.2)
			(type default)
		)
		(layer "In1.Cu")
	)
	(gr_line
		(start 103.3272 -205.6638)
		(end 103.3272 -204.2922)
		(stroke
			(width 0.2)
			(type default)
		)
		(layer "In1.Cu")
	)
	(gr_arc
		(start 103.3272 -204.2922)
		(mid 103.297442 -204.220358)
		(end 103.2256 -204.1906)
		(stroke
			(width 0.2)
			(type default)
		)
		(layer "In1.Cu")
	)
	(gr_arc
		(start 219.819474 -489.796582)
		(mid 220.330014 -490.307122)
		(end 220.840554 -489.796582)
		(stroke
			(width 0.2)
			(type default)
		)
		(layer "In1.Cu")
	)
	(gr_line
		(start 219.819474 -488.983782)
		(end 219.819474 -489.796582)
		(stroke
			(width 0.2)
			(type default)
		)
		(layer "In1.Cu")
	)
	(gr_arc
		(start 219.819474 -484.99649)
		(mid 220.330014 -485.50703)
		(end 220.840554 -484.99649)
		(stroke
			(width 0.2)
			(type default)
		)
		(layer "In1.Cu")
	)
	(gr_line
		(start 219.819474 -484.18369)
		(end 219.819474 -484.99649)
		(stroke
			(width 0.2)
			(type default)
		)
		(layer "In1.Cu")
	)
	(gr_arc
		(start 219.819474 -480.196652)
		(mid 220.330014 -480.707192)
		(end 220.840554 -480.196652)
		(stroke
			(width 0.2)
			(type default)
		)
		(layer "In1.Cu")
	)
	(gr_line
		(start 219.819474 -479.383852)
		(end 219.819474 -480.196652)
		(stroke
			(width 0.2)
			(type default)
		)
		(layer "In1.Cu")
	)
	(gr_arc
		(start 219.819474 -467.396576)
		(mid 220.330014 -467.907116)
		(end 220.840554 -467.396576)
		(stroke
			(width 0.2)
			(type default)
		)
		(layer "In1.Cu")
	)
	(gr_line
		(start 219.819474 -466.583776)
		(end 219.819474 -467.396576)
		(stroke
			(width 0.2)
			(type default)
		)
		(layer "In1.Cu")
	)
	(gr_arc
		(start 219.819474 -386.796534)
		(mid 220.330014 -387.307074)
		(end 220.840554 -386.796534)
		(stroke
			(width 0.2)
			(type default)
		)
		(layer "In1.Cu")
	)
	(gr_line
		(start 219.819474 -385.983734)
		(end 219.819474 -386.796534)
		(stroke
			(width 0.2)
			(type default)
		)
		(layer "In1.Cu")
	)
	(gr_arc
		(start 219.819474 -381.996442)
		(mid 220.330014 -382.506982)
		(end 220.840554 -381.996442)
		(stroke
			(width 0.2)
			(type default)
		)
		(layer "In1.Cu")
	)
	(gr_line
		(start 219.819474 -381.183642)
		(end 219.819474 -381.996442)
		(stroke
			(width 0.2)
			(type default)
		)
		(layer "In1.Cu")
	)
	(gr_arc
		(start 219.819474 -377.196604)
		(mid 220.330014 -377.707144)
		(end 220.840554 -377.196604)
		(stroke
			(width 0.2)
			(type default)
		)
		(layer "In1.Cu")
	)
	(gr_line
		(start 219.819474 -376.383804)
		(end 219.819474 -377.196604)
		(stroke
			(width 0.2)
			(type default)
		)
		(layer "In1.Cu")
	)
	(gr_arc
		(start 219.819474 -364.396528)
		(mid 220.330014 -364.907068)
		(end 220.840554 -364.396528)
		(stroke
			(width 0.2)
			(type default)
		)
		(layer "In1.Cu")
	)
	(gr_line
		(start 219.819474 -363.583728)
		(end 219.819474 -364.396528)
		(stroke
			(width 0.2)
			(type default)
		)
		(layer "In1.Cu")
	)
	(gr_arc
		(start 219.819474 -283.796486)
		(mid 220.330014 -284.307026)
		(end 220.840554 -283.796486)
		(stroke
			(width 0.2)
			(type default)
		)
		(layer "In1.Cu")
	)
	(gr_line
		(start 219.819474 -282.983686)
		(end 219.819474 -283.796486)
		(stroke
			(width 0.2)
			(type default)
		)
		(layer "In1.Cu")
	)
	(gr_arc
		(start 219.819474 -278.996394)
		(mid 220.330014 -279.506934)
		(end 220.840554 -278.996394)
		(stroke
			(width 0.2)
			(type default)
		)
		(layer "In1.Cu")
	)
	(gr_line
		(start 219.819474 -278.183594)
		(end 219.819474 -278.996394)
		(stroke
			(width 0.2)
			(type default)
		)
		(layer "In1.Cu")
	)
	(gr_arc
		(start 219.819474 -274.196556)
		(mid 220.330014 -274.707096)
		(end 220.840554 -274.196556)
		(stroke
			(width 0.2)
			(type default)
		)
		(layer "In1.Cu")
	)
	(gr_line
		(start 219.819474 -273.383756)
		(end 219.819474 -274.196556)
		(stroke
			(width 0.2)
			(type default)
		)
		(layer "In1.Cu")
	)
	(gr_arc
		(start 219.819474 -261.39648)
		(mid 220.330014 -261.90702)
		(end 220.840554 -261.39648)
		(stroke
			(width 0.2)
			(type default)
		)
		(layer "In1.Cu")
	)
	(gr_line
		(start 219.819474 -260.58368)
		(end 219.819474 -261.39648)
		(stroke
			(width 0.2)
			(type default)
		)
		(layer "In1.Cu")
	)
	(gr_arc
		(start 219.819474 -180.796438)
		(mid 220.330014 -181.306978)
		(end 220.840554 -180.796438)
		(stroke
			(width 0.2)
			(type default)
		)
		(layer "In1.Cu")
	)
	(gr_line
		(start 219.819474 -179.983638)
		(end 219.819474 -180.796438)
		(stroke
			(width 0.2)
			(type default)
		)
		(layer "In1.Cu")
	)
	(gr_arc
		(start 219.819474 -175.996346)
		(mid 220.330014 -176.506886)
		(end 220.840554 -175.996346)
		(stroke
			(width 0.2)
			(type default)
		)
		(layer "In1.Cu")
	)
	(gr_line
		(start 219.819474 -175.183546)
		(end 219.819474 -175.996346)
		(stroke
			(width 0.2)
			(type default)
		)
		(layer "In1.Cu")
	)
	(gr_arc
		(start 219.819474 -171.196508)
		(mid 220.330014 -171.707048)
		(end 220.840554 -171.196508)
		(stroke
			(width 0.2)
			(type default)
		)
		(layer "In1.Cu")
	)
	(gr_line
		(start 219.819474 -170.383708)
		(end 219.819474 -171.196508)
		(stroke
			(width 0.2)
			(type default)
		)
		(layer "In1.Cu")
	)
	(gr_arc
		(start 219.819474 -158.396432)
		(mid 220.330014 -158.906972)
		(end 220.840554 -158.396432)
		(stroke
			(width 0.2)
			(type default)
		)
		(layer "In1.Cu")
	)
	(gr_line
		(start 219.819474 -157.583632)
		(end 219.819474 -158.396432)
		(stroke
			(width 0.2)
			(type default)
		)
		(layer "In1.Cu")
	)
	(gr_arc
		(start 219.819474 -77.79639)
		(mid 220.330014 -78.30693)
		(end 220.840554 -77.79639)
		(stroke
			(width 0.2)
			(type default)
		)
		(layer "In1.Cu")
	)
	(gr_line
		(start 219.819474 -76.98359)
		(end 219.819474 -77.79639)
		(stroke
			(width 0.2)
			(type default)
		)
		(layer "In1.Cu")
	)
	(gr_arc
		(start 219.819474 -72.996298)
		(mid 220.330014 -73.506838)
		(end 220.840554 -72.996298)
		(stroke
			(width 0.2)
			(type default)
		)
		(layer "In1.Cu")
	)
	(gr_line
		(start 219.819474 -72.183498)
		(end 219.819474 -72.996298)
		(stroke
			(width 0.2)
			(type default)
		)
		(layer "In1.Cu")
	)
	(gr_arc
		(start 219.819474 -68.19646)
		(mid 220.330014 -68.707)
		(end 220.840554 -68.19646)
		(stroke
			(width 0.2)
			(type default)
		)
		(layer "In1.Cu")
	)
	(gr_line
		(start 219.819474 -67.38366)
		(end 219.819474 -68.19646)
		(stroke
			(width 0.2)
			(type default)
		)
		(layer "In1.Cu")
	)
	(gr_arc
		(start 219.819474 -55.396384)
		(mid 220.330014 -55.906924)
		(end 220.840554 -55.396384)
		(stroke
			(width 0.2)
			(type default)
		)
		(layer "In1.Cu")
	)
	(gr_line
		(start 219.819474 -54.583584)
		(end 219.819474 -55.396384)
		(stroke
			(width 0.2)
			(type default)
		)
		(layer "In1.Cu")
	)
	(gr_line
		(start 220.840554 -489.796582)
		(end 220.840554 -488.984036)
		(stroke
			(width 0.2)
			(type default)
		)
		(layer "In1.Cu")
	)
	(gr_arc
		(start 220.840554 -488.984036)
		(mid 220.330141 -488.473242)
		(end 219.819474 -488.983782)
		(stroke
			(width 0.2)
			(type default)
		)
		(layer "In1.Cu")
	)
	(gr_line
		(start 220.840554 -484.99649)
		(end 220.840554 -484.183944)
		(stroke
			(width 0.2)
			(type default)
		)
		(layer "In1.Cu")
	)
	(gr_arc
		(start 220.840554 -484.183944)
		(mid 220.330141 -483.67315)
		(end 219.819474 -484.18369)
		(stroke
			(width 0.2)
			(type default)
		)
		(layer "In1.Cu")
	)
	(gr_line
		(start 220.840554 -480.196652)
		(end 220.840554 -479.384106)
		(stroke
			(width 0.2)
			(type default)
		)
		(layer "In1.Cu")
	)
	(gr_arc
		(start 220.840554 -479.384106)
		(mid 220.330141 -478.873312)
		(end 219.819474 -479.383852)
		(stroke
			(width 0.2)
			(type default)
		)
		(layer "In1.Cu")
	)
	(gr_line
		(start 220.840554 -467.396576)
		(end 220.840554 -466.58403)
		(stroke
			(width 0.2)
			(type default)
		)
		(layer "In1.Cu")
	)
	(gr_arc
		(start 220.840554 -466.58403)
		(mid 220.330141 -466.073236)
		(end 219.819474 -466.583776)
		(stroke
			(width 0.2)
			(type default)
		)
		(layer "In1.Cu")
	)
	(gr_line
		(start 220.840554 -386.796534)
		(end 220.840554 -385.983988)
		(stroke
			(width 0.2)
			(type default)
		)
		(layer "In1.Cu")
	)
	(gr_arc
		(start 220.840554 -385.983988)
		(mid 220.330141 -385.473194)
		(end 219.819474 -385.983734)
		(stroke
			(width 0.2)
			(type default)
		)
		(layer "In1.Cu")
	)
	(gr_line
		(start 220.840554 -381.996442)
		(end 220.840554 -381.183896)
		(stroke
			(width 0.2)
			(type default)
		)
		(layer "In1.Cu")
	)
	(gr_arc
		(start 220.840554 -381.183896)
		(mid 220.330141 -380.673102)
		(end 219.819474 -381.183642)
		(stroke
			(width 0.2)
			(type default)
		)
		(layer "In1.Cu")
	)
	(gr_line
		(start 220.840554 -377.196604)
		(end 220.840554 -376.384058)
		(stroke
			(width 0.2)
			(type default)
		)
		(layer "In1.Cu")
	)
	(gr_arc
		(start 220.840554 -376.384058)
		(mid 220.330141 -375.873264)
		(end 219.819474 -376.383804)
		(stroke
			(width 0.2)
			(type default)
		)
		(layer "In1.Cu")
	)
	(gr_line
		(start 220.840554 -364.396528)
		(end 220.840554 -363.583982)
		(stroke
			(width 0.2)
			(type default)
		)
		(layer "In1.Cu")
	)
	(gr_arc
		(start 220.840554 -363.583982)
		(mid 220.330141 -363.073188)
		(end 219.819474 -363.583728)
		(stroke
			(width 0.2)
			(type default)
		)
		(layer "In1.Cu")
	)
	(gr_line
		(start 220.840554 -283.796486)
		(end 220.840554 -282.98394)
		(stroke
			(width 0.2)
			(type default)
		)
		(layer "In1.Cu")
	)
	(gr_arc
		(start 220.840554 -282.98394)
		(mid 220.330141 -282.473146)
		(end 219.819474 -282.983686)
		(stroke
			(width 0.2)
			(type default)
		)
		(layer "In1.Cu")
	)
	(gr_line
		(start 220.840554 -278.996394)
		(end 220.840554 -278.183848)
		(stroke
			(width 0.2)
			(type default)
		)
		(layer "In1.Cu")
	)
	(gr_arc
		(start 220.840554 -278.183848)
		(mid 220.330141 -277.673054)
		(end 219.819474 -278.183594)
		(stroke
			(width 0.2)
			(type default)
		)
		(layer "In1.Cu")
	)
	(gr_line
		(start 220.840554 -274.196556)
		(end 220.840554 -273.38401)
		(stroke
			(width 0.2)
			(type default)
		)
		(layer "In1.Cu")
	)
	(gr_arc
		(start 220.840554 -273.38401)
		(mid 220.330141 -272.873216)
		(end 219.819474 -273.383756)
		(stroke
			(width 0.2)
			(type default)
		)
		(layer "In1.Cu")
	)
	(gr_line
		(start 220.840554 -261.39648)
		(end 220.840554 -260.583934)
		(stroke
			(width 0.2)
			(type default)
		)
		(layer "In1.Cu")
	)
	(gr_arc
		(start 220.840554 -260.583934)
		(mid 220.330141 -260.07314)
		(end 219.819474 -260.58368)
		(stroke
			(width 0.2)
			(type default)
		)
		(layer "In1.Cu")
	)
	(gr_line
		(start 220.840554 -180.796438)
		(end 220.840554 -179.983892)
		(stroke
			(width 0.2)
			(type default)
		)
		(layer "In1.Cu")
	)
	(gr_arc
		(start 220.840554 -179.983892)
		(mid 220.330141 -179.473098)
		(end 219.819474 -179.983638)
		(stroke
			(width 0.2)
			(type default)
		)
		(layer "In1.Cu")
	)
	(gr_line
		(start 220.840554 -175.996346)
		(end 220.840554 -175.1838)
		(stroke
			(width 0.2)
			(type default)
		)
		(layer "In1.Cu")
	)
	(gr_arc
		(start 220.840554 -175.1838)
		(mid 220.330141 -174.673006)
		(end 219.819474 -175.183546)
		(stroke
			(width 0.2)
			(type default)
		)
		(layer "In1.Cu")
	)
	(gr_line
		(start 220.840554 -171.196508)
		(end 220.840554 -170.383962)
		(stroke
			(width 0.2)
			(type default)
		)
		(layer "In1.Cu")
	)
	(gr_arc
		(start 220.840554 -170.383962)
		(mid 220.330141 -169.873168)
		(end 219.819474 -170.383708)
		(stroke
			(width 0.2)
			(type default)
		)
		(layer "In1.Cu")
	)
	(gr_line
		(start 220.840554 -158.396432)
		(end 220.840554 -157.583886)
		(stroke
			(width 0.2)
			(type default)
		)
		(layer "In1.Cu")
	)
	(gr_arc
		(start 220.840554 -157.583886)
		(mid 220.330141 -157.073092)
		(end 219.819474 -157.583632)
		(stroke
			(width 0.2)
			(type default)
		)
		(layer "In1.Cu")
	)
	(gr_line
		(start 220.840554 -77.79639)
		(end 220.840554 -76.983844)
		(stroke
			(width 0.2)
			(type default)
		)
		(layer "In1.Cu")
	)
	(gr_arc
		(start 220.840554 -76.983844)
		(mid 220.330141 -76.47305)
		(end 219.819474 -76.98359)
		(stroke
			(width 0.2)
			(type default)
		)
		(layer "In1.Cu")
	)
	(gr_line
		(start 220.840554 -72.996298)
		(end 220.840554 -72.183752)
		(stroke
			(width 0.2)
			(type default)
		)
		(layer "In1.Cu")
	)
	(gr_arc
		(start 220.840554 -72.183752)
		(mid 220.330141 -71.672958)
		(end 219.819474 -72.183498)
		(stroke
			(width 0.2)
			(type default)
		)
		(layer "In1.Cu")
	)
	(gr_line
		(start 220.840554 -68.19646)
		(end 220.840554 -67.383914)
		(stroke
			(width 0.2)
			(type default)
		)
		(layer "In1.Cu")
	)
	(gr_arc
		(start 220.840554 -67.383914)
		(mid 220.330141 -66.87312)
		(end 219.819474 -67.38366)
		(stroke
			(width 0.2)
			(type default)
		)
		(layer "In1.Cu")
	)
	(gr_line
		(start 220.840554 -55.396384)
		(end 220.840554 -54.583838)
		(stroke
			(width 0.2)
			(type default)
		)
		(layer "In1.Cu")
	)
	(gr_arc
		(start 220.840554 -54.583838)
		(mid 220.330141 -54.073044)
		(end 219.819474 -54.583584)
		(stroke
			(width 0.2)
			(type default)
		)
		(layer "In1.Cu")
	)
	(gr_arc
		(start 221.114874 -492.349028)
		(mid 221.727014 -492.961168)
		(end 222.339154 -492.349028)
		(stroke
			(width 0.2)
			(type default)
		)
		(layer "In1.Cu")
	)
	(gr_line
		(start 221.114874 -491.231428)
		(end 221.114874 -492.349028)
		(stroke
			(width 0.2)
			(type default)
		)
		(layer "In1.Cu")
	)
	(gr_arc
		(start 221.114874 -487.548936)
		(mid 221.727014 -488.161076)
		(end 222.339154 -487.548936)
		(stroke
			(width 0.2)
			(type default)
		)
		(layer "In1.Cu")
	)
	(gr_line
		(start 221.114874 -486.431336)
		(end 221.114874 -487.548936)
		(stroke
			(width 0.2)
			(type default)
		)
		(layer "In1.Cu")
	)
	(gr_arc
		(start 221.114874 -482.748844)
		(mid 221.727014 -483.360984)
		(end 222.339154 -482.748844)
		(stroke
			(width 0.2)
			(type default)
		)
		(layer "In1.Cu")
	)
	(gr_line
		(start 221.114874 -481.631244)
		(end 221.114874 -482.748844)
		(stroke
			(width 0.2)
			(type default)
		)
		(layer "In1.Cu")
	)
	(gr_arc
		(start 221.114874 -469.949022)
		(mid 221.727014 -470.561162)
		(end 222.339154 -469.949022)
		(stroke
			(width 0.2)
			(type default)
		)
		(layer "In1.Cu")
	)
	(gr_line
		(start 221.114874 -468.831422)
		(end 221.114874 -469.949022)
		(stroke
			(width 0.2)
			(type default)
		)
		(layer "In1.Cu")
	)
	(gr_arc
		(start 221.114874 -389.34898)
		(mid 221.727014 -389.96112)
		(end 222.339154 -389.34898)
		(stroke
			(width 0.2)
			(type default)
		)
		(layer "In1.Cu")
	)
	(gr_line
		(start 221.114874 -388.23138)
		(end 221.114874 -389.34898)
		(stroke
			(width 0.2)
			(type default)
		)
		(layer "In1.Cu")
	)
	(gr_arc
		(start 221.114874 -384.548888)
		(mid 221.727014 -385.161028)
		(end 222.339154 -384.548888)
		(stroke
			(width 0.2)
			(type default)
		)
		(layer "In1.Cu")
	)
	(gr_line
		(start 221.114874 -383.431288)
		(end 221.114874 -384.548888)
		(stroke
			(width 0.2)
			(type default)
		)
		(layer "In1.Cu")
	)
	(gr_arc
		(start 221.114874 -379.748796)
		(mid 221.727014 -380.360936)
		(end 222.339154 -379.748796)
		(stroke
			(width 0.2)
			(type default)
		)
		(layer "In1.Cu")
	)
	(gr_line
		(start 221.114874 -378.631196)
		(end 221.114874 -379.748796)
		(stroke
			(width 0.2)
			(type default)
		)
		(layer "In1.Cu")
	)
	(gr_arc
		(start 221.114874 -366.948974)
		(mid 221.727014 -367.561114)
		(end 222.339154 -366.948974)
		(stroke
			(width 0.2)
			(type default)
		)
		(layer "In1.Cu")
	)
	(gr_line
		(start 221.114874 -365.831374)
		(end 221.114874 -366.948974)
		(stroke
			(width 0.2)
			(type default)
		)
		(layer "In1.Cu")
	)
	(gr_arc
		(start 221.114874 -286.348932)
		(mid 221.727014 -286.961072)
		(end 222.339154 -286.348932)
		(stroke
			(width 0.2)
			(type default)
		)
		(layer "In1.Cu")
	)
	(gr_line
		(start 221.114874 -285.231332)
		(end 221.114874 -286.348932)
		(stroke
			(width 0.2)
			(type default)
		)
		(layer "In1.Cu")
	)
	(gr_arc
		(start 221.114874 -281.54884)
		(mid 221.727014 -282.16098)
		(end 222.339154 -281.54884)
		(stroke
			(width 0.2)
			(type default)
		)
		(layer "In1.Cu")
	)
	(gr_line
		(start 221.114874 -280.43124)
		(end 221.114874 -281.54884)
		(stroke
			(width 0.2)
			(type default)
		)
		(layer "In1.Cu")
	)
	(gr_arc
		(start 221.114874 -276.748748)
		(mid 221.727014 -277.360888)
		(end 222.339154 -276.748748)
		(stroke
			(width 0.2)
			(type default)
		)
		(layer "In1.Cu")
	)
	(gr_line
		(start 221.114874 -275.631148)
		(end 221.114874 -276.748748)
		(stroke
			(width 0.2)
			(type default)
		)
		(layer "In1.Cu")
	)
	(gr_arc
		(start 221.114874 -263.948926)
		(mid 221.727014 -264.561066)
		(end 222.339154 -263.948926)
		(stroke
			(width 0.2)
			(type default)
		)
		(layer "In1.Cu")
	)
	(gr_line
		(start 221.114874 -262.831326)
		(end 221.114874 -263.948926)
		(stroke
			(width 0.2)
			(type default)
		)
		(layer "In1.Cu")
	)
	(gr_arc
		(start 221.114874 -183.348884)
		(mid 221.727014 -183.961024)
		(end 222.339154 -183.348884)
		(stroke
			(width 0.2)
			(type default)
		)
		(layer "In1.Cu")
	)
	(gr_line
		(start 221.114874 -182.231284)
		(end 221.114874 -183.348884)
		(stroke
			(width 0.2)
			(type default)
		)
		(layer "In1.Cu")
	)
	(gr_arc
		(start 221.114874 -178.548792)
		(mid 221.727014 -179.160932)
		(end 222.339154 -178.548792)
		(stroke
			(width 0.2)
			(type default)
		)
		(layer "In1.Cu")
	)
	(gr_line
		(start 221.114874 -177.431192)
		(end 221.114874 -178.548792)
		(stroke
			(width 0.2)
			(type default)
		)
		(layer "In1.Cu")
	)
	(gr_arc
		(start 221.114874 -173.7487)
		(mid 221.727014 -174.36084)
		(end 222.339154 -173.7487)
		(stroke
			(width 0.2)
			(type default)
		)
		(layer "In1.Cu")
	)
	(gr_line
		(start 221.114874 -172.6311)
		(end 221.114874 -173.7487)
		(stroke
			(width 0.2)
			(type default)
		)
		(layer "In1.Cu")
	)
	(gr_arc
		(start 221.114874 -160.948878)
		(mid 221.727014 -161.561018)
		(end 222.339154 -160.948878)
		(stroke
			(width 0.2)
			(type default)
		)
		(layer "In1.Cu")
	)
	(gr_line
		(start 221.114874 -159.831278)
		(end 221.114874 -160.948878)
		(stroke
			(width 0.2)
			(type default)
		)
		(layer "In1.Cu")
	)
	(gr_arc
		(start 221.114874 -80.348836)
		(mid 221.727014 -80.960976)
		(end 222.339154 -80.348836)
		(stroke
			(width 0.2)
			(type default)
		)
		(layer "In1.Cu")
	)
	(gr_line
		(start 221.114874 -79.231236)
		(end 221.114874 -80.348836)
		(stroke
			(width 0.2)
			(type default)
		)
		(layer "In1.Cu")
	)
	(gr_arc
		(start 221.114874 -75.548744)
		(mid 221.727014 -76.160884)
		(end 222.339154 -75.548744)
		(stroke
			(width 0.2)
			(type default)
		)
		(layer "In1.Cu")
	)
	(gr_line
		(start 221.114874 -74.431144)
		(end 221.114874 -75.548744)
		(stroke
			(width 0.2)
			(type default)
		)
		(layer "In1.Cu")
	)
	(gr_arc
		(start 221.114874 -70.748652)
		(mid 221.727014 -71.360792)
		(end 222.339154 -70.748652)
		(stroke
			(width 0.2)
			(type default)
		)
		(layer "In1.Cu")
	)
	(gr_line
		(start 221.114874 -69.631052)
		(end 221.114874 -70.748652)
		(stroke
			(width 0.2)
			(type default)
		)
		(layer "In1.Cu")
	)
	(gr_arc
		(start 221.114874 -57.94883)
		(mid 221.727014 -58.56097)
		(end 222.339154 -57.94883)
		(stroke
			(width 0.2)
			(type default)
		)
		(layer "In1.Cu")
	)
	(gr_line
		(start 221.114874 -56.83123)
		(end 221.114874 -57.94883)
		(stroke
			(width 0.2)
			(type default)
		)
		(layer "In1.Cu")
	)
	(gr_line
		(start 222.339154 -492.349028)
		(end 222.339154 -491.231682)
		(stroke
			(width 0.2)
			(type default)
		)
		(layer "In1.Cu")
	)
	(gr_arc
		(start 222.339154 -491.231682)
		(mid 221.727141 -490.619288)
		(end 221.114874 -491.231428)
		(stroke
			(width 0.2)
			(type default)
		)
		(layer "In1.Cu")
	)
	(gr_line
		(start 222.339154 -487.548936)
		(end 222.339154 -486.43159)
		(stroke
			(width 0.2)
			(type default)
		)
		(layer "In1.Cu")
	)
	(gr_arc
		(start 222.339154 -486.43159)
		(mid 221.727141 -485.819196)
		(end 221.114874 -486.431336)
		(stroke
			(width 0.2)
			(type default)
		)
		(layer "In1.Cu")
	)
	(gr_line
		(start 222.339154 -482.748844)
		(end 222.339154 -481.631498)
		(stroke
			(width 0.2)
			(type default)
		)
		(layer "In1.Cu")
	)
	(gr_arc
		(start 222.339154 -481.631498)
		(mid 221.727141 -481.019104)
		(end 221.114874 -481.631244)
		(stroke
			(width 0.2)
			(type default)
		)
		(layer "In1.Cu")
	)
	(gr_line
		(start 222.339154 -469.949022)
		(end 222.339154 -468.831676)
		(stroke
			(width 0.2)
			(type default)
		)
		(layer "In1.Cu")
	)
	(gr_arc
		(start 222.339154 -468.831676)
		(mid 221.727141 -468.219282)
		(end 221.114874 -468.831422)
		(stroke
			(width 0.2)
			(type default)
		)
		(layer "In1.Cu")
	)
	(gr_line
		(start 222.339154 -389.34898)
		(end 222.339154 -388.231634)
		(stroke
			(width 0.2)
			(type default)
		)
		(layer "In1.Cu")
	)
	(gr_arc
		(start 222.339154 -388.231634)
		(mid 221.727141 -387.61924)
		(end 221.114874 -388.23138)
		(stroke
			(width 0.2)
			(type default)
		)
		(layer "In1.Cu")
	)
	(gr_line
		(start 222.339154 -384.548888)
		(end 222.339154 -383.431542)
		(stroke
			(width 0.2)
			(type default)
		)
		(layer "In1.Cu")
	)
	(gr_arc
		(start 222.339154 -383.431542)
		(mid 221.727141 -382.819148)
		(end 221.114874 -383.431288)
		(stroke
			(width 0.2)
			(type default)
		)
		(layer "In1.Cu")
	)
	(gr_line
		(start 222.339154 -379.748796)
		(end 222.339154 -378.63145)
		(stroke
			(width 0.2)
			(type default)
		)
		(layer "In1.Cu")
	)
	(gr_arc
		(start 222.339154 -378.63145)
		(mid 221.727141 -378.019056)
		(end 221.114874 -378.631196)
		(stroke
			(width 0.2)
			(type default)
		)
		(layer "In1.Cu")
	)
	(gr_line
		(start 222.339154 -366.948974)
		(end 222.339154 -365.831628)
		(stroke
			(width 0.2)
			(type default)
		)
		(layer "In1.Cu")
	)
	(gr_arc
		(start 222.339154 -365.831628)
		(mid 221.727141 -365.219234)
		(end 221.114874 -365.831374)
		(stroke
			(width 0.2)
			(type default)
		)
		(layer "In1.Cu")
	)
	(gr_line
		(start 222.339154 -286.348932)
		(end 222.339154 -285.231586)
		(stroke
			(width 0.2)
			(type default)
		)
		(layer "In1.Cu")
	)
	(gr_arc
		(start 222.339154 -285.231586)
		(mid 221.727141 -284.619192)
		(end 221.114874 -285.231332)
		(stroke
			(width 0.2)
			(type default)
		)
		(layer "In1.Cu")
	)
	(gr_line
		(start 222.339154 -281.54884)
		(end 222.339154 -280.431494)
		(stroke
			(width 0.2)
			(type default)
		)
		(layer "In1.Cu")
	)
	(gr_arc
		(start 222.339154 -280.431494)
		(mid 221.727141 -279.8191)
		(end 221.114874 -280.43124)
		(stroke
			(width 0.2)
			(type default)
		)
		(layer "In1.Cu")
	)
	(gr_line
		(start 222.339154 -276.748748)
		(end 222.339154 -275.631402)
		(stroke
			(width 0.2)
			(type default)
		)
		(layer "In1.Cu")
	)
	(gr_arc
		(start 222.339154 -275.631402)
		(mid 221.727141 -275.019008)
		(end 221.114874 -275.631148)
		(stroke
			(width 0.2)
			(type default)
		)
		(layer "In1.Cu")
	)
	(gr_line
		(start 222.339154 -263.948926)
		(end 222.339154 -262.83158)
		(stroke
			(width 0.2)
			(type default)
		)
		(layer "In1.Cu")
	)
	(gr_arc
		(start 222.339154 -262.83158)
		(mid 221.727141 -262.219186)
		(end 221.114874 -262.831326)
		(stroke
			(width 0.2)
			(type default)
		)
		(layer "In1.Cu")
	)
	(gr_line
		(start 222.339154 -183.348884)
		(end 222.339154 -182.231538)
		(stroke
			(width 0.2)
			(type default)
		)
		(layer "In1.Cu")
	)
	(gr_arc
		(start 222.339154 -182.231538)
		(mid 221.727141 -181.619144)
		(end 221.114874 -182.231284)
		(stroke
			(width 0.2)
			(type default)
		)
		(layer "In1.Cu")
	)
	(gr_line
		(start 222.339154 -178.548792)
		(end 222.339154 -177.431446)
		(stroke
			(width 0.2)
			(type default)
		)
		(layer "In1.Cu")
	)
	(gr_arc
		(start 222.339154 -177.431446)
		(mid 221.727141 -176.819052)
		(end 221.114874 -177.431192)
		(stroke
			(width 0.2)
			(type default)
		)
		(layer "In1.Cu")
	)
	(gr_line
		(start 222.339154 -173.7487)
		(end 222.339154 -172.631354)
		(stroke
			(width 0.2)
			(type default)
		)
		(layer "In1.Cu")
	)
	(gr_arc
		(start 222.339154 -172.631354)
		(mid 221.727141 -172.01896)
		(end 221.114874 -172.6311)
		(stroke
			(width 0.2)
			(type default)
		)
		(layer "In1.Cu")
	)
	(gr_line
		(start 222.339154 -160.948878)
		(end 222.339154 -159.831532)
		(stroke
			(width 0.2)
			(type default)
		)
		(layer "In1.Cu")
	)
	(gr_arc
		(start 222.339154 -159.831532)
		(mid 221.727141 -159.219138)
		(end 221.114874 -159.831278)
		(stroke
			(width 0.2)
			(type default)
		)
		(layer "In1.Cu")
	)
	(gr_line
		(start 222.339154 -80.348836)
		(end 222.339154 -79.23149)
		(stroke
			(width 0.2)
			(type default)
		)
		(layer "In1.Cu")
	)
	(gr_arc
		(start 222.339154 -79.23149)
		(mid 221.727141 -78.619096)
		(end 221.114874 -79.231236)
		(stroke
			(width 0.2)
			(type default)
		)
		(layer "In1.Cu")
	)
	(gr_line
		(start 222.339154 -75.548744)
		(end 222.339154 -74.431398)
		(stroke
			(width 0.2)
			(type default)
		)
		(layer "In1.Cu")
	)
	(gr_arc
		(start 222.339154 -74.431398)
		(mid 221.727141 -73.819004)
		(end 221.114874 -74.431144)
		(stroke
			(width 0.2)
			(type default)
		)
		(layer "In1.Cu")
	)
	(gr_line
		(start 222.339154 -70.748652)
		(end 222.339154 -69.631306)
		(stroke
			(width 0.2)
			(type default)
		)
		(layer "In1.Cu")
	)
	(gr_arc
		(start 222.339154 -69.631306)
		(mid 221.727141 -69.018912)
		(end 221.114874 -69.631052)
		(stroke
			(width 0.2)
			(type default)
		)
		(layer "In1.Cu")
	)
	(gr_line
		(start 222.339154 -57.94883)
		(end 222.339154 -56.831484)
		(stroke
			(width 0.2)
			(type default)
		)
		(layer "In1.Cu")
	)
	(gr_arc
		(start 222.339154 -56.831484)
		(mid 221.727141 -56.21909)
		(end 221.114874 -56.83123)
		(stroke
			(width 0.2)
			(type default)
		)
		(layer "In1.Cu")
	)
	(gr_line
		(start 223.196658 -492.736124)
		(end 225.203258 -492.736124)
		(stroke
			(width 0.2)
			(type default)
		)
		(layer "In1.Cu")
	)
	(gr_line
		(start 223.196658 -490.844078)
		(end 223.196658 -492.736124)
		(stroke
			(width 0.2)
			(type default)
		)
		(layer "In1.Cu")
	)
	(gr_line
		(start 223.196658 -490.336332)
		(end 225.203258 -490.336332)
		(stroke
			(width 0.2)
			(type default)
		)
		(layer "In1.Cu")
	)
	(gr_line
		(start 223.196658 -488.444032)
		(end 223.196658 -490.336332)
		(stroke
			(width 0.2)
			(type default)
		)
		(layer "In1.Cu")
	)
	(gr_line
		(start 223.196658 -487.936286)
		(end 225.203258 -487.936286)
		(stroke
			(width 0.2)
			(type default)
		)
		(layer "In1.Cu")
	)
	(gr_line
		(start 223.196658 -486.043986)
		(end 223.196658 -487.936286)
		(stroke
			(width 0.2)
			(type default)
		)
		(layer "In1.Cu")
	)
	(gr_line
		(start 223.196658 -485.535986)
		(end 223.196912 -485.53624)
		(stroke
			(width 0.2)
			(type default)
		)
		(layer "In1.Cu")
	)
	(gr_line
		(start 223.196658 -483.64394)
		(end 223.196658 -485.535986)
		(stroke
			(width 0.2)
			(type default)
		)
		(layer "In1.Cu")
	)
	(gr_line
		(start 223.196658 -483.136194)
		(end 225.203258 -483.136194)
		(stroke
			(width 0.2)
			(type default)
		)
		(layer "In1.Cu")
	)
	(gr_line
		(start 223.196658 -481.243894)
		(end 223.196658 -483.136194)
		(stroke
			(width 0.2)
			(type default)
		)
		(layer "In1.Cu")
	)
	(gr_line
		(start 223.196658 -480.736148)
		(end 225.203258 -480.736148)
		(stroke
			(width 0.2)
			(type default)
		)
		(layer "In1.Cu")
	)
	(gr_line
		(start 223.196658 -478.844102)
		(end 223.196658 -480.736148)
		(stroke
			(width 0.2)
			(type default)
		)
		(layer "In1.Cu")
	)
	(gr_line
		(start 223.196658 -470.336118)
		(end 225.203258 -470.336118)
		(stroke
			(width 0.2)
			(type default)
		)
		(layer "In1.Cu")
	)
	(gr_line
		(start 223.196658 -468.444072)
		(end 223.196658 -470.336118)
		(stroke
			(width 0.2)
			(type default)
		)
		(layer "In1.Cu")
	)
	(gr_line
		(start 223.196658 -467.936326)
		(end 225.203258 -467.936326)
		(stroke
			(width 0.2)
			(type default)
		)
		(layer "In1.Cu")
	)
	(gr_line
		(start 223.196658 -466.044026)
		(end 223.196658 -467.936326)
		(stroke
			(width 0.2)
			(type default)
		)
		(layer "In1.Cu")
	)
	(gr_line
		(start 223.196658 -465.53628)
		(end 225.203258 -465.53628)
		(stroke
			(width 0.2)
			(type default)
		)
		(layer "In1.Cu")
	)
	(gr_line
		(start 223.196658 -463.64398)
		(end 223.196658 -465.53628)
		(stroke
			(width 0.2)
			(type default)
		)
		(layer "In1.Cu")
	)
	(gr_line
		(start 223.196658 -389.736076)
		(end 225.203258 -389.736076)
		(stroke
			(width 0.2)
			(type default)
		)
		(layer "In1.Cu")
	)
	(gr_line
		(start 223.196658 -387.84403)
		(end 223.196658 -389.736076)
		(stroke
			(width 0.2)
			(type default)
		)
		(layer "In1.Cu")
	)
	(gr_line
		(start 223.196658 -387.336284)
		(end 225.203258 -387.336284)
		(stroke
			(width 0.2)
			(type default)
		)
		(layer "In1.Cu")
	)
	(gr_line
		(start 223.196658 -385.443984)
		(end 223.196658 -387.336284)
		(stroke
			(width 0.2)
			(type default)
		)
		(layer "In1.Cu")
	)
	(gr_line
		(start 223.196658 -384.936238)
		(end 225.203258 -384.936238)
		(stroke
			(width 0.2)
			(type default)
		)
		(layer "In1.Cu")
	)
	(gr_line
		(start 223.196658 -383.043938)
		(end 223.196658 -384.936238)
		(stroke
			(width 0.2)
			(type default)
		)
		(layer "In1.Cu")
	)
	(gr_line
		(start 223.196658 -382.536192)
		(end 225.203258 -382.536192)
		(stroke
			(width 0.2)
			(type default)
		)
		(layer "In1.Cu")
	)
	(gr_line
		(start 223.196658 -380.643892)
		(end 223.196658 -382.536192)
		(stroke
			(width 0.2)
			(type default)
		)
		(layer "In1.Cu")
	)
	(gr_line
		(start 223.196658 -380.136146)
		(end 225.203258 -380.136146)
		(stroke
			(width 0.2)
			(type default)
		)
		(layer "In1.Cu")
	)
	(gr_line
		(start 223.196658 -378.243846)
		(end 223.196658 -380.136146)
		(stroke
			(width 0.2)
			(type default)
		)
		(layer "In1.Cu")
	)
	(gr_line
		(start 223.196658 -377.7361)
		(end 225.203258 -377.7361)
		(stroke
			(width 0.2)
			(type default)
		)
		(layer "In1.Cu")
	)
	(gr_line
		(start 223.196658 -375.844054)
		(end 223.196658 -377.7361)
		(stroke
			(width 0.2)
			(type default)
		)
		(layer "In1.Cu")
	)
	(gr_line
		(start 223.196658 -367.33607)
		(end 225.203258 -367.33607)
		(stroke
			(width 0.2)
			(type default)
		)
		(layer "In1.Cu")
	)
	(gr_line
		(start 223.196658 -365.444024)
		(end 223.196658 -367.33607)
		(stroke
			(width 0.2)
			(type default)
		)
		(layer "In1.Cu")
	)
	(gr_line
		(start 223.196658 -364.936278)
		(end 225.203258 -364.936278)
		(stroke
			(width 0.2)
			(type default)
		)
		(layer "In1.Cu")
	)
	(gr_line
		(start 223.196658 -363.043978)
		(end 223.196658 -364.936278)
		(stroke
			(width 0.2)
			(type default)
		)
		(layer "In1.Cu")
	)
	(gr_line
		(start 223.196658 -362.536232)
		(end 225.203258 -362.536232)
		(stroke
			(width 0.2)
			(type default)
		)
		(layer "In1.Cu")
	)
	(gr_line
		(start 223.196658 -360.643932)
		(end 223.196658 -362.536232)
		(stroke
			(width 0.2)
			(type default)
		)
		(layer "In1.Cu")
	)
	(gr_line
		(start 223.196658 -286.736028)
		(end 225.203258 -286.736028)
		(stroke
			(width 0.2)
			(type default)
		)
		(layer "In1.Cu")
	)
	(gr_line
		(start 223.196658 -284.843982)
		(end 223.196658 -286.736028)
		(stroke
			(width 0.2)
			(type default)
		)
		(layer "In1.Cu")
	)
	(gr_line
		(start 223.196658 -284.336236)
		(end 225.203258 -284.336236)
		(stroke
			(width 0.2)
			(type default)
		)
		(layer "In1.Cu")
	)
	(gr_line
		(start 223.196658 -282.443936)
		(end 223.196658 -284.336236)
		(stroke
			(width 0.2)
			(type default)
		)
		(layer "In1.Cu")
	)
	(gr_line
		(start 223.196658 -281.93619)
		(end 225.203258 -281.93619)
		(stroke
			(width 0.2)
			(type default)
		)
		(layer "In1.Cu")
	)
	(gr_line
		(start 223.196658 -280.04389)
		(end 223.196658 -281.93619)
		(stroke
			(width 0.2)
			(type default)
		)
		(layer "In1.Cu")
	)
	(gr_line
		(start 223.196658 -279.536144)
		(end 225.203258 -279.536144)
		(stroke
			(width 0.2)
			(type default)
		)
		(layer "In1.Cu")
	)
	(gr_line
		(start 223.196658 -277.643844)
		(end 223.196658 -279.536144)
		(stroke
			(width 0.2)
			(type default)
		)
		(layer "In1.Cu")
	)
	(gr_line
		(start 223.196658 -277.136098)
		(end 225.203258 -277.136098)
		(stroke
			(width 0.2)
			(type default)
		)
		(layer "In1.Cu")
	)
	(gr_line
		(start 223.196658 -275.243798)
		(end 223.196658 -277.136098)
		(stroke
			(width 0.2)
			(type default)
		)
		(layer "In1.Cu")
	)
	(gr_line
		(start 223.196658 -274.736052)
		(end 225.203258 -274.736052)
		(stroke
			(width 0.2)
			(type default)
		)
		(layer "In1.Cu")
	)
	(gr_line
		(start 223.196658 -272.844006)
		(end 223.196658 -274.736052)
		(stroke
			(width 0.2)
			(type default)
		)
		(layer "In1.Cu")
	)
	(gr_line
		(start 223.196658 -264.335768)
		(end 223.196912 -264.336022)
		(stroke
			(width 0.2)
			(type default)
		)
		(layer "In1.Cu")
	)
	(gr_line
		(start 223.196658 -262.443976)
		(end 223.196658 -264.335768)
		(stroke
			(width 0.2)
			(type default)
		)
		(layer "In1.Cu")
	)
	(gr_line
		(start 223.196658 -261.93623)
		(end 225.203258 -261.93623)
		(stroke
			(width 0.2)
			(type default)
		)
		(layer "In1.Cu")
	)
	(gr_line
		(start 223.196658 -260.04393)
		(end 223.196658 -261.93623)
		(stroke
			(width 0.2)
			(type default)
		)
		(layer "In1.Cu")
	)
	(gr_line
		(start 223.196658 -259.536184)
		(end 225.203258 -259.536184)
		(stroke
			(width 0.2)
			(type default)
		)
		(layer "In1.Cu")
	)
	(gr_line
		(start 223.196658 -257.643884)
		(end 223.196658 -259.536184)
		(stroke
			(width 0.2)
			(type default)
		)
		(layer "In1.Cu")
	)
	(gr_line
		(start 223.196658 -183.73598)
		(end 225.203258 -183.73598)
		(stroke
			(width 0.2)
			(type default)
		)
		(layer "In1.Cu")
	)
	(gr_line
		(start 223.196658 -181.843934)
		(end 223.196658 -183.73598)
		(stroke
			(width 0.2)
			(type default)
		)
		(layer "In1.Cu")
	)
	(gr_line
		(start 223.196658 -181.336188)
		(end 225.203258 -181.336188)
		(stroke
			(width 0.2)
			(type default)
		)
		(layer "In1.Cu")
	)
	(gr_line
		(start 223.196658 -179.443888)
		(end 223.196658 -181.336188)
		(stroke
			(width 0.2)
			(type default)
		)
		(layer "In1.Cu")
	)
	(gr_line
		(start 223.196658 -178.936142)
		(end 225.203258 -178.936142)
		(stroke
			(width 0.2)
			(type default)
		)
		(layer "In1.Cu")
	)
	(gr_line
		(start 223.196658 -177.043842)
		(end 223.196658 -178.936142)
		(stroke
			(width 0.2)
			(type default)
		)
		(layer "In1.Cu")
	)
	(gr_line
		(start 223.196658 -176.536096)
		(end 225.203258 -176.536096)
		(stroke
			(width 0.2)
			(type default)
		)
		(layer "In1.Cu")
	)
	(gr_line
		(start 223.196658 -174.643796)
		(end 223.196658 -176.536096)
		(stroke
			(width 0.2)
			(type default)
		)
		(layer "In1.Cu")
	)
	(gr_line
		(start 223.196658 -174.13605)
		(end 225.203258 -174.13605)
		(stroke
			(width 0.2)
			(type default)
		)
		(layer "In1.Cu")
	)
	(gr_line
		(start 223.196658 -172.24375)
		(end 223.196658 -174.13605)
		(stroke
			(width 0.2)
			(type default)
		)
		(layer "In1.Cu")
	)
	(gr_line
		(start 223.196658 -171.736004)
		(end 225.203258 -171.736004)
		(stroke
			(width 0.2)
			(type default)
		)
		(layer "In1.Cu")
	)
	(gr_line
		(start 223.196658 -169.843958)
		(end 223.196658 -171.736004)
		(stroke
			(width 0.2)
			(type default)
		)
		(layer "In1.Cu")
	)
	(gr_line
		(start 223.196658 -161.335974)
		(end 225.203258 -161.335974)
		(stroke
			(width 0.2)
			(type default)
		)
		(layer "In1.Cu")
	)
	(gr_line
		(start 223.196658 -159.443928)
		(end 223.196658 -161.335974)
		(stroke
			(width 0.2)
			(type default)
		)
		(layer "In1.Cu")
	)
	(gr_line
		(start 223.196658 -158.936182)
		(end 225.203258 -158.936182)
		(stroke
			(width 0.2)
			(type default)
		)
		(layer "In1.Cu")
	)
	(gr_line
		(start 223.196658 -157.043882)
		(end 223.196658 -158.936182)
		(stroke
			(width 0.2)
			(type default)
		)
		(layer "In1.Cu")
	)
	(gr_line
		(start 223.196658 -156.536136)
		(end 225.203258 -156.536136)
		(stroke
			(width 0.2)
			(type default)
		)
		(layer "In1.Cu")
	)
	(gr_line
		(start 223.196658 -154.643836)
		(end 223.196658 -156.536136)
		(stroke
			(width 0.2)
			(type default)
		)
		(layer "In1.Cu")
	)
	(gr_line
		(start 223.196658 -80.735932)
		(end 225.203258 -80.735932)
		(stroke
			(width 0.2)
			(type default)
		)
		(layer "In1.Cu")
	)
	(gr_line
		(start 223.196658 -78.843886)
		(end 223.196658 -80.735932)
		(stroke
			(width 0.2)
			(type default)
		)
		(layer "In1.Cu")
	)
	(gr_line
		(start 223.196658 -78.33614)
		(end 225.203258 -78.33614)
		(stroke
			(width 0.2)
			(type default)
		)
		(layer "In1.Cu")
	)
	(gr_line
		(start 223.196658 -76.44384)
		(end 223.196658 -78.33614)
		(stroke
			(width 0.2)
			(type default)
		)
		(layer "In1.Cu")
	)
	(gr_line
		(start 223.196658 -75.936094)
		(end 225.203258 -75.936094)
		(stroke
			(width 0.2)
			(type default)
		)
		(layer "In1.Cu")
	)
	(gr_line
		(start 223.196658 -74.043794)
		(end 223.196658 -75.936094)
		(stroke
			(width 0.2)
			(type default)
		)
		(layer "In1.Cu")
	)
	(gr_line
		(start 223.196658 -73.536048)
		(end 225.203258 -73.536048)
		(stroke
			(width 0.2)
			(type default)
		)
		(layer "In1.Cu")
	)
	(gr_line
		(start 223.196658 -71.643748)
		(end 223.196658 -73.536048)
		(stroke
			(width 0.2)
			(type default)
		)
		(layer "In1.Cu")
	)
	(gr_line
		(start 223.196658 -71.136002)
		(end 225.203258 -71.136002)
		(stroke
			(width 0.2)
			(type default)
		)
		(layer "In1.Cu")
	)
	(gr_line
		(start 223.196658 -69.243702)
		(end 223.196658 -71.136002)
		(stroke
			(width 0.2)
			(type default)
		)
		(layer "In1.Cu")
	)
	(gr_line
		(start 223.196658 -68.735956)
		(end 225.203258 -68.735956)
		(stroke
			(width 0.2)
			(type default)
		)
		(layer "In1.Cu")
	)
	(gr_line
		(start 223.196658 -66.84391)
		(end 223.196658 -68.735956)
		(stroke
			(width 0.2)
			(type default)
		)
		(layer "In1.Cu")
	)
	(gr_line
		(start 223.196658 -58.335926)
		(end 225.203258 -58.335926)
		(stroke
			(width 0.2)
			(type default)
		)
		(layer "In1.Cu")
	)
	(gr_line
		(start 223.196658 -56.44388)
		(end 223.196658 -58.335926)
		(stroke
			(width 0.2)
			(type default)
		)
		(layer "In1.Cu")
	)
	(gr_line
		(start 223.196658 -55.936134)
		(end 225.203258 -55.936134)
		(stroke
			(width 0.2)
			(type default)
		)
		(layer "In1.Cu")
	)
	(gr_line
		(start 223.196658 -54.043834)
		(end 223.196658 -55.936134)
		(stroke
			(width 0.2)
			(type default)
		)
		(layer "In1.Cu")
	)
	(gr_line
		(start 223.196658 -53.536088)
		(end 225.203258 -53.536088)
		(stroke
			(width 0.2)
			(type default)
		)
		(layer "In1.Cu")
	)
	(gr_line
		(start 223.196658 -51.643788)
		(end 223.196658 -53.536088)
		(stroke
			(width 0.2)
			(type default)
		)
		(layer "In1.Cu")
	)
	(gr_line
		(start 223.196912 -485.53624)
		(end 225.203258 -485.53624)
		(stroke
			(width 0.2)
			(type default)
		)
		(layer "In1.Cu")
	)
	(gr_line
		(start 223.196912 -264.336022)
		(end 225.203258 -264.336022)
		(stroke
			(width 0.2)
			(type default)
		)
		(layer "In1.Cu")
	)
	(gr_line
		(start 225.203004 -490.844078)
		(end 223.196658 -490.844078)
		(stroke
			(width 0.2)
			(type default)
		)
		(layer "In1.Cu")
	)
	(gr_line
		(start 225.203004 -488.444032)
		(end 223.196658 -488.444032)
		(stroke
			(width 0.2)
			(type default)
		)
		(layer "In1.Cu")
	)
	(gr_line
		(start 225.203004 -486.043986)
		(end 223.196658 -486.043986)
		(stroke
			(width 0.2)
			(type default)
		)
		(layer "In1.Cu")
	)
	(gr_line
		(start 225.203004 -481.243894)
		(end 223.196658 -481.243894)
		(stroke
			(width 0.2)
			(type default)
		)
		(layer "In1.Cu")
	)
	(gr_line
		(start 225.203004 -478.844102)
		(end 223.196658 -478.844102)
		(stroke
			(width 0.2)
			(type default)
		)
		(layer "In1.Cu")
	)
	(gr_line
		(start 225.203004 -468.444072)
		(end 223.196658 -468.444072)
		(stroke
			(width 0.2)
			(type default)
		)
		(layer "In1.Cu")
	)
	(gr_line
		(start 225.203004 -466.044026)
		(end 223.196658 -466.044026)
		(stroke
			(width 0.2)
			(type default)
		)
		(layer "In1.Cu")
	)
	(gr_line
		(start 225.203004 -463.64398)
		(end 223.196658 -463.64398)
		(stroke
			(width 0.2)
			(type default)
		)
		(layer "In1.Cu")
	)
	(gr_line
		(start 225.203004 -387.84403)
		(end 223.196658 -387.84403)
		(stroke
			(width 0.2)
			(type default)
		)
		(layer "In1.Cu")
	)
	(gr_line
		(start 225.203004 -385.443984)
		(end 223.196658 -385.443984)
		(stroke
			(width 0.2)
			(type default)
		)
		(layer "In1.Cu")
	)
	(gr_line
		(start 225.203004 -383.043938)
		(end 223.196658 -383.043938)
		(stroke
			(width 0.2)
			(type default)
		)
		(layer "In1.Cu")
	)
	(gr_line
		(start 225.203004 -380.643892)
		(end 223.196658 -380.643892)
		(stroke
			(width 0.2)
			(type default)
		)
		(layer "In1.Cu")
	)
	(gr_line
		(start 225.203004 -378.243846)
		(end 223.196658 -378.243846)
		(stroke
			(width 0.2)
			(type default)
		)
		(layer "In1.Cu")
	)
	(gr_line
		(start 225.203004 -375.844054)
		(end 223.196658 -375.844054)
		(stroke
			(width 0.2)
			(type default)
		)
		(layer "In1.Cu")
	)
	(gr_line
		(start 225.203004 -365.444024)
		(end 223.196658 -365.444024)
		(stroke
			(width 0.2)
			(type default)
		)
		(layer "In1.Cu")
	)
	(gr_line
		(start 225.203004 -363.043978)
		(end 223.196658 -363.043978)
		(stroke
			(width 0.2)
			(type default)
		)
		(layer "In1.Cu")
	)
	(gr_line
		(start 225.203004 -360.643932)
		(end 223.196658 -360.643932)
		(stroke
			(width 0.2)
			(type default)
		)
		(layer "In1.Cu")
	)
	(gr_line
		(start 225.203004 -284.843982)
		(end 223.196658 -284.843982)
		(stroke
			(width 0.2)
			(type default)
		)
		(layer "In1.Cu")
	)
	(gr_line
		(start 225.203004 -282.443936)
		(end 223.196658 -282.443936)
		(stroke
			(width 0.2)
			(type default)
		)
		(layer "In1.Cu")
	)
	(gr_line
		(start 225.203004 -280.04389)
		(end 223.196658 -280.04389)
		(stroke
			(width 0.2)
			(type default)
		)
		(layer "In1.Cu")
	)
	(gr_line
		(start 225.203004 -277.643844)
		(end 223.196658 -277.643844)
		(stroke
			(width 0.2)
			(type default)
		)
		(layer "In1.Cu")
	)
	(gr_line
		(start 225.203004 -275.243798)
		(end 223.196658 -275.243798)
		(stroke
			(width 0.2)
			(type default)
		)
		(layer "In1.Cu")
	)
	(gr_line
		(start 225.203004 -272.844006)
		(end 223.196658 -272.844006)
		(stroke
			(width 0.2)
			(type default)
		)
		(layer "In1.Cu")
	)
	(gr_line
		(start 225.203004 -260.04393)
		(end 223.196658 -260.04393)
		(stroke
			(width 0.2)
			(type default)
		)
		(layer "In1.Cu")
	)
	(gr_line
		(start 225.203004 -257.643884)
		(end 223.196658 -257.643884)
		(stroke
			(width 0.2)
			(type default)
		)
		(layer "In1.Cu")
	)
	(gr_line
		(start 225.203004 -181.843934)
		(end 223.196658 -181.843934)
		(stroke
			(width 0.2)
			(type default)
		)
		(layer "In1.Cu")
	)
	(gr_line
		(start 225.203004 -179.443888)
		(end 223.196658 -179.443888)
		(stroke
			(width 0.2)
			(type default)
		)
		(layer "In1.Cu")
	)
	(gr_line
		(start 225.203004 -177.043842)
		(end 223.196658 -177.043842)
		(stroke
			(width 0.2)
			(type default)
		)
		(layer "In1.Cu")
	)
	(gr_line
		(start 225.203004 -174.643796)
		(end 223.196658 -174.643796)
		(stroke
			(width 0.2)
			(type default)
		)
		(layer "In1.Cu")
	)
	(gr_line
		(start 225.203004 -172.24375)
		(end 223.196658 -172.24375)
		(stroke
			(width 0.2)
			(type default)
		)
		(layer "In1.Cu")
	)
	(gr_line
		(start 225.203004 -169.843958)
		(end 223.196658 -169.843958)
		(stroke
			(width 0.2)
			(type default)
		)
		(layer "In1.Cu")
	)
	(gr_line
		(start 225.203004 -159.443928)
		(end 223.196658 -159.443928)
		(stroke
			(width 0.2)
			(type default)
		)
		(layer "In1.Cu")
	)
	(gr_line
		(start 225.203004 -157.043882)
		(end 223.196658 -157.043882)
		(stroke
			(width 0.2)
			(type default)
		)
		(layer "In1.Cu")
	)
	(gr_line
		(start 225.203004 -154.643836)
		(end 223.196658 -154.643836)
		(stroke
			(width 0.2)
			(type default)
		)
		(layer "In1.Cu")
	)
	(gr_line
		(start 225.203004 -78.843886)
		(end 223.196658 -78.843886)
		(stroke
			(width 0.2)
			(type default)
		)
		(layer "In1.Cu")
	)
	(gr_line
		(start 225.203004 -76.44384)
		(end 223.196658 -76.44384)
		(stroke
			(width 0.2)
			(type default)
		)
		(layer "In1.Cu")
	)
	(gr_line
		(start 225.203004 -74.043794)
		(end 223.196658 -74.043794)
		(stroke
			(width 0.2)
			(type default)
		)
		(layer "In1.Cu")
	)
	(gr_line
		(start 225.203004 -71.643748)
		(end 223.196658 -71.643748)
		(stroke
			(width 0.2)
			(type default)
		)
		(layer "In1.Cu")
	)
	(gr_line
		(start 225.203004 -69.243702)
		(end 223.196658 -69.243702)
		(stroke
			(width 0.2)
			(type default)
		)
		(layer "In1.Cu")
	)
	(gr_line
		(start 225.203004 -66.84391)
		(end 223.196658 -66.84391)
		(stroke
			(width 0.2)
			(type default)
		)
		(layer "In1.Cu")
	)
	(gr_line
		(start 225.203004 -56.44388)
		(end 223.196658 -56.44388)
		(stroke
			(width 0.2)
			(type default)
		)
		(layer "In1.Cu")
	)
	(gr_line
		(start 225.203004 -54.043834)
		(end 223.196658 -54.043834)
		(stroke
			(width 0.2)
			(type default)
		)
		(layer "In1.Cu")
	)
	(gr_line
		(start 225.203004 -51.643788)
		(end 223.196658 -51.643788)
		(stroke
			(width 0.2)
			(type default)
		)
		(layer "In1.Cu")
	)
	(gr_line
		(start 225.203258 -492.736124)
		(end 225.203258 -490.844332)
		(stroke
			(width 0.2)
			(type default)
		)
		(layer "In1.Cu")
	)
	(gr_line
		(start 225.203258 -490.844332)
		(end 225.203004 -490.844078)
		(stroke
			(width 0.2)
			(type default)
		)
		(layer "In1.Cu")
	)
	(gr_line
		(start 225.203258 -490.336332)
		(end 225.203258 -488.444286)
		(stroke
			(width 0.2)
			(type default)
		)
		(layer "In1.Cu")
	)
	(gr_line
		(start 225.203258 -488.444286)
		(end 225.203004 -488.444032)
		(stroke
			(width 0.2)
			(type default)
		)
		(layer "In1.Cu")
	)
	(gr_line
		(start 225.203258 -487.936286)
		(end 225.203258 -486.04424)
		(stroke
			(width 0.2)
			(type default)
		)
		(layer "In1.Cu")
	)
	(gr_line
		(start 225.203258 -486.04424)
		(end 225.203004 -486.043986)
		(stroke
			(width 0.2)
			(type default)
		)
		(layer "In1.Cu")
	)
	(gr_line
		(start 225.203258 -485.53624)
		(end 225.203258 -483.64394)
		(stroke
			(width 0.2)
			(type default)
		)
		(layer "In1.Cu")
	)
	(gr_line
		(start 225.203258 -483.64394)
		(end 223.196658 -483.64394)
		(stroke
			(width 0.2)
			(type default)
		)
		(layer "In1.Cu")
	)
	(gr_line
		(start 225.203258 -483.136194)
		(end 225.203258 -481.244148)
		(stroke
			(width 0.2)
			(type default)
		)
		(layer "In1.Cu")
	)
	(gr_line
		(start 225.203258 -481.244148)
		(end 225.203004 -481.243894)
		(stroke
			(width 0.2)
			(type default)
		)
		(layer "In1.Cu")
	)
	(gr_line
		(start 225.203258 -480.736148)
		(end 225.203258 -478.844356)
		(stroke
			(width 0.2)
			(type default)
		)
		(layer "In1.Cu")
	)
	(gr_line
		(start 225.203258 -478.844356)
		(end 225.203004 -478.844102)
		(stroke
			(width 0.2)
			(type default)
		)
		(layer "In1.Cu")
	)
	(gr_line
		(start 225.203258 -470.336118)
		(end 225.203258 -468.444326)
		(stroke
			(width 0.2)
			(type default)
		)
		(layer "In1.Cu")
	)
	(gr_line
		(start 225.203258 -468.444326)
		(end 225.203004 -468.444072)
		(stroke
			(width 0.2)
			(type default)
		)
		(layer "In1.Cu")
	)
	(gr_line
		(start 225.203258 -467.936326)
		(end 225.203258 -466.04428)
		(stroke
			(width 0.2)
			(type default)
		)
		(layer "In1.Cu")
	)
	(gr_line
		(start 225.203258 -466.04428)
		(end 225.203004 -466.044026)
		(stroke
			(width 0.2)
			(type default)
		)
		(layer "In1.Cu")
	)
	(gr_line
		(start 225.203258 -465.53628)
		(end 225.203258 -463.644234)
		(stroke
			(width 0.2)
			(type default)
		)
		(layer "In1.Cu")
	)
	(gr_line
		(start 225.203258 -463.644234)
		(end 225.203004 -463.64398)
		(stroke
			(width 0.2)
			(type default)
		)
		(layer "In1.Cu")
	)
	(gr_line
		(start 225.203258 -389.736076)
		(end 225.203258 -387.844284)
		(stroke
			(width 0.2)
			(type default)
		)
		(layer "In1.Cu")
	)
	(gr_line
		(start 225.203258 -387.844284)
		(end 225.203004 -387.84403)
		(stroke
			(width 0.2)
			(type default)
		)
		(layer "In1.Cu")
	)
	(gr_line
		(start 225.203258 -387.336284)
		(end 225.203258 -385.444238)
		(stroke
			(width 0.2)
			(type default)
		)
		(layer "In1.Cu")
	)
	(gr_line
		(start 225.203258 -385.444238)
		(end 225.203004 -385.443984)
		(stroke
			(width 0.2)
			(type default)
		)
		(layer "In1.Cu")
	)
	(gr_line
		(start 225.203258 -384.936238)
		(end 225.203258 -383.044192)
		(stroke
			(width 0.2)
			(type default)
		)
		(layer "In1.Cu")
	)
	(gr_line
		(start 225.203258 -383.044192)
		(end 225.203004 -383.043938)
		(stroke
			(width 0.2)
			(type default)
		)
		(layer "In1.Cu")
	)
	(gr_line
		(start 225.203258 -382.536192)
		(end 225.203258 -380.644146)
		(stroke
			(width 0.2)
			(type default)
		)
		(layer "In1.Cu")
	)
	(gr_line
		(start 225.203258 -380.644146)
		(end 225.203004 -380.643892)
		(stroke
			(width 0.2)
			(type default)
		)
		(layer "In1.Cu")
	)
	(gr_line
		(start 225.203258 -380.136146)
		(end 225.203258 -378.2441)
		(stroke
			(width 0.2)
			(type default)
		)
		(layer "In1.Cu")
	)
	(gr_line
		(start 225.203258 -378.2441)
		(end 225.203004 -378.243846)
		(stroke
			(width 0.2)
			(type default)
		)
		(layer "In1.Cu")
	)
	(gr_line
		(start 225.203258 -377.7361)
		(end 225.203258 -375.844308)
		(stroke
			(width 0.2)
			(type default)
		)
		(layer "In1.Cu")
	)
	(gr_line
		(start 225.203258 -375.844308)
		(end 225.203004 -375.844054)
		(stroke
			(width 0.2)
			(type default)
		)
		(layer "In1.Cu")
	)
	(gr_line
		(start 225.203258 -367.33607)
		(end 225.203258 -365.444278)
		(stroke
			(width 0.2)
			(type default)
		)
		(layer "In1.Cu")
	)
	(gr_line
		(start 225.203258 -365.444278)
		(end 225.203004 -365.444024)
		(stroke
			(width 0.2)
			(type default)
		)
		(layer "In1.Cu")
	)
	(gr_line
		(start 225.203258 -364.936278)
		(end 225.203258 -363.044232)
		(stroke
			(width 0.2)
			(type default)
		)
		(layer "In1.Cu")
	)
	(gr_line
		(start 225.203258 -363.044232)
		(end 225.203004 -363.043978)
		(stroke
			(width 0.2)
			(type default)
		)
		(layer "In1.Cu")
	)
	(gr_line
		(start 225.203258 -362.536232)
		(end 225.203258 -360.644186)
		(stroke
			(width 0.2)
			(type default)
		)
		(layer "In1.Cu")
	)
	(gr_line
		(start 225.203258 -360.644186)
		(end 225.203004 -360.643932)
		(stroke
			(width 0.2)
			(type default)
		)
		(layer "In1.Cu")
	)
	(gr_line
		(start 225.203258 -286.736028)
		(end 225.203258 -284.844236)
		(stroke
			(width 0.2)
			(type default)
		)
		(layer "In1.Cu")
	)
	(gr_line
		(start 225.203258 -284.844236)
		(end 225.203004 -284.843982)
		(stroke
			(width 0.2)
			(type default)
		)
		(layer "In1.Cu")
	)
	(gr_line
		(start 225.203258 -284.336236)
		(end 225.203258 -282.44419)
		(stroke
			(width 0.2)
			(type default)
		)
		(layer "In1.Cu")
	)
	(gr_line
		(start 225.203258 -282.44419)
		(end 225.203004 -282.443936)
		(stroke
			(width 0.2)
			(type default)
		)
		(layer "In1.Cu")
	)
	(gr_line
		(start 225.203258 -281.93619)
		(end 225.203258 -280.044144)
		(stroke
			(width 0.2)
			(type default)
		)
		(layer "In1.Cu")
	)
	(gr_line
		(start 225.203258 -280.044144)
		(end 225.203004 -280.04389)
		(stroke
			(width 0.2)
			(type default)
		)
		(layer "In1.Cu")
	)
	(gr_line
		(start 225.203258 -279.536144)
		(end 225.203258 -277.644098)
		(stroke
			(width 0.2)
			(type default)
		)
		(layer "In1.Cu")
	)
	(gr_line
		(start 225.203258 -277.644098)
		(end 225.203004 -277.643844)
		(stroke
			(width 0.2)
			(type default)
		)
		(layer "In1.Cu")
	)
	(gr_line
		(start 225.203258 -277.136098)
		(end 225.203258 -275.244052)
		(stroke
			(width 0.2)
			(type default)
		)
		(layer "In1.Cu")
	)
	(gr_line
		(start 225.203258 -275.244052)
		(end 225.203004 -275.243798)
		(stroke
			(width 0.2)
			(type default)
		)
		(layer "In1.Cu")
	)
	(gr_line
		(start 225.203258 -274.736052)
		(end 225.203258 -272.84426)
		(stroke
			(width 0.2)
			(type default)
		)
		(layer "In1.Cu")
	)
	(gr_line
		(start 225.203258 -272.84426)
		(end 225.203004 -272.844006)
		(stroke
			(width 0.2)
			(type default)
		)
		(layer "In1.Cu")
	)
	(gr_line
		(start 225.203258 -264.336022)
		(end 225.203258 -262.443976)
		(stroke
			(width 0.2)
			(type default)
		)
		(layer "In1.Cu")
	)
	(gr_line
		(start 225.203258 -262.443976)
		(end 223.196658 -262.443976)
		(stroke
			(width 0.2)
			(type default)
		)
		(layer "In1.Cu")
	)
	(gr_line
		(start 225.203258 -261.93623)
		(end 225.203258 -260.044184)
		(stroke
			(width 0.2)
			(type default)
		)
		(layer "In1.Cu")
	)
	(gr_line
		(start 225.203258 -260.044184)
		(end 225.203004 -260.04393)
		(stroke
			(width 0.2)
			(type default)
		)
		(layer "In1.Cu")
	)
	(gr_line
		(start 225.203258 -259.536184)
		(end 225.203258 -257.644138)
		(stroke
			(width 0.2)
			(type default)
		)
		(layer "In1.Cu")
	)
	(gr_line
		(start 225.203258 -257.644138)
		(end 225.203004 -257.643884)
		(stroke
			(width 0.2)
			(type default)
		)
		(layer "In1.Cu")
	)
	(gr_line
		(start 225.203258 -183.73598)
		(end 225.203258 -181.844188)
		(stroke
			(width 0.2)
			(type default)
		)
		(layer "In1.Cu")
	)
	(gr_line
		(start 225.203258 -181.844188)
		(end 225.203004 -181.843934)
		(stroke
			(width 0.2)
			(type default)
		)
		(layer "In1.Cu")
	)
	(gr_line
		(start 225.203258 -181.336188)
		(end 225.203258 -179.444142)
		(stroke
			(width 0.2)
			(type default)
		)
		(layer "In1.Cu")
	)
	(gr_line
		(start 225.203258 -179.444142)
		(end 225.203004 -179.443888)
		(stroke
			(width 0.2)
			(type default)
		)
		(layer "In1.Cu")
	)
	(gr_line
		(start 225.203258 -178.936142)
		(end 225.203258 -177.044096)
		(stroke
			(width 0.2)
			(type default)
		)
		(layer "In1.Cu")
	)
	(gr_line
		(start 225.203258 -177.044096)
		(end 225.203004 -177.043842)
		(stroke
			(width 0.2)
			(type default)
		)
		(layer "In1.Cu")
	)
	(gr_line
		(start 225.203258 -176.536096)
		(end 225.203258 -174.64405)
		(stroke
			(width 0.2)
			(type default)
		)
		(layer "In1.Cu")
	)
	(gr_line
		(start 225.203258 -174.64405)
		(end 225.203004 -174.643796)
		(stroke
			(width 0.2)
			(type default)
		)
		(layer "In1.Cu")
	)
	(gr_line
		(start 225.203258 -174.13605)
		(end 225.203258 -172.244004)
		(stroke
			(width 0.2)
			(type default)
		)
		(layer "In1.Cu")
	)
	(gr_line
		(start 225.203258 -172.244004)
		(end 225.203004 -172.24375)
		(stroke
			(width 0.2)
			(type default)
		)
		(layer "In1.Cu")
	)
	(gr_line
		(start 225.203258 -171.736004)
		(end 225.203258 -169.844212)
		(stroke
			(width 0.2)
			(type default)
		)
		(layer "In1.Cu")
	)
	(gr_line
		(start 225.203258 -169.844212)
		(end 225.203004 -169.843958)
		(stroke
			(width 0.2)
			(type default)
		)
		(layer "In1.Cu")
	)
	(gr_line
		(start 225.203258 -161.335974)
		(end 225.203258 -159.444182)
		(stroke
			(width 0.2)
			(type default)
		)
		(layer "In1.Cu")
	)
	(gr_line
		(start 225.203258 -159.444182)
		(end 225.203004 -159.443928)
		(stroke
			(width 0.2)
			(type default)
		)
		(layer "In1.Cu")
	)
	(gr_line
		(start 225.203258 -158.936182)
		(end 225.203258 -157.044136)
		(stroke
			(width 0.2)
			(type default)
		)
		(layer "In1.Cu")
	)
	(gr_line
		(start 225.203258 -157.044136)
		(end 225.203004 -157.043882)
		(stroke
			(width 0.2)
			(type default)
		)
		(layer "In1.Cu")
	)
	(gr_line
		(start 225.203258 -156.536136)
		(end 225.203258 -154.64409)
		(stroke
			(width 0.2)
			(type default)
		)
		(layer "In1.Cu")
	)
	(gr_line
		(start 225.203258 -154.64409)
		(end 225.203004 -154.643836)
		(stroke
			(width 0.2)
			(type default)
		)
		(layer "In1.Cu")
	)
	(gr_line
		(start 225.203258 -80.735932)
		(end 225.203258 -78.84414)
		(stroke
			(width 0.2)
			(type default)
		)
		(layer "In1.Cu")
	)
	(gr_line
		(start 225.203258 -78.84414)
		(end 225.203004 -78.843886)
		(stroke
			(width 0.2)
			(type default)
		)
		(layer "In1.Cu")
	)
	(gr_line
		(start 225.203258 -78.33614)
		(end 225.203258 -76.444094)
		(stroke
			(width 0.2)
			(type default)
		)
		(layer "In1.Cu")
	)
	(gr_line
		(start 225.203258 -76.444094)
		(end 225.203004 -76.44384)
		(stroke
			(width 0.2)
			(type default)
		)
		(layer "In1.Cu")
	)
	(gr_line
		(start 225.203258 -75.936094)
		(end 225.203258 -74.044048)
		(stroke
			(width 0.2)
			(type default)
		)
		(layer "In1.Cu")
	)
	(gr_line
		(start 225.203258 -74.044048)
		(end 225.203004 -74.043794)
		(stroke
			(width 0.2)
			(type default)
		)
		(layer "In1.Cu")
	)
	(gr_line
		(start 225.203258 -73.536048)
		(end 225.203258 -71.644002)
		(stroke
			(width 0.2)
			(type default)
		)
		(layer "In1.Cu")
	)
	(gr_line
		(start 225.203258 -71.644002)
		(end 225.203004 -71.643748)
		(stroke
			(width 0.2)
			(type default)
		)
		(layer "In1.Cu")
	)
	(gr_line
		(start 225.203258 -71.136002)
		(end 225.203258 -69.243956)
		(stroke
			(width 0.2)
			(type default)
		)
		(layer "In1.Cu")
	)
	(gr_line
		(start 225.203258 -69.243956)
		(end 225.203004 -69.243702)
		(stroke
			(width 0.2)
			(type default)
		)
		(layer "In1.Cu")
	)
	(gr_line
		(start 225.203258 -68.735956)
		(end 225.203258 -66.844164)
		(stroke
			(width 0.2)
			(type default)
		)
		(layer "In1.Cu")
	)
	(gr_line
		(start 225.203258 -66.844164)
		(end 225.203004 -66.84391)
		(stroke
			(width 0.2)
			(type default)
		)
		(layer "In1.Cu")
	)
	(gr_line
		(start 225.203258 -58.335926)
		(end 225.203258 -56.444134)
		(stroke
			(width 0.2)
			(type default)
		)
		(layer "In1.Cu")
	)
	(gr_line
		(start 225.203258 -56.444134)
		(end 225.203004 -56.44388)
		(stroke
			(width 0.2)
			(type default)
		)
		(layer "In1.Cu")
	)
	(gr_line
		(start 225.203258 -55.936134)
		(end 225.203258 -54.044088)
		(stroke
			(width 0.2)
			(type default)
		)
		(layer "In1.Cu")
	)
	(gr_line
		(start 225.203258 -54.044088)
		(end 225.203004 -54.043834)
		(stroke
			(width 0.2)
			(type default)
		)
		(layer "In1.Cu")
	)
	(gr_line
		(start 225.203258 -53.536088)
		(end 225.203258 -51.644042)
		(stroke
			(width 0.2)
			(type default)
		)
		(layer "In1.Cu")
	)
	(gr_line
		(start 225.203258 -51.644042)
		(end 225.203004 -51.643788)
		(stroke
			(width 0.2)
			(type default)
		)
		(layer "In1.Cu")
	)
	(gr_line
		(start 226.386644 -473.936314)
		(end 228.393244 -473.936314)
		(stroke
			(width 0.2)
			(type default)
		)
		(layer "In1.Cu")
	)
	(gr_line
		(start 226.386644 -472.044014)
		(end 226.386644 -473.936314)
		(stroke
			(width 0.2)
			(type default)
		)
		(layer "In1.Cu")
	)
	(gr_line
		(start 226.386644 -370.936266)
		(end 228.393244 -370.936266)
		(stroke
			(width 0.2)
			(type default)
		)
		(layer "In1.Cu")
	)
	(gr_line
		(start 226.386644 -369.043966)
		(end 226.386644 -370.936266)
		(stroke
			(width 0.2)
			(type default)
		)
		(layer "In1.Cu")
	)
	(gr_line
		(start 226.386644 -267.936218)
		(end 228.393244 -267.936218)
		(stroke
			(width 0.2)
			(type default)
		)
		(layer "In1.Cu")
	)
	(gr_line
		(start 226.386644 -266.043918)
		(end 226.386644 -267.936218)
		(stroke
			(width 0.2)
			(type default)
		)
		(layer "In1.Cu")
	)
	(gr_line
		(start 226.386644 -164.93617)
		(end 228.393244 -164.93617)
		(stroke
			(width 0.2)
			(type default)
		)
		(layer "In1.Cu")
	)
	(gr_line
		(start 226.386644 -163.04387)
		(end 226.386644 -164.93617)
		(stroke
			(width 0.2)
			(type default)
		)
		(layer "In1.Cu")
	)
	(gr_line
		(start 226.386644 -61.935868)
		(end 226.386898 -61.936122)
		(stroke
			(width 0.2)
			(type default)
		)
		(layer "In1.Cu")
	)
	(gr_line
		(start 226.386644 -60.043822)
		(end 226.386644 -61.935868)
		(stroke
			(width 0.2)
			(type default)
		)
		(layer "In1.Cu")
	)
	(gr_line
		(start 226.386898 -61.936122)
		(end 228.393244 -61.936122)
		(stroke
			(width 0.2)
			(type default)
		)
		(layer "In1.Cu")
	)
	(gr_line
		(start 228.39299 -472.044014)
		(end 226.386644 -472.044014)
		(stroke
			(width 0.2)
			(type default)
		)
		(layer "In1.Cu")
	)
	(gr_line
		(start 228.39299 -369.043966)
		(end 226.386644 -369.043966)
		(stroke
			(width 0.2)
			(type default)
		)
		(layer "In1.Cu")
	)
	(gr_line
		(start 228.39299 -266.043918)
		(end 226.386644 -266.043918)
		(stroke
			(width 0.2)
			(type default)
		)
		(layer "In1.Cu")
	)
	(gr_line
		(start 228.39299 -163.04387)
		(end 226.386644 -163.04387)
		(stroke
			(width 0.2)
			(type default)
		)
		(layer "In1.Cu")
	)
	(gr_line
		(start 228.393244 -473.936314)
		(end 228.393244 -472.044268)
		(stroke
			(width 0.2)
			(type default)
		)
		(layer "In1.Cu")
	)
	(gr_line
		(start 228.393244 -472.044268)
		(end 228.39299 -472.044014)
		(stroke
			(width 0.2)
			(type default)
		)
		(layer "In1.Cu")
	)
	(gr_line
		(start 228.393244 -370.936266)
		(end 228.393244 -369.04422)
		(stroke
			(width 0.2)
			(type default)
		)
		(layer "In1.Cu")
	)
	(gr_line
		(start 228.393244 -369.04422)
		(end 228.39299 -369.043966)
		(stroke
			(width 0.2)
			(type default)
		)
		(layer "In1.Cu")
	)
	(gr_line
		(start 228.393244 -267.936218)
		(end 228.393244 -266.044172)
		(stroke
			(width 0.2)
			(type default)
		)
		(layer "In1.Cu")
	)
	(gr_line
		(start 228.393244 -266.044172)
		(end 228.39299 -266.043918)
		(stroke
			(width 0.2)
			(type default)
		)
		(layer "In1.Cu")
	)
	(gr_line
		(start 228.393244 -164.93617)
		(end 228.393244 -163.044124)
		(stroke
			(width 0.2)
			(type default)
		)
		(layer "In1.Cu")
	)
	(gr_line
		(start 228.393244 -163.044124)
		(end 228.39299 -163.04387)
		(stroke
			(width 0.2)
			(type default)
		)
		(layer "In1.Cu")
	)
	(gr_line
		(start 228.393244 -61.936122)
		(end 228.393244 -60.043822)
		(stroke
			(width 0.2)
			(type default)
		)
		(layer "In1.Cu")
	)
	(gr_line
		(start 228.393244 -60.043822)
		(end 226.386644 -60.043822)
		(stroke
			(width 0.2)
			(type default)
		)
		(layer "In1.Cu")
	)
	(gr_line
		(start 229.907084 -472.300808)
		(end 230.71963 -472.300808)
		(stroke
			(width 0.2)
			(type default)
		)
		(layer "In1.Cu")
	)
	(gr_arc
		(start 229.907084 -471.279728)
		(mid 229.396544 -471.790268)
		(end 229.907084 -472.300808)
		(stroke
			(width 0.2)
			(type default)
		)
		(layer "In1.Cu")
	)
	(gr_line
		(start 229.907084 -369.30076)
		(end 230.71963 -369.30076)
		(stroke
			(width 0.2)
			(type default)
		)
		(layer "In1.Cu")
	)
	(gr_arc
		(start 229.907084 -368.27968)
		(mid 229.396544 -368.79022)
		(end 229.907084 -369.30076)
		(stroke
			(width 0.2)
			(type default)
		)
		(layer "In1.Cu")
	)
	(gr_line
		(start 229.907084 -266.300712)
		(end 230.71963 -266.300712)
		(stroke
			(width 0.2)
			(type default)
		)
		(layer "In1.Cu")
	)
	(gr_arc
		(start 229.907084 -265.279632)
		(mid 229.396544 -265.790172)
		(end 229.907084 -266.300712)
		(stroke
			(width 0.2)
			(type default)
		)
		(layer "In1.Cu")
	)
	(gr_line
		(start 229.907084 -163.300664)
		(end 230.71963 -163.300664)
		(stroke
			(width 0.2)
			(type default)
		)
		(layer "In1.Cu")
	)
	(gr_arc
		(start 229.907084 -162.279584)
		(mid 229.396544 -162.790124)
		(end 229.907084 -163.300664)
		(stroke
			(width 0.2)
			(type default)
		)
		(layer "In1.Cu")
	)
	(gr_line
		(start 229.907084 -60.300616)
		(end 230.71963 -60.300616)
		(stroke
			(width 0.2)
			(type default)
		)
		(layer "In1.Cu")
	)
	(gr_arc
		(start 229.907084 -59.279536)
		(mid 229.396544 -59.790076)
		(end 229.907084 -60.300616)
		(stroke
			(width 0.2)
			(type default)
		)
		(layer "In1.Cu")
	)
	(gr_arc
		(start 230.71963 -472.300808)
		(mid 231.230424 -471.790395)
		(end 230.719884 -471.279728)
		(stroke
			(width 0.2)
			(type default)
		)
		(layer "In1.Cu")
	)
	(gr_arc
		(start 230.71963 -369.30076)
		(mid 231.230424 -368.790347)
		(end 230.719884 -368.27968)
		(stroke
			(width 0.2)
			(type default)
		)
		(layer "In1.Cu")
	)
	(gr_arc
		(start 230.71963 -266.300712)
		(mid 231.230424 -265.790299)
		(end 230.719884 -265.279632)
		(stroke
			(width 0.2)
			(type default)
		)
		(layer "In1.Cu")
	)
	(gr_arc
		(start 230.71963 -163.300664)
		(mid 231.230424 -162.790251)
		(end 230.719884 -162.279584)
		(stroke
			(width 0.2)
			(type default)
		)
		(layer "In1.Cu")
	)
	(gr_arc
		(start 230.71963 -60.300616)
		(mid 231.230424 -59.790203)
		(end 230.719884 -59.279536)
		(stroke
			(width 0.2)
			(type default)
		)
		(layer "In1.Cu")
	)
	(gr_line
		(start 230.719884 -471.279728)
		(end 229.907084 -471.279728)
		(stroke
			(width 0.2)
			(type default)
		)
		(layer "In1.Cu")
	)
	(gr_line
		(start 230.719884 -368.27968)
		(end 229.907084 -368.27968)
		(stroke
			(width 0.2)
			(type default)
		)
		(layer "In1.Cu")
	)
	(gr_line
		(start 230.719884 -265.279632)
		(end 229.907084 -265.279632)
		(stroke
			(width 0.2)
			(type default)
		)
		(layer "In1.Cu")
	)
	(gr_line
		(start 230.719884 -162.279584)
		(end 229.907084 -162.279584)
		(stroke
			(width 0.2)
			(type default)
		)
		(layer "In1.Cu")
	)
	(gr_line
		(start 230.719884 -59.279536)
		(end 229.907084 -59.279536)
		(stroke
			(width 0.2)
			(type default)
		)
		(layer "In1.Cu")
	)
	(gr_arc
		(start 232.876344 -473.391992)
		(mid 233.386757 -473.902786)
		(end 233.897424 -473.392246)
		(stroke
			(width 0.2)
			(type default)
		)
		(layer "In1.Cu")
	)
	(gr_line
		(start 232.876344 -472.579446)
		(end 232.876344 -473.391992)
		(stroke
			(width 0.2)
			(type default)
		)
		(layer "In1.Cu")
	)
	(gr_arc
		(start 232.876344 -370.391944)
		(mid 233.386757 -370.902738)
		(end 233.897424 -370.392198)
		(stroke
			(width 0.2)
			(type default)
		)
		(layer "In1.Cu")
	)
	(gr_line
		(start 232.876344 -369.579398)
		(end 232.876344 -370.391944)
		(stroke
			(width 0.2)
			(type default)
		)
		(layer "In1.Cu")
	)
	(gr_arc
		(start 232.876344 -267.391896)
		(mid 233.386757 -267.90269)
		(end 233.897424 -267.39215)
		(stroke
			(width 0.2)
			(type default)
		)
		(layer "In1.Cu")
	)
	(gr_line
		(start 232.876344 -266.57935)
		(end 232.876344 -267.391896)
		(stroke
			(width 0.2)
			(type default)
		)
		(layer "In1.Cu")
	)
	(gr_arc
		(start 232.876344 -164.391848)
		(mid 233.386757 -164.902642)
		(end 233.897424 -164.392102)
		(stroke
			(width 0.2)
			(type default)
		)
		(layer "In1.Cu")
	)
	(gr_line
		(start 232.876344 -163.579302)
		(end 232.876344 -164.391848)
		(stroke
			(width 0.2)
			(type default)
		)
		(layer "In1.Cu")
	)
	(gr_arc
		(start 232.876344 -61.3918)
		(mid 233.386757 -61.902594)
		(end 233.897424 -61.392054)
		(stroke
			(width 0.2)
			(type default)
		)
		(layer "In1.Cu")
	)
	(gr_line
		(start 232.876344 -60.579254)
		(end 232.876344 -61.3918)
		(stroke
			(width 0.2)
			(type default)
		)
		(layer "In1.Cu")
	)
	(gr_line
		(start 233.897424 -473.392246)
		(end 233.897424 -472.579446)
		(stroke
			(width 0.2)
			(type default)
		)
		(layer "In1.Cu")
	)
	(gr_arc
		(start 233.897424 -472.579446)
		(mid 233.386884 -472.068906)
		(end 232.876344 -472.579446)
		(stroke
			(width 0.2)
			(type default)
		)
		(layer "In1.Cu")
	)
	(gr_line
		(start 233.897424 -370.392198)
		(end 233.897424 -369.579398)
		(stroke
			(width 0.2)
			(type default)
		)
		(layer "In1.Cu")
	)
	(gr_arc
		(start 233.897424 -369.579398)
		(mid 233.386884 -369.068858)
		(end 232.876344 -369.579398)
		(stroke
			(width 0.2)
			(type default)
		)
		(layer "In1.Cu")
	)
	(gr_line
		(start 233.897424 -267.39215)
		(end 233.897424 -266.57935)
		(stroke
			(width 0.2)
			(type default)
		)
		(layer "In1.Cu")
	)
	(gr_arc
		(start 233.897424 -266.57935)
		(mid 233.386884 -266.06881)
		(end 232.876344 -266.57935)
		(stroke
			(width 0.2)
			(type default)
		)
		(layer "In1.Cu")
	)
	(gr_line
		(start 233.897424 -164.392102)
		(end 233.897424 -163.579302)
		(stroke
			(width 0.2)
			(type default)
		)
		(layer "In1.Cu")
	)
	(gr_arc
		(start 233.897424 -163.579302)
		(mid 233.386884 -163.068762)
		(end 232.876344 -163.579302)
		(stroke
			(width 0.2)
			(type default)
		)
		(layer "In1.Cu")
	)
	(gr_line
		(start 233.897424 -61.392054)
		(end 233.897424 -60.579254)
		(stroke
			(width 0.2)
			(type default)
		)
		(layer "In1.Cu")
	)
	(gr_arc
		(start 233.897424 -60.579254)
		(mid 233.386884 -60.068714)
		(end 232.876344 -60.579254)
		(stroke
			(width 0.2)
			(type default)
		)
		(layer "In1.Cu")
	)
	(gr_line
		(start 252.394974 -410.485082)
		(end 258.899914 -410.485082)
		(stroke
			(width 1.524)
			(type default)
		)
		(layer "In1.Cu")
	)
	(gr_arc
		(start 252.394974 -409.41498)
		(mid 251.859796 -409.950158)
		(end 252.394974 -410.485082)
		(stroke
			(width 1.524)
			(type default)
		)
		(layer "In1.Cu")
	)
	(gr_line
		(start 258.899914 -410.485082)
		(end 259.899912 -411.48508)
		(stroke
			(width 1.524)
			(type default)
		)
		(layer "In1.Cu")
	)
	(gr_line
		(start 258.899914 -409.41498)
		(end 252.394974 -409.41498)
		(stroke
			(width 1.524)
			(type default)
		)
		(layer "In1.Cu")
	)
	(gr_arc
		(start 259.899912 -425.69003)
		(mid 260.307091 -426.672919)
		(end 261.290054 -427.079918)
		(stroke
			(width 1.524)
			(type default)
		)
		(layer "In1.Cu")
	)
	(gr_line
		(start 259.899912 -411.48508)
		(end 259.899912 -425.69003)
		(stroke
			(width 1.524)
			(type default)
		)
		(layer "In1.Cu")
	)
	(gr_line
		(start 259.899912 -408.414982)
		(end 258.899914 -409.41498)
		(stroke
			(width 1.524)
			(type default)
		)
		(layer "In1.Cu")
	)
	(gr_line
		(start 259.899912 -364.309914)
		(end 259.899912 -408.414982)
		(stroke
			(width 1.524)
			(type default)
		)
		(layer "In1.Cu")
	)
	(gr_line
		(start 261.290054 -427.079918)
		(end 262.50011 -427.079918)
		(stroke
			(width 1.524)
			(type default)
		)
		(layer "In1.Cu")
	)
	(gr_arc
		(start 261.290054 -362.920026)
		(mid 260.307165 -363.327099)
		(end 259.899912 -364.309914)
		(stroke
			(width 1.524)
			(type default)
		)
		(layer "In1.Cu")
	)
	(gr_line
		(start 262.50011 -506.000004)
		(end 0.999998 -506.000004)
		(stroke
			(width 1.524)
			(type default)
		)
		(layer "In1.Cu")
	)
	(gr_arc
		(start 262.50011 -506.000004)
		(mid 263.207211 -505.707108)
		(end 263.500108 -505.000006)
		(stroke
			(width 1.524)
			(type default)
		)
		(layer "In1.Cu")
	)
	(gr_line
		(start 262.50011 -427.079918)
		(end 263.500108 -428.079916)
		(stroke
			(width 1.524)
			(type default)
		)
		(layer "In1.Cu")
	)
	(gr_line
		(start 262.50011 -362.920026)
		(end 261.290054 -362.920026)
		(stroke
			(width 1.524)
			(type default)
		)
		(layer "In1.Cu")
	)
	(gr_line
		(start 263.500108 -428.079916)
		(end 263.500108 -505.000006)
		(stroke
			(width 1.524)
			(type default)
		)
		(layer "In1.Cu")
	)
	(gr_line
		(start 263.500108 -361.920028)
		(end 262.50011 -362.920026)
		(stroke
			(width 1.524)
			(type default)
		)
		(layer "In1.Cu")
	)
	(gr_arc
		(start 263.500108 -0.999998)
		(mid 263.207215 -0.29289)
		(end 262.50011 0)
		(stroke
			(width 1.524)
			(type default)
		)
		(layer "In1.Cu")
	)
	(gr_line
		(start 263.500108 -0.999998)
		(end 263.500108 -361.920028)
		(stroke
			(width 1.524)
			(type default)
		)
		(layer "In1.Cu")
	)
	(gr_line
		(start 5.08 -445.548004)
		(end 5.233162 -445.394842)
		(stroke
			(width 0.08255)
			(type default)
		)
		(layer "In2.Cu")
	)
	(gr_line
		(start 5.08 -444.735204)
		(end 5.233162 -444.888366)
		(stroke
			(width 0.08255)
			(type default)
		)
		(layer "In2.Cu")
	)
	(gr_line
		(start 5.08 -442.348112)
		(end 5.233162 -442.19495)
		(stroke
			(width 0.08255)
			(type default)
		)
		(layer "In2.Cu")
	)
	(gr_line
		(start 5.08 -441.535312)
		(end 5.233162 -441.688474)
		(stroke
			(width 0.08255)
			(type default)
		)
		(layer "In2.Cu")
	)
	(gr_line
		(start 5.08 -439.147966)
		(end 5.233162 -438.994804)
		(stroke
			(width 0.08255)
			(type default)
		)
		(layer "In2.Cu")
	)
	(gr_line
		(start 5.08 -438.335166)
		(end 5.233162 -438.488328)
		(stroke
			(width 0.08255)
			(type default)
		)
		(layer "In2.Cu")
	)
	(gr_line
		(start 5.08 -435.948074)
		(end 5.233162 -435.794912)
		(stroke
			(width 0.08255)
			(type default)
		)
		(layer "In2.Cu")
	)
	(gr_line
		(start 5.08 -435.135274)
		(end 5.233162 -435.288436)
		(stroke
			(width 0.08255)
			(type default)
		)
		(layer "In2.Cu")
	)
	(gr_line
		(start 5.08 -430.347882)
		(end 5.233162 -430.19472)
		(stroke
			(width 0.08255)
			(type default)
		)
		(layer "In2.Cu")
	)
	(gr_line
		(start 5.08 -429.535082)
		(end 5.233162 -429.688244)
		(stroke
			(width 0.08255)
			(type default)
		)
		(layer "In2.Cu")
	)
	(gr_line
		(start 5.08 -427.14799)
		(end 5.233162 -426.994828)
		(stroke
			(width 0.08255)
			(type default)
		)
		(layer "In2.Cu")
	)
	(gr_line
		(start 5.08 -426.33519)
		(end 5.233162 -426.488352)
		(stroke
			(width 0.08255)
			(type default)
		)
		(layer "In2.Cu")
	)
	(gr_line
		(start 5.08 -423.948098)
		(end 5.233162 -423.794936)
		(stroke
			(width 0.08255)
			(type default)
		)
		(layer "In2.Cu")
	)
	(gr_line
		(start 5.08 -423.135298)
		(end 5.233162 -423.28846)
		(stroke
			(width 0.08255)
			(type default)
		)
		(layer "In2.Cu")
	)
	(gr_line
		(start 5.08 -417.54806)
		(end 5.233162 -417.394898)
		(stroke
			(width 0.08255)
			(type default)
		)
		(layer "In2.Cu")
	)
	(gr_line
		(start 5.08 -416.73526)
		(end 5.233162 -416.888422)
		(stroke
			(width 0.08255)
			(type default)
		)
		(layer "In2.Cu")
	)
	(gr_line
		(start 5.08 -414.347914)
		(end 5.233162 -414.194752)
		(stroke
			(width 0.08255)
			(type default)
		)
		(layer "In2.Cu")
	)
	(gr_line
		(start 5.08 -413.535114)
		(end 5.233162 -413.688276)
		(stroke
			(width 0.08255)
			(type default)
		)
		(layer "In2.Cu")
	)
	(gr_line
		(start 5.08 -411.148022)
		(end 5.233162 -410.99486)
		(stroke
			(width 0.08255)
			(type default)
		)
		(layer "In2.Cu")
	)
	(gr_line
		(start 5.08 -410.335222)
		(end 5.233162 -410.488384)
		(stroke
			(width 0.08255)
			(type default)
		)
		(layer "In2.Cu")
	)
	(gr_line
		(start 5.08 -407.947876)
		(end 5.233162 -407.794714)
		(stroke
			(width 0.08255)
			(type default)
		)
		(layer "In2.Cu")
	)
	(gr_line
		(start 5.08 -407.135076)
		(end 5.233162 -407.288238)
		(stroke
			(width 0.08255)
			(type default)
		)
		(layer "In2.Cu")
	)
	(gr_line
		(start 5.08 -404.747984)
		(end 5.233162 -404.594822)
		(stroke
			(width 0.08255)
			(type default)
		)
		(layer "In2.Cu")
	)
	(gr_line
		(start 5.08 -403.935184)
		(end 5.233162 -404.088346)
		(stroke
			(width 0.08255)
			(type default)
		)
		(layer "In2.Cu")
	)
	(gr_line
		(start 5.08 -399.148046)
		(end 5.233162 -398.994884)
		(stroke
			(width 0.08255)
			(type default)
		)
		(layer "In2.Cu")
	)
	(gr_line
		(start 5.08 -398.335246)
		(end 5.233162 -398.488408)
		(stroke
			(width 0.08255)
			(type default)
		)
		(layer "In2.Cu")
	)
	(gr_line
		(start 5.08 -395.9479)
		(end 5.233162 -395.794738)
		(stroke
			(width 0.08255)
			(type default)
		)
		(layer "In2.Cu")
	)
	(gr_line
		(start 5.08 -395.1351)
		(end 5.233162 -395.288262)
		(stroke
			(width 0.08255)
			(type default)
		)
		(layer "In2.Cu")
	)
	(gr_line
		(start 5.08 -392.748008)
		(end 5.233162 -392.594846)
		(stroke
			(width 0.08255)
			(type default)
		)
		(layer "In2.Cu")
	)
	(gr_line
		(start 5.08 -391.935208)
		(end 5.233162 -392.08837)
		(stroke
			(width 0.08255)
			(type default)
		)
		(layer "In2.Cu")
	)
	(gr_line
		(start 5.08 -389.548116)
		(end 5.233162 -389.394954)
		(stroke
			(width 0.08255)
			(type default)
		)
		(layer "In2.Cu")
	)
	(gr_line
		(start 5.08 -388.735316)
		(end 5.233162 -388.888478)
		(stroke
			(width 0.08255)
			(type default)
		)
		(layer "In2.Cu")
	)
	(gr_line
		(start 5.08 -358.74833)
		(end 5.233162 -358.595168)
		(stroke
			(width 0.08255)
			(type default)
		)
		(layer "In2.Cu")
	)
	(gr_line
		(start 5.08 -357.93553)
		(end 5.233162 -358.088692)
		(stroke
			(width 0.08255)
			(type default)
		)
		(layer "In2.Cu")
	)
	(gr_line
		(start 5.08 -355.548184)
		(end 5.233162 -355.395022)
		(stroke
			(width 0.08255)
			(type default)
		)
		(layer "In2.Cu")
	)
	(gr_line
		(start 5.08 -354.735384)
		(end 5.233162 -354.888546)
		(stroke
			(width 0.08255)
			(type default)
		)
		(layer "In2.Cu")
	)
	(gr_line
		(start 5.08 -352.348292)
		(end 5.233162 -352.19513)
		(stroke
			(width 0.08255)
			(type default)
		)
		(layer "In2.Cu")
	)
	(gr_line
		(start 5.08 -351.535492)
		(end 5.233162 -351.688654)
		(stroke
			(width 0.08255)
			(type default)
		)
		(layer "In2.Cu")
	)
	(gr_line
		(start 5.08 -349.148146)
		(end 5.233162 -348.994984)
		(stroke
			(width 0.08255)
			(type default)
		)
		(layer "In2.Cu")
	)
	(gr_line
		(start 5.08 -348.335346)
		(end 5.233162 -348.488508)
		(stroke
			(width 0.08255)
			(type default)
		)
		(layer "In2.Cu")
	)
	(gr_line
		(start 5.08 -345.948254)
		(end 5.233162 -345.795092)
		(stroke
			(width 0.08255)
			(type default)
		)
		(layer "In2.Cu")
	)
	(gr_line
		(start 5.08 -345.135454)
		(end 5.233162 -345.288616)
		(stroke
			(width 0.08255)
			(type default)
		)
		(layer "In2.Cu")
	)
	(gr_line
		(start 5.08 -342.748108)
		(end 5.233162 -342.594946)
		(stroke
			(width 0.08255)
			(type default)
		)
		(layer "In2.Cu")
	)
	(gr_line
		(start 5.08 -341.935308)
		(end 5.233162 -342.08847)
		(stroke
			(width 0.08255)
			(type default)
		)
		(layer "In2.Cu")
	)
	(gr_line
		(start 5.08 -339.548216)
		(end 5.233162 -339.395054)
		(stroke
			(width 0.08255)
			(type default)
		)
		(layer "In2.Cu")
	)
	(gr_line
		(start 5.08 -338.735416)
		(end 5.233162 -338.888578)
		(stroke
			(width 0.08255)
			(type default)
		)
		(layer "In2.Cu")
	)
	(gr_line
		(start 5.08 -336.348324)
		(end 5.233162 -336.195162)
		(stroke
			(width 0.08255)
			(type default)
		)
		(layer "In2.Cu")
	)
	(gr_line
		(start 5.08 -335.535524)
		(end 5.233162 -335.688686)
		(stroke
			(width 0.08255)
			(type default)
		)
		(layer "In2.Cu")
	)
	(gr_line
		(start 5.08 -330.748132)
		(end 5.233162 -330.59497)
		(stroke
			(width 0.08255)
			(type default)
		)
		(layer "In2.Cu")
	)
	(gr_line
		(start 5.08 -329.935332)
		(end 5.233162 -330.088494)
		(stroke
			(width 0.08255)
			(type default)
		)
		(layer "In2.Cu")
	)
	(gr_line
		(start 5.08 -327.54824)
		(end 5.233162 -327.395078)
		(stroke
			(width 0.08255)
			(type default)
		)
		(layer "In2.Cu")
	)
	(gr_line
		(start 5.08 -326.73544)
		(end 5.233162 -326.888602)
		(stroke
			(width 0.08255)
			(type default)
		)
		(layer "In2.Cu")
	)
	(gr_line
		(start 5.08 -324.348094)
		(end 5.233162 -324.194932)
		(stroke
			(width 0.08255)
			(type default)
		)
		(layer "In2.Cu")
	)
	(gr_line
		(start 5.08 -323.535294)
		(end 5.233162 -323.688456)
		(stroke
			(width 0.08255)
			(type default)
		)
		(layer "In2.Cu")
	)
	(gr_line
		(start 5.08 -321.148202)
		(end 5.233162 -320.99504)
		(stroke
			(width 0.08255)
			(type default)
		)
		(layer "In2.Cu")
	)
	(gr_line
		(start 5.08 -320.335402)
		(end 5.233162 -320.488564)
		(stroke
			(width 0.08255)
			(type default)
		)
		(layer "In2.Cu")
	)
	(gr_line
		(start 5.08 -317.94831)
		(end 5.233162 -317.795148)
		(stroke
			(width 0.08255)
			(type default)
		)
		(layer "In2.Cu")
	)
	(gr_line
		(start 5.08 -317.13551)
		(end 5.233162 -317.288672)
		(stroke
			(width 0.08255)
			(type default)
		)
		(layer "In2.Cu")
	)
	(gr_line
		(start 5.08 -309.948326)
		(end 5.233162 -309.795164)
		(stroke
			(width 0.08255)
			(type default)
		)
		(layer "In2.Cu")
	)
	(gr_line
		(start 5.08 -309.135526)
		(end 5.233162 -309.288688)
		(stroke
			(width 0.08255)
			(type default)
		)
		(layer "In2.Cu")
	)
	(gr_line
		(start 5.08 -306.74818)
		(end 5.233162 -306.595018)
		(stroke
			(width 0.08255)
			(type default)
		)
		(layer "In2.Cu")
	)
	(gr_line
		(start 5.08 -305.93538)
		(end 5.233162 -306.088542)
		(stroke
			(width 0.08255)
			(type default)
		)
		(layer "In2.Cu")
	)
	(gr_line
		(start 5.08 -303.548288)
		(end 5.233162 -303.395126)
		(stroke
			(width 0.08255)
			(type default)
		)
		(layer "In2.Cu")
	)
	(gr_line
		(start 5.08 -302.735488)
		(end 5.233162 -302.88865)
		(stroke
			(width 0.08255)
			(type default)
		)
		(layer "In2.Cu")
	)
	(gr_line
		(start 5.08 -300.348142)
		(end 5.233162 -300.19498)
		(stroke
			(width 0.08255)
			(type default)
		)
		(layer "In2.Cu")
	)
	(gr_line
		(start 5.08 -299.535342)
		(end 5.233162 -299.688504)
		(stroke
			(width 0.08255)
			(type default)
		)
		(layer "In2.Cu")
	)
	(gr_line
		(start 5.08 -297.14825)
		(end 5.233162 -296.995088)
		(stroke
			(width 0.08255)
			(type default)
		)
		(layer "In2.Cu")
	)
	(gr_line
		(start 5.08 -296.33545)
		(end 5.233162 -296.488612)
		(stroke
			(width 0.08255)
			(type default)
		)
		(layer "In2.Cu")
	)
	(gr_line
		(start 5.08 -293.948104)
		(end 5.233162 -293.794942)
		(stroke
			(width 0.08255)
			(type default)
		)
		(layer "In2.Cu")
	)
	(gr_line
		(start 5.08 -293.135304)
		(end 5.233162 -293.288466)
		(stroke
			(width 0.08255)
			(type default)
		)
		(layer "In2.Cu")
	)
	(gr_line
		(start 5.08 -290.748212)
		(end 5.233162 -290.59505)
		(stroke
			(width 0.08255)
			(type default)
		)
		(layer "In2.Cu")
	)
	(gr_line
		(start 5.08 -289.935412)
		(end 5.233162 -290.088574)
		(stroke
			(width 0.08255)
			(type default)
		)
		(layer "In2.Cu")
	)
	(gr_line
		(start 5.08 -284.348174)
		(end 5.233162 -284.195012)
		(stroke
			(width 0.08255)
			(type default)
		)
		(layer "In2.Cu")
	)
	(gr_line
		(start 5.08 -283.535374)
		(end 5.233162 -283.688536)
		(stroke
			(width 0.08255)
			(type default)
		)
		(layer "In2.Cu")
	)
	(gr_line
		(start 5.08 -281.148282)
		(end 5.233162 -280.99512)
		(stroke
			(width 0.08255)
			(type default)
		)
		(layer "In2.Cu")
	)
	(gr_line
		(start 5.08 -280.335482)
		(end 5.233162 -280.488644)
		(stroke
			(width 0.08255)
			(type default)
		)
		(layer "In2.Cu")
	)
	(gr_line
		(start 5.08 -232.748328)
		(end 5.233162 -232.595166)
		(stroke
			(width 0.08255)
			(type default)
		)
		(layer "In2.Cu")
	)
	(gr_line
		(start 5.08 -231.935528)
		(end 5.233162 -232.08869)
		(stroke
			(width 0.08255)
			(type default)
		)
		(layer "In2.Cu")
	)
	(gr_line
		(start 5.08 -229.548182)
		(end 5.233162 -229.39502)
		(stroke
			(width 0.08255)
			(type default)
		)
		(layer "In2.Cu")
	)
	(gr_line
		(start 5.08 -228.735382)
		(end 5.233162 -228.888544)
		(stroke
			(width 0.08255)
			(type default)
		)
		(layer "In2.Cu")
	)
	(gr_line
		(start 5.08 -223.148144)
		(end 5.233162 -222.994982)
		(stroke
			(width 0.08255)
			(type default)
		)
		(layer "In2.Cu")
	)
	(gr_line
		(start 5.08 -222.335344)
		(end 5.233162 -222.488506)
		(stroke
			(width 0.08255)
			(type default)
		)
		(layer "In2.Cu")
	)
	(gr_line
		(start 5.08 -219.948252)
		(end 5.233162 -219.79509)
		(stroke
			(width 0.08255)
			(type default)
		)
		(layer "In2.Cu")
	)
	(gr_line
		(start 5.08 -219.135452)
		(end 5.233162 -219.288614)
		(stroke
			(width 0.08255)
			(type default)
		)
		(layer "In2.Cu")
	)
	(gr_line
		(start 5.08 -216.748106)
		(end 5.233162 -216.594944)
		(stroke
			(width 0.08255)
			(type default)
		)
		(layer "In2.Cu")
	)
	(gr_line
		(start 5.08 -215.935306)
		(end 5.233162 -216.088468)
		(stroke
			(width 0.08255)
			(type default)
		)
		(layer "In2.Cu")
	)
	(gr_line
		(start 5.08 -213.548214)
		(end 5.233162 -213.395052)
		(stroke
			(width 0.08255)
			(type default)
		)
		(layer "In2.Cu")
	)
	(gr_line
		(start 5.08 -212.735414)
		(end 5.233162 -212.888576)
		(stroke
			(width 0.08255)
			(type default)
		)
		(layer "In2.Cu")
	)
	(gr_line
		(start 5.08 -210.348322)
		(end 5.233162 -210.19516)
		(stroke
			(width 0.08255)
			(type default)
		)
		(layer "In2.Cu")
	)
	(gr_line
		(start 5.08 -209.535522)
		(end 5.233162 -209.688684)
		(stroke
			(width 0.08255)
			(type default)
		)
		(layer "In2.Cu")
	)
	(gr_line
		(start 5.08 -207.148176)
		(end 5.233162 -206.995014)
		(stroke
			(width 0.08255)
			(type default)
		)
		(layer "In2.Cu")
	)
	(gr_line
		(start 5.08 -206.335376)
		(end 5.233162 -206.488538)
		(stroke
			(width 0.08255)
			(type default)
		)
		(layer "In2.Cu")
	)
	(gr_line
		(start 5.08 -203.948284)
		(end 5.233162 -203.795122)
		(stroke
			(width 0.08255)
			(type default)
		)
		(layer "In2.Cu")
	)
	(gr_line
		(start 5.08 -203.135484)
		(end 5.233162 -203.288646)
		(stroke
			(width 0.08255)
			(type default)
		)
		(layer "In2.Cu")
	)
	(gr_line
		(start 5.08 -200.748138)
		(end 5.233162 -200.594976)
		(stroke
			(width 0.08255)
			(type default)
		)
		(layer "In2.Cu")
	)
	(gr_line
		(start 5.08 -199.935338)
		(end 5.233162 -200.0885)
		(stroke
			(width 0.08255)
			(type default)
		)
		(layer "In2.Cu")
	)
	(gr_line
		(start 5.08 -195.1482)
		(end 5.233162 -194.995038)
		(stroke
			(width 0.08255)
			(type default)
		)
		(layer "In2.Cu")
	)
	(gr_line
		(start 5.08 -194.3354)
		(end 5.233162 -194.488562)
		(stroke
			(width 0.08255)
			(type default)
		)
		(layer "In2.Cu")
	)
	(gr_line
		(start 5.08 -191.948308)
		(end 5.233162 -191.795146)
		(stroke
			(width 0.08255)
			(type default)
		)
		(layer "In2.Cu")
	)
	(gr_line
		(start 5.08 -191.135508)
		(end 5.233162 -191.28867)
		(stroke
			(width 0.08255)
			(type default)
		)
		(layer "In2.Cu")
	)
	(gr_line
		(start 5.08 -183.948324)
		(end 5.233162 -183.795162)
		(stroke
			(width 0.08255)
			(type default)
		)
		(layer "In2.Cu")
	)
	(gr_line
		(start 5.08 -183.135524)
		(end 5.233162 -183.288686)
		(stroke
			(width 0.08255)
			(type default)
		)
		(layer "In2.Cu")
	)
	(gr_line
		(start 5.08 -180.748178)
		(end 5.233162 -180.595016)
		(stroke
			(width 0.08255)
			(type default)
		)
		(layer "In2.Cu")
	)
	(gr_line
		(start 5.08 -179.935378)
		(end 5.233162 -180.08854)
		(stroke
			(width 0.08255)
			(type default)
		)
		(layer "In2.Cu")
	)
	(gr_line
		(start 5.08 -177.548286)
		(end 5.233162 -177.395124)
		(stroke
			(width 0.08255)
			(type default)
		)
		(layer "In2.Cu")
	)
	(gr_line
		(start 5.08 -176.735486)
		(end 5.233162 -176.888648)
		(stroke
			(width 0.08255)
			(type default)
		)
		(layer "In2.Cu")
	)
	(gr_line
		(start 5.08 -174.34814)
		(end 5.233162 -174.194978)
		(stroke
			(width 0.08255)
			(type default)
		)
		(layer "In2.Cu")
	)
	(gr_line
		(start 5.08 -173.53534)
		(end 5.233162 -173.688502)
		(stroke
			(width 0.08255)
			(type default)
		)
		(layer "In2.Cu")
	)
	(gr_line
		(start 5.08 -171.148248)
		(end 5.233162 -170.995086)
		(stroke
			(width 0.08255)
			(type default)
		)
		(layer "In2.Cu")
	)
	(gr_line
		(start 5.08 -170.335448)
		(end 5.233162 -170.48861)
		(stroke
			(width 0.08255)
			(type default)
		)
		(layer "In2.Cu")
	)
	(gr_line
		(start 5.08 -167.948102)
		(end 5.233162 -167.79494)
		(stroke
			(width 0.08255)
			(type default)
		)
		(layer "In2.Cu")
	)
	(gr_line
		(start 5.08 -167.135302)
		(end 5.233162 -167.288464)
		(stroke
			(width 0.08255)
			(type default)
		)
		(layer "In2.Cu")
	)
	(gr_line
		(start 5.08 -164.74821)
		(end 5.233162 -164.595048)
		(stroke
			(width 0.08255)
			(type default)
		)
		(layer "In2.Cu")
	)
	(gr_line
		(start 5.08 -163.93541)
		(end 5.233162 -164.088572)
		(stroke
			(width 0.08255)
			(type default)
		)
		(layer "In2.Cu")
	)
	(gr_line
		(start 5.08 -161.548318)
		(end 5.233162 -161.395156)
		(stroke
			(width 0.08255)
			(type default)
		)
		(layer "In2.Cu")
	)
	(gr_line
		(start 5.08 -160.735518)
		(end 5.233162 -160.88868)
		(stroke
			(width 0.08255)
			(type default)
		)
		(layer "In2.Cu")
	)
	(gr_line
		(start 5.08 -158.348172)
		(end 5.233162 -158.19501)
		(stroke
			(width 0.08255)
			(type default)
		)
		(layer "In2.Cu")
	)
	(gr_line
		(start 5.08 -157.535372)
		(end 5.233162 -157.688534)
		(stroke
			(width 0.08255)
			(type default)
		)
		(layer "In2.Cu")
	)
	(gr_line
		(start 5.08 -155.14828)
		(end 5.233162 -154.995118)
		(stroke
			(width 0.08255)
			(type default)
		)
		(layer "In2.Cu")
	)
	(gr_line
		(start 5.08 -154.33548)
		(end 5.233162 -154.488642)
		(stroke
			(width 0.08255)
			(type default)
		)
		(layer "In2.Cu")
	)
	(gr_line
		(start 6.472174 -104.557576)
		(end 6.47573 -104.578404)
		(stroke
			(width 0.08255)
			(type default)
		)
		(layer "In2.Cu")
	)
	(gr_line
		(start 6.472174 -104.557576)
		(end 6.47573 -104.537002)
		(stroke
			(width 0.08255)
			(type default)
		)
		(layer "In2.Cu")
	)
	(gr_line
		(start 6.47573 -104.57815)
		(end 6.47573 -104.578912)
		(stroke
			(width 0.08255)
			(type default)
		)
		(layer "In2.Cu")
	)
	(gr_line
		(start 7.000748 -417.108132)
		(end 7.036562 -417.114482)
		(stroke
			(width 0.08255)
			(type default)
		)
		(layer "In2.Cu")
	)
	(gr_line
		(start 7.036562 -417.114482)
		(end 7.066788 -417.135564)
		(stroke
			(width 0.08255)
			(type default)
		)
		(layer "In2.Cu")
	)
	(gr_line
		(start 7.224268 -194.919854)
		(end 7.281672 -194.879722)
		(stroke
			(width 0.08255)
			(type default)
		)
		(layer "In2.Cu")
	)
	(gr_line
		(start 7.224268 -191.719962)
		(end 7.281672 -191.67983)
		(stroke
			(width 0.08255)
			(type default)
		)
		(layer "In2.Cu")
	)
	(gr_line
		(start 7.392924 -157.962346)
		(end 7.428992 -157.955996)
		(stroke
			(width 0.08255)
			(type default)
		)
		(layer "In2.Cu")
	)
	(gr_line
		(start 7.428992 -157.955996)
		(end 7.459218 -157.934914)
		(stroke
			(width 0.08255)
			(type default)
		)
		(layer "In2.Cu")
	)
	(gr_line
		(start 7.44474 -330.38288)
		(end 7.480808 -330.37653)
		(stroke
			(width 0.08255)
			(type default)
		)
		(layer "In2.Cu")
	)
	(gr_line
		(start 7.480808 -330.37653)
		(end 7.511034 -330.355448)
		(stroke
			(width 0.08255)
			(type default)
		)
		(layer "In2.Cu")
	)
	(gr_line
		(start 7.538212 -389.196072)
		(end 7.57428 -389.202422)
		(stroke
			(width 0.08255)
			(type default)
		)
		(layer "In2.Cu")
	)
	(gr_line
		(start 7.57428 -389.202422)
		(end 7.604506 -389.223504)
		(stroke
			(width 0.08255)
			(type default)
		)
		(layer "In2.Cu")
	)
	(gr_line
		(start 7.601458 -176.87544)
		(end 7.75208 -176.660556)
		(stroke
			(width 0.08255)
			(type default)
		)
		(layer "In2.Cu")
	)
	(gr_line
		(start 7.61873 -206.830676)
		(end 7.654544 -206.824326)
		(stroke
			(width 0.08255)
			(type default)
		)
		(layer "In2.Cu")
	)
	(gr_line
		(start 7.654544 -206.824326)
		(end 7.68477 -206.803244)
		(stroke
			(width 0.08255)
			(type default)
		)
		(layer "In2.Cu")
	)
	(gr_line
		(start 7.66318 -299.896022)
		(end 7.701534 -299.889164)
		(stroke
			(width 0.08255)
			(type default)
		)
		(layer "In2.Cu")
	)
	(gr_line
		(start 7.701534 -299.889164)
		(end 7.733538 -299.866812)
		(stroke
			(width 0.08255)
			(type default)
		)
		(layer "In2.Cu")
	)
	(gr_line
		(start 7.701534 -177.221642)
		(end 8.477504 -177.084736)
		(stroke
			(width 0.08255)
			(type default)
		)
		(layer "In2.Cu")
	)
	(gr_line
		(start 7.74573 -210.008216)
		(end 7.781798 -210.001866)
		(stroke
			(width 0.08255)
			(type default)
		)
		(layer "In2.Cu")
	)
	(gr_line
		(start 7.750048 -213.207346)
		(end 7.786116 -213.200996)
		(stroke
			(width 0.08255)
			(type default)
		)
		(layer "In2.Cu")
	)
	(gr_line
		(start 7.75208 -176.660556)
		(end 8.23976 -176.57445)
		(stroke
			(width 0.08255)
			(type default)
		)
		(layer "In2.Cu")
	)
	(gr_line
		(start 7.761224 -303.21123)
		(end 7.799324 -303.204372)
		(stroke
			(width 0.08255)
			(type default)
		)
		(layer "In2.Cu")
	)
	(gr_line
		(start 7.764526 -445.07912)
		(end 7.800594 -445.08547)
		(stroke
			(width 0.08255)
			(type default)
		)
		(layer "In2.Cu")
	)
	(gr_line
		(start 7.768844 -441.87999)
		(end 7.804658 -441.88634)
		(stroke
			(width 0.08255)
			(type default)
		)
		(layer "In2.Cu")
	)
	(gr_line
		(start 7.781798 -210.001866)
		(end 7.812024 -209.980784)
		(stroke
			(width 0.08255)
			(type default)
		)
		(layer "In2.Cu")
	)
	(gr_line
		(start 7.786116 -213.200996)
		(end 7.816342 -213.179914)
		(stroke
			(width 0.08255)
			(type default)
		)
		(layer "In2.Cu")
	)
	(gr_line
		(start 7.799324 -303.204372)
		(end 7.830312 -303.182528)
		(stroke
			(width 0.08255)
			(type default)
		)
		(layer "In2.Cu")
	)
	(gr_line
		(start 7.800594 -445.08547)
		(end 7.83082 -445.106552)
		(stroke
			(width 0.08255)
			(type default)
		)
		(layer "In2.Cu")
	)
	(gr_line
		(start 7.804658 -441.88634)
		(end 7.834884 -441.907422)
		(stroke
			(width 0.08255)
			(type default)
		)
		(layer "In2.Cu")
	)
	(gr_line
		(start 7.854188 -358.295194)
		(end 7.890256 -358.301544)
		(stroke
			(width 0.08255)
			(type default)
		)
		(layer "In2.Cu")
	)
	(gr_line
		(start 7.874254 -348.69882)
		(end 7.910322 -348.70517)
		(stroke
			(width 0.08255)
			(type default)
		)
		(layer "In2.Cu")
	)
	(gr_line
		(start 7.880096 -392.299444)
		(end 7.916164 -392.305794)
		(stroke
			(width 0.08255)
			(type default)
		)
		(layer "In2.Cu")
	)
	(gr_line
		(start 7.884922 -216.022428)
		(end 8.659622 -215.885776)
		(stroke
			(width 0.08255)
			(type default)
		)
		(layer "In2.Cu")
	)
	(gr_line
		(start 7.890256 -358.301544)
		(end 7.920482 -358.322626)
		(stroke
			(width 0.08255)
			(type default)
		)
		(layer "In2.Cu")
	)
	(gr_line
		(start 7.896098 -438.702196)
		(end 7.932166 -438.708546)
		(stroke
			(width 0.08255)
			(type default)
		)
		(layer "In2.Cu")
	)
	(gr_line
		(start 7.900416 -435.503066)
		(end 7.936484 -435.509416)
		(stroke
			(width 0.08255)
			(type default)
		)
		(layer "In2.Cu")
	)
	(gr_line
		(start 7.908036 -216.382092)
		(end 8.12292 -216.53246)
		(stroke
			(width 0.08255)
			(type default)
		)
		(layer "In2.Cu")
	)
	(gr_line
		(start 7.910322 -348.70517)
		(end 7.940548 -348.726252)
		(stroke
			(width 0.08255)
			(type default)
		)
		(layer "In2.Cu")
	)
	(gr_line
		(start 7.913878 -345.51112)
		(end 7.949946 -345.51747)
		(stroke
			(width 0.08255)
			(type default)
		)
		(layer "In2.Cu")
	)
	(gr_line
		(start 7.916164 -392.305794)
		(end 7.94639 -392.326876)
		(stroke
			(width 0.08255)
			(type default)
		)
		(layer "In2.Cu")
	)
	(gr_line
		(start 7.932166 -438.708546)
		(end 7.962392 -438.729628)
		(stroke
			(width 0.08255)
			(type default)
		)
		(layer "In2.Cu")
	)
	(gr_line
		(start 7.936484 -435.509416)
		(end 7.965948 -435.530244)
		(stroke
			(width 0.08255)
			(type default)
		)
		(layer "In2.Cu")
	)
	(gr_line
		(start 7.949946 -345.51747)
		(end 7.980172 -345.538552)
		(stroke
			(width 0.08255)
			(type default)
		)
		(layer "In2.Cu")
	)
	(gr_line
		(start 8.007604 -335.922366)
		(end 8.043418 -335.928716)
		(stroke
			(width 0.08255)
			(type default)
		)
		(layer "In2.Cu")
	)
	(gr_line
		(start 8.022844 -212.601302)
		(end 8.665972 -212.15096)
		(stroke
			(width 0.08255)
			(type default)
		)
		(layer "In2.Cu")
	)
	(gr_line
		(start 8.027162 -203.558394)
		(end 8.062976 -203.552044)
		(stroke
			(width 0.08255)
			(type default)
		)
		(layer "In2.Cu")
	)
	(gr_line
		(start 8.043418 -335.928716)
		(end 8.073644 -335.949798)
		(stroke
			(width 0.08255)
			(type default)
		)
		(layer "In2.Cu")
	)
	(gr_line
		(start 8.062976 -203.552044)
		(end 8.093202 -203.530962)
		(stroke
			(width 0.08255)
			(type default)
		)
		(layer "In2.Cu")
	)
	(gr_line
		(start 8.075676 -232.50017)
		(end 8.111744 -232.50652)
		(stroke
			(width 0.08255)
			(type default)
		)
		(layer "In2.Cu")
	)
	(gr_line
		(start 8.111744 -232.50652)
		(end 8.14197 -232.527602)
		(stroke
			(width 0.08255)
			(type default)
		)
		(layer "In2.Cu")
	)
	(gr_line
		(start 8.118602 -290.228782)
		(end 8.15467 -290.222432)
		(stroke
			(width 0.08255)
			(type default)
		)
		(layer "In2.Cu")
	)
	(gr_line
		(start 8.12292 -216.53246)
		(end 8.6106 -216.446354)
		(stroke
			(width 0.08255)
			(type default)
		)
		(layer "In2.Cu")
	)
	(gr_line
		(start 8.150352 -417.894008)
		(end 8.16864 -417.906708)
		(stroke
			(width 0.08255)
			(type default)
		)
		(layer "In2.Cu")
	)
	(gr_line
		(start 8.152638 -351.947734)
		(end 8.188706 -351.954084)
		(stroke
			(width 0.08255)
			(type default)
		)
		(layer "In2.Cu")
	)
	(gr_line
		(start 8.15467 -290.222432)
		(end 8.184896 -290.20135)
		(stroke
			(width 0.08255)
			(type default)
		)
		(layer "In2.Cu")
	)
	(gr_line
		(start 8.16864 -417.906708)
		(end 8.18134 -417.924996)
		(stroke
			(width 0.08255)
			(type default)
		)
		(layer "In2.Cu")
	)
	(gr_line
		(start 8.186166 -317.53048)
		(end 8.22198 -317.52413)
		(stroke
			(width 0.08255)
			(type default)
		)
		(layer "In2.Cu")
	)
	(gr_line
		(start 8.188706 -351.954084)
		(end 8.218932 -351.975166)
		(stroke
			(width 0.08255)
			(type default)
		)
		(layer "In2.Cu")
	)
	(gr_line
		(start 8.195056 -212.917532)
		(end 8.453628 -212.962998)
		(stroke
			(width 0.08255)
			(type default)
		)
		(layer "In2.Cu")
	)
	(gr_line
		(start 8.22198 -317.52413)
		(end 8.252206 -317.503048)
		(stroke
			(width 0.08255)
			(type default)
		)
		(layer "In2.Cu")
	)
	(gr_line
		(start 8.232394 -426.764196)
		(end 8.268462 -426.770546)
		(stroke
			(width 0.08255)
			(type default)
		)
		(layer "In2.Cu")
	)
	(gr_line
		(start 8.23976 -176.57445)
		(end 8.454644 -176.725072)
		(stroke
			(width 0.08255)
			(type default)
		)
		(layer "In2.Cu")
	)
	(gr_line
		(start 8.268462 -426.770546)
		(end 8.298688 -426.791628)
		(stroke
			(width 0.08255)
			(type default)
		)
		(layer "In2.Cu")
	)
	(gr_line
		(start 8.310118 -336.55254)
		(end 8.355838 -336.811112)
		(stroke
			(width 0.08255)
			(type default)
		)
		(layer "In2.Cu")
	)
	(gr_line
		(start 8.346948 -161.107882)
		(end 8.383778 -161.101278)
		(stroke
			(width 0.08255)
			(type default)
		)
		(layer "In2.Cu")
	)
	(gr_line
		(start 8.355838 -336.811112)
		(end 8.76173 -337.095084)
		(stroke
			(width 0.08255)
			(type default)
		)
		(layer "In2.Cu")
	)
	(gr_line
		(start 8.383778 -161.101278)
		(end 8.412988 -161.080704)
		(stroke
			(width 0.08255)
			(type default)
		)
		(layer "In2.Cu")
	)
	(gr_line
		(start 8.409432 -445.511682)
		(end 8.427212 -445.524128)
		(stroke
			(width 0.08255)
			(type default)
		)
		(layer "In2.Cu")
	)
	(gr_line
		(start 8.412988 -200.296272)
		(end 8.449056 -200.289922)
		(stroke
			(width 0.08255)
			(type default)
		)
		(layer "In2.Cu")
	)
	(gr_line
		(start 8.421624 -442.318394)
		(end 8.439912 -442.331094)
		(stroke
			(width 0.08255)
			(type default)
		)
		(layer "In2.Cu")
	)
	(gr_line
		(start 8.427212 -445.524128)
		(end 8.439658 -445.541908)
		(stroke
			(width 0.08255)
			(type default)
		)
		(layer "In2.Cu")
	)
	(gr_line
		(start 8.439912 -442.331094)
		(end 8.452612 -442.349382)
		(stroke
			(width 0.08255)
			(type default)
		)
		(layer "In2.Cu")
	)
	(gr_line
		(start 8.449056 -200.289922)
		(end 8.479282 -200.26884)
		(stroke
			(width 0.08255)
			(type default)
		)
		(layer "In2.Cu")
	)
	(gr_line
		(start 8.453628 -212.962998)
		(end 8.859266 -212.679026)
		(stroke
			(width 0.08255)
			(type default)
		)
		(layer "In2.Cu")
	)
	(gr_line
		(start 8.455914 -296.760138)
		(end 8.491728 -296.753788)
		(stroke
			(width 0.08255)
			(type default)
		)
		(layer "In2.Cu")
	)
	(gr_line
		(start 8.463534 -294.173656)
		(end 8.490712 -294.179498)
		(stroke
			(width 0.08255)
			(type default)
		)
		(layer "In2.Cu")
	)
	(gr_line
		(start 8.490712 -294.179498)
		(end 8.518144 -294.174672)
		(stroke
			(width 0.08255)
			(type default)
		)
		(layer "In2.Cu")
	)
	(gr_line
		(start 8.491728 -296.753788)
		(end 8.521954 -296.732706)
		(stroke
			(width 0.08255)
			(type default)
		)
		(layer "In2.Cu")
	)
	(gr_line
		(start 8.548624 -336.282538)
		(end 9.19353 -336.733896)
		(stroke
			(width 0.08255)
			(type default)
		)
		(layer "In2.Cu")
	)
	(gr_line
		(start 8.55091 -309.466234)
		(end 8.586724 -309.459884)
		(stroke
			(width 0.08255)
			(type default)
		)
		(layer "In2.Cu")
	)
	(gr_line
		(start 8.560816 -339.219794)
		(end 8.596884 -339.226144)
		(stroke
			(width 0.08255)
			(type default)
		)
		(layer "In2.Cu")
	)
	(gr_line
		(start 8.586724 -309.459884)
		(end 8.61695 -309.438802)
		(stroke
			(width 0.08255)
			(type default)
		)
		(layer "In2.Cu")
	)
	(gr_line
		(start 8.596884 -339.226144)
		(end 8.62711 -339.247226)
		(stroke
			(width 0.08255)
			(type default)
		)
		(layer "In2.Cu")
	)
	(gr_line
		(start 8.6106 -216.446354)
		(end 8.760968 -216.23147)
		(stroke
			(width 0.08255)
			(type default)
		)
		(layer "In2.Cu")
	)
	(gr_line
		(start 8.648954 -430.034954)
		(end 8.684768 -430.041304)
		(stroke
			(width 0.08255)
			(type default)
		)
		(layer "In2.Cu")
	)
	(gr_line
		(start 8.650224 -160.477454)
		(end 8.695944 -160.218882)
		(stroke
			(width 0.08255)
			(type default)
		)
		(layer "In2.Cu")
	)
	(gr_line
		(start 8.684768 -430.041304)
		(end 8.714994 -430.062386)
		(stroke
			(width 0.08255)
			(type default)
		)
		(layer "In2.Cu")
	)
	(gr_line
		(start 8.695944 -160.218882)
		(end 9.101582 -159.934656)
		(stroke
			(width 0.08255)
			(type default)
		)
		(layer "In2.Cu")
	)
	(gr_line
		(start 8.74522 -323.831966)
		(end 8.781034 -323.825616)
		(stroke
			(width 0.08255)
			(type default)
		)
		(layer "In2.Cu")
	)
	(gr_line
		(start 8.76173 -337.095084)
		(end 9.020302 -337.049618)
		(stroke
			(width 0.08255)
			(type default)
		)
		(layer "In2.Cu")
	)
	(gr_line
		(start 8.781034 -323.825616)
		(end 8.81126 -323.804534)
		(stroke
			(width 0.08255)
			(type default)
		)
		(layer "In2.Cu")
	)
	(gr_line
		(start 8.800338 -209.288634)
		(end 8.818626 -209.275934)
		(stroke
			(width 0.08255)
			(type default)
		)
		(layer "In2.Cu")
	)
	(gr_line
		(start 8.802116 -342.467946)
		(end 8.838184 -342.474296)
		(stroke
			(width 0.08255)
			(type default)
		)
		(layer "In2.Cu")
	)
	(gr_line
		(start 8.818626 -209.275934)
		(end 8.831326 -209.257646)
		(stroke
			(width 0.08255)
			(type default)
		)
		(layer "In2.Cu")
	)
	(gr_line
		(start 8.833612 -339.825838)
		(end 9.47674 -340.27618)
		(stroke
			(width 0.08255)
			(type default)
		)
		(layer "In2.Cu")
	)
	(gr_line
		(start 8.836914 -349.353886)
		(end 8.855202 -349.366586)
		(stroke
			(width 0.08255)
			(type default)
		)
		(layer "In2.Cu")
	)
	(gr_line
		(start 8.838184 -342.474296)
		(end 8.86841 -342.495378)
		(stroke
			(width 0.08255)
			(type default)
		)
		(layer "In2.Cu")
	)
	(gr_line
		(start 8.852408 -436.15102)
		(end 8.870696 -436.16372)
		(stroke
			(width 0.08255)
			(type default)
		)
		(layer "In2.Cu")
	)
	(gr_line
		(start 8.855202 -349.366586)
		(end 8.867902 -349.384874)
		(stroke
			(width 0.08255)
			(type default)
		)
		(layer "In2.Cu")
	)
	(gr_line
		(start 8.859266 -212.679026)
		(end 8.904986 -212.420454)
		(stroke
			(width 0.08255)
			(type default)
		)
		(layer "In2.Cu")
	)
	(gr_line
		(start 8.870696 -436.16372)
		(end 8.883396 -436.182008)
		(stroke
			(width 0.08255)
			(type default)
		)
		(layer "In2.Cu")
	)
	(gr_line
		(start 8.88111 -164.21354)
		(end 8.917178 -164.20719)
		(stroke
			(width 0.08255)
			(type default)
		)
		(layer "In2.Cu")
	)
	(gr_line
		(start 8.886444 -160.749234)
		(end 9.533128 -160.296352)
		(stroke
			(width 0.08255)
			(type default)
		)
		(layer "In2.Cu")
	)
	(gr_line
		(start 8.894064 -327.005696)
		(end 8.930132 -326.999346)
		(stroke
			(width 0.08255)
			(type default)
		)
		(layer "In2.Cu")
	)
	(gr_line
		(start 8.896604 -423.679112)
		(end 8.932418 -423.685462)
		(stroke
			(width 0.08255)
			(type default)
		)
		(layer "In2.Cu")
	)
	(gr_line
		(start 8.899398 -439.385964)
		(end 8.917686 -439.398664)
		(stroke
			(width 0.08255)
			(type default)
		)
		(layer "In2.Cu")
	)
	(gr_line
		(start 8.917178 -164.20719)
		(end 8.947404 -164.186108)
		(stroke
			(width 0.08255)
			(type default)
		)
		(layer "In2.Cu")
	)
	(gr_line
		(start 8.917686 -439.398664)
		(end 8.930386 -439.416952)
		(stroke
			(width 0.08255)
			(type default)
		)
		(layer "In2.Cu")
	)
	(gr_line
		(start 8.929116 -320.599562)
		(end 8.965184 -320.593212)
		(stroke
			(width 0.08255)
			(type default)
		)
		(layer "In2.Cu")
	)
	(gr_line
		(start 8.930132 -326.999346)
		(end 8.960358 -326.978264)
		(stroke
			(width 0.08255)
			(type default)
		)
		(layer "In2.Cu")
	)
	(gr_line
		(start 8.932418 -423.685462)
		(end 8.962644 -423.706544)
		(stroke
			(width 0.08255)
			(type default)
		)
		(layer "In2.Cu")
	)
	(gr_line
		(start 8.947404 -176.638204)
		(end 9.097772 -176.42332)
		(stroke
			(width 0.08255)
			(type default)
		)
		(layer "In2.Cu")
	)
	(gr_line
		(start 8.950452 -446.27165)
		(end 8.971534 -446.301876)
		(stroke
			(width 0.08255)
			(type default)
		)
		(layer "In2.Cu")
	)
	(gr_line
		(start 8.965184 -320.593212)
		(end 8.99541 -320.57213)
		(stroke
			(width 0.08255)
			(type default)
		)
		(layer "In2.Cu")
	)
	(gr_line
		(start 8.96874 -154.753564)
		(end 9.004808 -154.747214)
		(stroke
			(width 0.08255)
			(type default)
		)
		(layer "In2.Cu")
	)
	(gr_line
		(start 8.971534 -446.301876)
		(end 8.977884 -446.33769)
		(stroke
			(width 0.08255)
			(type default)
		)
		(layer "In2.Cu")
	)
	(gr_line
		(start 9.004808 -154.747214)
		(end 9.035034 -154.726132)
		(stroke
			(width 0.08255)
			(type default)
		)
		(layer "In2.Cu")
	)
	(gr_line
		(start 9.005824 -339.509608)
		(end 9.264396 -339.464142)
		(stroke
			(width 0.08255)
			(type default)
		)
		(layer "In2.Cu")
	)
	(gr_line
		(start 9.032748 -359.101644)
		(end 9.051036 -359.114344)
		(stroke
			(width 0.08255)
			(type default)
		)
		(layer "In2.Cu")
	)
	(gr_line
		(start 9.047226 -176.984406)
		(end 9.826498 -176.846992)
		(stroke
			(width 0.08255)
			(type default)
		)
		(layer "In2.Cu")
	)
	(gr_line
		(start 9.051036 -359.114344)
		(end 9.063736 -359.132632)
		(stroke
			(width 0.08255)
			(type default)
		)
		(layer "In2.Cu")
	)
	(gr_line
		(start 9.097772 -176.42332)
		(end 9.585452 -176.337214)
		(stroke
			(width 0.08255)
			(type default)
		)
		(layer "In2.Cu")
	)
	(gr_line
		(start 9.101582 -159.934656)
		(end 9.360154 -159.980376)
		(stroke
			(width 0.08255)
			(type default)
		)
		(layer "In2.Cu")
	)
	(gr_line
		(start 9.135364 -89.442036)
		(end 9.141714 -89.405968)
		(stroke
			(width 0.08255)
			(type default)
		)
		(layer "In2.Cu")
	)
	(gr_line
		(start 9.141714 -89.405968)
		(end 9.162796 -89.375742)
		(stroke
			(width 0.08255)
			(type default)
		)
		(layer "In2.Cu")
	)
	(gr_line
		(start 9.142222 -211.817458)
		(end 9.785858 -211.366608)
		(stroke
			(width 0.08255)
			(type default)
		)
		(layer "In2.Cu")
	)
	(gr_line
		(start 9.17448 -306.156106)
		(end 9.210294 -306.149756)
		(stroke
			(width 0.08255)
			(type default)
		)
		(layer "In2.Cu")
	)
	(gr_line
		(start 9.198356 -229.14864)
		(end 9.234424 -229.15499)
		(stroke
			(width 0.08255)
			(type default)
		)
		(layer "In2.Cu")
	)
	(gr_line
		(start 9.210294 -306.149756)
		(end 9.24052 -306.128674)
		(stroke
			(width 0.08255)
			(type default)
		)
		(layer "In2.Cu")
	)
	(gr_line
		(start 9.234424 -229.15499)
		(end 9.26465 -229.176072)
		(stroke
			(width 0.08255)
			(type default)
		)
		(layer "In2.Cu")
	)
	(gr_line
		(start 9.264396 -339.464142)
		(end 9.670034 -339.748114)
		(stroke
			(width 0.08255)
			(type default)
		)
		(layer "In2.Cu")
	)
	(gr_line
		(start 9.314434 -212.133688)
		(end 9.573006 -212.179154)
		(stroke
			(width 0.08255)
			(type default)
		)
		(layer "In2.Cu")
	)
	(gr_line
		(start 9.429496 -337.33613)
		(end 9.475216 -337.594956)
		(stroke
			(width 0.08255)
			(type default)
		)
		(layer "In2.Cu")
	)
	(gr_line
		(start 9.450578 -347.002354)
		(end 10.078212 -347.442028)
		(stroke
			(width 0.08255)
			(type default)
		)
		(layer "In2.Cu")
	)
	(gr_line
		(start 9.454896 -395.777212)
		(end 9.490964 -395.783562)
		(stroke
			(width 0.08255)
			(type default)
		)
		(layer "In2.Cu")
	)
	(gr_line
		(start 9.46277 -443.791594)
		(end 9.483852 -443.82182)
		(stroke
			(width 0.08255)
			(type default)
		)
		(layer "In2.Cu")
	)
	(gr_line
		(start 9.472676 -173.4439)
		(end 9.623298 -173.22927)
		(stroke
			(width 0.08255)
			(type default)
		)
		(layer "In2.Cu")
	)
	(gr_line
		(start 9.475216 -337.594956)
		(end 9.881108 -337.878928)
		(stroke
			(width 0.08255)
			(type default)
		)
		(layer "In2.Cu")
	)
	(gr_line
		(start 9.483852 -443.82182)
		(end 9.490202 -443.857888)
		(stroke
			(width 0.08255)
			(type default)
		)
		(layer "In2.Cu")
	)
	(gr_line
		(start 9.490964 -395.783562)
		(end 9.52119 -395.804644)
		(stroke
			(width 0.08255)
			(type default)
		)
		(layer "In2.Cu")
	)
	(gr_line
		(start 9.56564 -171.34713)
		(end 10.343134 -171.48429)
		(stroke
			(width 0.08255)
			(type default)
		)
		(layer "In2.Cu")
	)
	(gr_line
		(start 9.573006 -212.179154)
		(end 9.978644 -211.895182)
		(stroke
			(width 0.08255)
			(type default)
		)
		(layer "In2.Cu")
	)
	(gr_line
		(start 9.573514 -173.790102)
		(end 10.349738 -173.653196)
		(stroke
			(width 0.08255)
			(type default)
		)
		(layer "In2.Cu")
	)
	(gr_line
		(start 9.585452 -176.337214)
		(end 9.80059 -176.487836)
		(stroke
			(width 0.08255)
			(type default)
		)
		(layer "In2.Cu")
	)
	(gr_line
		(start 9.589008 -170.987466)
		(end 9.803892 -170.837098)
		(stroke
			(width 0.08255)
			(type default)
		)
		(layer "In2.Cu")
	)
	(gr_arc
		(start 9.596374 -424.597068)
		(mid 9.577834 -424.574968)
		(end 9.555734 -424.556428)
		(stroke
			(width 0.08255)
			(type default)
		)
		(layer "In2.Cu")
	)
	(gr_line
		(start 9.600946 -316.558676)
		(end 9.619234 -316.545976)
		(stroke
			(width 0.08255)
			(type default)
		)
		(layer "In2.Cu")
	)
	(gr_line
		(start 9.619234 -316.545976)
		(end 9.631934 -316.527688)
		(stroke
			(width 0.08255)
			(type default)
		)
		(layer "In2.Cu")
	)
	(gr_line
		(start 9.62279 -346.686124)
		(end 9.867138 -346.642944)
		(stroke
			(width 0.08255)
			(type default)
		)
		(layer "In2.Cu")
	)
	(gr_line
		(start 9.623298 -173.22927)
		(end 10.110978 -173.143164)
		(stroke
			(width 0.08255)
			(type default)
		)
		(layer "In2.Cu")
	)
	(gr_line
		(start 9.66724 -337.06562)
		(end 10.313924 -337.518248)
		(stroke
			(width 0.08255)
			(type default)
		)
		(layer "In2.Cu")
	)
	(gr_line
		(start 9.670034 -339.748114)
		(end 9.715754 -340.006432)
		(stroke
			(width 0.08255)
			(type default)
		)
		(layer "In2.Cu")
	)
	(gr_line
		(start 9.719564 -355.424232)
		(end 9.755378 -355.430582)
		(stroke
			(width 0.08255)
			(type default)
		)
		(layer "In2.Cu")
	)
	(gr_line
		(start 9.755378 -355.430582)
		(end 9.785604 -355.451664)
		(stroke
			(width 0.08255)
			(type default)
		)
		(layer "In2.Cu")
	)
	(gr_line
		(start 9.769602 -159.69361)
		(end 9.815322 -159.435038)
		(stroke
			(width 0.08255)
			(type default)
		)
		(layer "In2.Cu")
	)
	(gr_line
		(start 9.786366 -156.305504)
		(end 9.804654 -156.292804)
		(stroke
			(width 0.08255)
			(type default)
		)
		(layer "In2.Cu")
	)
	(gr_line
		(start 9.787128 -155.369768)
		(end 9.832848 -155.62834)
		(stroke
			(width 0.08255)
			(type default)
		)
		(layer "In2.Cu")
	)
	(gr_line
		(start 9.787128 -155.369768)
		(end 10.071354 -154.96413)
		(stroke
			(width 0.08255)
			(type default)
		)
		(layer "In2.Cu")
	)
	(gr_line
		(start 9.79297 -424.288204)
		(end 9.835134 -424.317668)
		(stroke
			(width 0.08255)
			(type default)
		)
		(layer "In2.Cu")
	)
	(gr_line
		(start 9.803892 -170.837098)
		(end 10.291826 -170.92295)
		(stroke
			(width 0.08255)
			(type default)
		)
		(layer "In2.Cu")
	)
	(gr_line
		(start 9.804654 -156.292804)
		(end 9.817354 -156.274516)
		(stroke
			(width 0.08255)
			(type default)
		)
		(layer "In2.Cu")
	)
	(gr_line
		(start 9.814306 -167.83558)
		(end 9.849612 -167.84193)
		(stroke
			(width 0.08255)
			(type default)
		)
		(layer "In2.Cu")
	)
	(gr_line
		(start 9.815322 -159.435038)
		(end 10.22096 -159.150812)
		(stroke
			(width 0.08255)
			(type default)
		)
		(layer "In2.Cu")
	)
	(gr_line
		(start 9.835134 -424.317668)
		(end 9.864598 -424.359832)
		(stroke
			(width 0.08255)
			(type default)
		)
		(layer "In2.Cu")
	)
	(gr_line
		(start 9.849612 -167.84193)
		(end 9.879076 -167.862504)
		(stroke
			(width 0.08255)
			(type default)
		)
		(layer "In2.Cu")
	)
	(gr_line
		(start 9.857994 -440.741562)
		(end 9.879076 -440.771788)
		(stroke
			(width 0.08255)
			(type default)
		)
		(layer "In2.Cu")
	)
	(gr_line
		(start 9.867138 -346.642944)
		(end 10.272776 -346.92717)
		(stroke
			(width 0.08255)
			(type default)
		)
		(layer "In2.Cu")
	)
	(gr_line
		(start 9.879076 -440.771788)
		(end 9.885426 -440.807602)
		(stroke
			(width 0.08255)
			(type default)
		)
		(layer "In2.Cu")
	)
	(gr_line
		(start 9.881108 -337.878928)
		(end 10.139934 -337.833462)
		(stroke
			(width 0.08255)
			(type default)
		)
		(layer "In2.Cu")
	)
	(gr_line
		(start 9.888982 -233.750612)
		(end 9.90727 -233.763312)
		(stroke
			(width 0.08255)
			(type default)
		)
		(layer "In2.Cu")
	)
	(gr_line
		(start 9.90727 -233.763312)
		(end 9.91997 -233.7816)
		(stroke
			(width 0.08255)
			(type default)
		)
		(layer "In2.Cu")
	)
	(gr_line
		(start 9.91108 -390.838944)
		(end 9.929368 -390.851644)
		(stroke
			(width 0.08255)
			(type default)
		)
		(layer "In2.Cu")
	)
	(gr_line
		(start 9.929368 -390.851644)
		(end 9.942068 -390.869932)
		(stroke
			(width 0.08255)
			(type default)
		)
		(layer "In2.Cu")
	)
	(gr_line
		(start 9.936226 -118.759986)
		(end 9.939782 -118.780814)
		(stroke
			(width 0.08255)
			(type default)
		)
		(layer "In2.Cu")
	)
	(gr_line
		(start 9.936226 -118.759986)
		(end 9.939782 -118.739412)
		(stroke
			(width 0.08255)
			(type default)
		)
		(layer "In2.Cu")
	)
	(gr_line
		(start 9.939782 -118.78056)
		(end 9.939782 -118.781322)
		(stroke
			(width 0.08255)
			(type default)
		)
		(layer "In2.Cu")
	)
	(gr_line
		(start 9.95299 -340.609682)
		(end 10.485628 -340.982808)
		(stroke
			(width 0.08255)
			(type default)
		)
		(layer "In2.Cu")
	)
	(gr_line
		(start 9.978644 -211.895182)
		(end 10.024364 -211.63661)
		(stroke
			(width 0.08255)
			(type default)
		)
		(layer "In2.Cu")
	)
	(gr_line
		(start 9.996678 -154.053032)
		(end 10.014966 -154.040332)
		(stroke
			(width 0.08255)
			(type default)
		)
		(layer "In2.Cu")
	)
	(gr_line
		(start 10.007092 -159.964374)
		(end 10.651744 -159.512762)
		(stroke
			(width 0.08255)
			(type default)
		)
		(layer "In2.Cu")
	)
	(gr_line
		(start 10.014966 -154.040332)
		(end 10.02792 -154.022044)
		(stroke
			(width 0.08255)
			(type default)
		)
		(layer "In2.Cu")
	)
	(gr_line
		(start 10.071354 -154.96413)
		(end 10.329926 -154.91841)
		(stroke
			(width 0.08255)
			(type default)
		)
		(layer "In2.Cu")
	)
	(gr_line
		(start 10.110978 -173.143164)
		(end 10.325862 -173.293532)
		(stroke
			(width 0.08255)
			(type default)
		)
		(layer "In2.Cu")
	)
	(gr_line
		(start 10.113264 -215.990424)
		(end 10.149078 -215.984074)
		(stroke
			(width 0.08255)
			(type default)
		)
		(layer "In2.Cu")
	)
	(gr_line
		(start 10.125456 -340.293452)
		(end 10.383774 -340.247986)
		(stroke
			(width 0.08255)
			(type default)
		)
		(layer "In2.Cu")
	)
	(gr_line
		(start 10.149078 -215.984074)
		(end 10.179304 -215.962992)
		(stroke
			(width 0.08255)
			(type default)
		)
		(layer "In2.Cu")
	)
	(gr_line
		(start 10.149332 -155.800298)
		(end 10.601198 -155.155138)
		(stroke
			(width 0.08255)
			(type default)
		)
		(layer "In2.Cu")
	)
	(gr_line
		(start 10.152126 -428.089568)
		(end 10.170414 -428.102268)
		(stroke
			(width 0.08255)
			(type default)
		)
		(layer "In2.Cu")
	)
	(gr_line
		(start 10.167366 -431.079656)
		(end 10.185654 -431.092356)
		(stroke
			(width 0.08255)
			(type default)
		)
		(layer "In2.Cu")
	)
	(gr_line
		(start 10.170414 -428.102268)
		(end 10.183368 -428.120556)
		(stroke
			(width 0.08255)
			(type default)
		)
		(layer "In2.Cu")
	)
	(gr_line
		(start 10.185654 -431.092356)
		(end 10.198354 -431.110644)
		(stroke
			(width 0.08255)
			(type default)
		)
		(layer "In2.Cu")
	)
	(gr_line
		(start 10.22096 -159.150812)
		(end 10.479532 -159.196532)
		(stroke
			(width 0.08255)
			(type default)
		)
		(layer "In2.Cu")
	)
	(gr_line
		(start 10.2235 -229.847394)
		(end 10.241788 -229.860094)
		(stroke
			(width 0.08255)
			(type default)
		)
		(layer "In2.Cu")
	)
	(gr_line
		(start 10.241788 -229.860094)
		(end 10.254488 -229.878382)
		(stroke
			(width 0.08255)
			(type default)
		)
		(layer "In2.Cu")
	)
	(gr_line
		(start 10.261346 -211.033614)
		(end 10.904982 -210.583018)
		(stroke
			(width 0.08255)
			(type default)
		)
		(layer "In2.Cu")
	)
	(gr_line
		(start 10.272776 -346.92717)
		(end 10.315956 -347.171518)
		(stroke
			(width 0.08255)
			(type default)
		)
		(layer "In2.Cu")
	)
	(gr_line
		(start 10.291826 -293.861236)
		(end 10.32764 -293.854886)
		(stroke
			(width 0.08255)
			(type default)
		)
		(layer "In2.Cu")
	)
	(gr_line
		(start 10.291826 -170.92295)
		(end 10.442448 -171.137834)
		(stroke
			(width 0.08255)
			(type default)
		)
		(layer "In2.Cu")
	)
	(gr_line
		(start 10.293096 -176.400968)
		(end 10.443464 -176.18583)
		(stroke
			(width 0.08255)
			(type default)
		)
		(layer "In2.Cu")
	)
	(gr_line
		(start 10.32764 -293.854886)
		(end 10.357866 -293.833804)
		(stroke
			(width 0.08255)
			(type default)
		)
		(layer "In2.Cu")
	)
	(gr_line
		(start 10.337038 -219.1512)
		(end 10.373106 -219.14485)
		(stroke
			(width 0.08255)
			(type default)
		)
		(layer "In2.Cu")
	)
	(gr_line
		(start 10.360406 -438.29097)
		(end 10.381488 -438.321196)
		(stroke
			(width 0.08255)
			(type default)
		)
		(layer "In2.Cu")
	)
	(gr_line
		(start 10.373106 -219.14485)
		(end 10.40257 -219.124022)
		(stroke
			(width 0.08255)
			(type default)
		)
		(layer "In2.Cu")
	)
	(gr_line
		(start 10.381488 -438.321196)
		(end 10.387838 -438.357264)
		(stroke
			(width 0.08255)
			(type default)
		)
		(layer "In2.Cu")
	)
	(gr_line
		(start 10.383774 -340.247986)
		(end 10.789412 -340.531958)
		(stroke
			(width 0.08255)
			(type default)
		)
		(layer "In2.Cu")
	)
	(gr_line
		(start 10.39368 -176.746916)
		(end 11.170158 -176.61001)
		(stroke
			(width 0.08255)
			(type default)
		)
		(layer "In2.Cu")
	)
	(gr_line
		(start 10.433812 -211.349844)
		(end 10.692384 -211.395564)
		(stroke
			(width 0.08255)
			(type default)
		)
		(layer "In2.Cu")
	)
	(gr_line
		(start 10.440162 -308.162198)
		(end 10.45845 -308.149498)
		(stroke
			(width 0.08255)
			(type default)
		)
		(layer "In2.Cu")
	)
	(gr_line
		(start 10.443464 -176.18583)
		(end 10.931144 -176.099978)
		(stroke
			(width 0.08255)
			(type default)
		)
		(layer "In2.Cu")
	)
	(gr_line
		(start 10.45845 -308.149498)
		(end 10.47115 -308.13121)
		(stroke
			(width 0.08255)
			(type default)
		)
		(layer "In2.Cu")
	)
	(gr_line
		(start 10.467848 -431.4952)
		(end 10.489692 -431.526442)
		(stroke
			(width 0.08255)
			(type default)
		)
		(layer "In2.Cu")
	)
	(gr_line
		(start 10.485628 -340.982808)
		(end 10.596118 -341.060024)
		(stroke
			(width 0.08255)
			(type default)
		)
		(layer "In2.Cu")
	)
	(gr_line
		(start 10.486136 -294.922702)
		(end 10.512044 -294.904668)
		(stroke
			(width 0.08255)
			(type default)
		)
		(layer "In2.Cu")
	)
	(gr_line
		(start 10.489692 -431.526442)
		(end 10.496296 -431.56378)
		(stroke
			(width 0.08255)
			(type default)
		)
		(layer "In2.Cu")
	)
	(gr_line
		(start 10.512044 -294.904668)
		(end 10.543032 -294.898064)
		(stroke
			(width 0.08255)
			(type default)
		)
		(layer "In2.Cu")
	)
	(gr_line
		(start 10.548874 -338.11972)
		(end 10.594594 -338.3788)
		(stroke
			(width 0.08255)
			(type default)
		)
		(layer "In2.Cu")
	)
	(gr_line
		(start 10.55243 -347.77426)
		(end 11.18108 -348.214442)
		(stroke
			(width 0.08255)
			(type default)
		)
		(layer "In2.Cu")
	)
	(gr_line
		(start 10.554208 -222.3135)
		(end 10.590276 -222.30715)
		(stroke
			(width 0.08255)
			(type default)
		)
		(layer "In2.Cu")
	)
	(gr_line
		(start 10.5791 -322.566538)
		(end 10.597388 -322.553838)
		(stroke
			(width 0.08255)
			(type default)
		)
		(layer "In2.Cu")
	)
	(gr_line
		(start 10.590276 -222.30715)
		(end 10.620502 -222.286068)
		(stroke
			(width 0.08255)
			(type default)
		)
		(layer "In2.Cu")
	)
	(gr_line
		(start 10.594594 -338.3788)
		(end 11.000486 -338.662772)
		(stroke
			(width 0.08255)
			(type default)
		)
		(layer "In2.Cu")
	)
	(gr_line
		(start 10.597388 -322.553838)
		(end 10.610088 -322.53555)
		(stroke
			(width 0.08255)
			(type default)
		)
		(layer "In2.Cu")
	)
	(gr_line
		(start 10.628376 -341.082884)
		(end 10.723626 -341.149432)
		(stroke
			(width 0.08255)
			(type default)
		)
		(layer "In2.Cu")
	)
	(gr_line
		(start 10.640822 -283.477208)
		(end 10.679176 -283.47035)
		(stroke
			(width 0.08255)
			(type default)
		)
		(layer "In2.Cu")
	)
	(gr_line
		(start 10.641838 -319.41897)
		(end 10.660126 -319.40627)
		(stroke
			(width 0.08255)
			(type default)
		)
		(layer "In2.Cu")
	)
	(gr_line
		(start 10.660126 -319.40627)
		(end 10.672826 -319.387982)
		(stroke
			(width 0.08255)
			(type default)
		)
		(layer "In2.Cu")
	)
	(gr_line
		(start 10.660634 -151.609552)
		(end 10.74674 -151.121872)
		(stroke
			(width 0.08255)
			(type default)
		)
		(layer "In2.Cu")
	)
	(gr_line
		(start 10.660634 -151.609552)
		(end 10.81151 -151.82469)
		(stroke
			(width 0.08255)
			(type default)
		)
		(layer "In2.Cu")
	)
	(gr_line
		(start 10.679176 -283.47035)
		(end 10.710164 -283.448506)
		(stroke
			(width 0.08255)
			(type default)
		)
		(layer "In2.Cu")
	)
	(gr_line
		(start 10.69213 -353.707192)
		(end 10.710418 -353.719892)
		(stroke
			(width 0.08255)
			(type default)
		)
		(layer "In2.Cu")
	)
	(gr_line
		(start 10.692384 -211.395564)
		(end 11.098022 -211.111338)
		(stroke
			(width 0.08255)
			(type default)
		)
		(layer "In2.Cu")
	)
	(gr_line
		(start 10.710418 -353.719892)
		(end 10.723118 -353.73818)
		(stroke
			(width 0.08255)
			(type default)
		)
		(layer "In2.Cu")
	)
	(gr_line
		(start 10.71626 -280.290016)
		(end 10.754614 -280.283158)
		(stroke
			(width 0.08255)
			(type default)
		)
		(layer "In2.Cu")
	)
	(gr_line
		(start 10.72515 -347.458284)
		(end 10.969498 -347.415104)
		(stroke
			(width 0.08255)
			(type default)
		)
		(layer "In2.Cu")
	)
	(gr_line
		(start 10.74674 -151.121872)
		(end 10.961878 -150.97125)
		(stroke
			(width 0.08255)
			(type default)
		)
		(layer "In2.Cu")
	)
	(gr_line
		(start 10.754614 -280.283158)
		(end 10.785602 -280.261314)
		(stroke
			(width 0.08255)
			(type default)
		)
		(layer "In2.Cu")
	)
	(gr_line
		(start 10.759694 -168.913302)
		(end 10.78992 -168.934384)
		(stroke
			(width 0.08255)
			(type default)
		)
		(layer "In2.Cu")
	)
	(gr_line
		(start 10.782554 -204.63383)
		(end 10.799572 -204.621892)
		(stroke
			(width 0.08255)
			(type default)
		)
		(layer "In2.Cu")
	)
	(gr_line
		(start 10.784586 -337.847686)
		(end 11.43381 -338.302346)
		(stroke
			(width 0.08255)
			(type default)
		)
		(layer "In2.Cu")
	)
	(gr_line
		(start 10.789412 -340.531958)
		(end 10.835132 -340.790276)
		(stroke
			(width 0.08255)
			(type default)
		)
		(layer "In2.Cu")
	)
	(gr_line
		(start 10.78992 -168.934384)
		(end 10.825734 -168.940734)
		(stroke
			(width 0.08255)
			(type default)
		)
		(layer "In2.Cu")
	)
	(gr_line
		(start 10.799572 -204.621892)
		(end 10.81151 -204.604874)
		(stroke
			(width 0.08255)
			(type default)
		)
		(layer "In2.Cu")
	)
	(gr_line
		(start 10.818114 -173.206664)
		(end 10.96899 -172.99178)
		(stroke
			(width 0.08255)
			(type default)
		)
		(layer "In2.Cu")
	)
	(gr_line
		(start 10.83564 -340.793832)
		(end 10.927588 -340.858348)
		(stroke
			(width 0.08255)
			(type default)
		)
		(layer "In2.Cu")
	)
	(gr_line
		(start 10.87628 -118.880382)
		(end 10.879836 -118.90121)
		(stroke
			(width 0.08255)
			(type default)
		)
		(layer "In2.Cu")
	)
	(gr_line
		(start 10.87628 -118.880382)
		(end 10.879836 -118.859808)
		(stroke
			(width 0.08255)
			(type default)
		)
		(layer "In2.Cu")
	)
	(gr_line
		(start 10.879836 -118.900956)
		(end 10.879836 -118.901718)
		(stroke
			(width 0.08255)
			(type default)
		)
		(layer "In2.Cu")
	)
	(gr_line
		(start 10.89787 -150.26386)
		(end 10.983976 -149.77618)
		(stroke
			(width 0.08255)
			(type default)
		)
		(layer "In2.Cu")
	)
	(gr_line
		(start 10.89787 -150.26386)
		(end 11.048746 -150.478998)
		(stroke
			(width 0.08255)
			(type default)
		)
		(layer "In2.Cu")
	)
	(gr_line
		(start 10.898124 -162.820096)
		(end 10.916412 -162.807396)
		(stroke
			(width 0.08255)
			(type default)
		)
		(layer "In2.Cu")
	)
	(gr_line
		(start 10.911332 -171.584366)
		(end 11.688826 -171.721526)
		(stroke
			(width 0.08255)
			(type default)
		)
		(layer "In2.Cu")
	)
	(gr_line
		(start 10.916412 -162.807396)
		(end 10.929112 -162.789108)
		(stroke
			(width 0.08255)
			(type default)
		)
		(layer "In2.Cu")
	)
	(gr_line
		(start 10.917174 -173.55312)
		(end 11.695176 -173.41596)
		(stroke
			(width 0.08255)
			(type default)
		)
		(layer "In2.Cu")
	)
	(gr_line
		(start 10.923778 -343.93505)
		(end 10.942066 -343.94775)
		(stroke
			(width 0.08255)
			(type default)
		)
		(layer "In2.Cu")
	)
	(gr_line
		(start 10.931144 -176.099978)
		(end 11.146282 -176.2506)
		(stroke
			(width 0.08255)
			(type default)
		)
		(layer "In2.Cu")
	)
	(gr_line
		(start 10.9347 -171.224702)
		(end 11.149838 -171.074334)
		(stroke
			(width 0.08255)
			(type default)
		)
		(layer "In2.Cu")
	)
	(gr_line
		(start 10.942066 -343.94775)
		(end 10.954766 -343.966038)
		(stroke
			(width 0.08255)
			(type default)
		)
		(layer "In2.Cu")
	)
	(gr_line
		(start 10.959084 -344.592148)
		(end 11.399012 -345.22029)
		(stroke
			(width 0.08255)
			(type default)
		)
		(layer "In2.Cu")
	)
	(gr_line
		(start 10.96899 -172.99178)
		(end 11.45667 -172.905928)
		(stroke
			(width 0.08255)
			(type default)
		)
		(layer "In2.Cu")
	)
	(gr_line
		(start 10.969498 -347.415104)
		(end 11.37539 -347.69933)
		(stroke
			(width 0.08255)
			(type default)
		)
		(layer "In2.Cu")
	)
	(gr_line
		(start 10.983976 -149.77618)
		(end 11.199114 -149.625558)
		(stroke
			(width 0.08255)
			(type default)
		)
		(layer "In2.Cu")
	)
	(gr_line
		(start 11.000486 -338.662772)
		(end 11.259058 -338.617052)
		(stroke
			(width 0.08255)
			(type default)
		)
		(layer "In2.Cu")
	)
	(gr_line
		(start 11.021822 -152.600914)
		(end 11.043666 -152.569926)
		(stroke
			(width 0.08255)
			(type default)
		)
		(layer "In2.Cu")
	)
	(gr_line
		(start 11.043666 -152.569926)
		(end 11.050524 -152.531826)
		(stroke
			(width 0.08255)
			(type default)
		)
		(layer "In2.Cu")
	)
	(gr_arc
		(start 11.049254 -429.385222)
		(mid 11.03913 -429.350711)
		(end 11.021822 -429.319182)
		(stroke
			(width 0.08255)
			(type default)
		)
		(layer "In2.Cu")
	)
	(gr_line
		(start 11.049254 -429.384968)
		(end 11.049254 -429.385222)
		(stroke
			(width 0.08255)
			(type default)
		)
		(layer "In2.Cu")
	)
	(gr_line
		(start 11.063732 -314.482734)
		(end 11.084814 -314.452508)
		(stroke
			(width 0.08255)
			(type default)
		)
		(layer "In2.Cu")
	)
	(gr_line
		(start 11.071606 -341.393272)
		(end 11.716512 -341.844884)
		(stroke
			(width 0.08255)
			(type default)
		)
		(layer "In2.Cu")
	)
	(gr_line
		(start 11.084814 -314.452508)
		(end 11.091164 -314.41644)
		(stroke
			(width 0.08255)
			(type default)
		)
		(layer "In2.Cu")
	)
	(gr_line
		(start 11.098022 -211.111338)
		(end 11.143742 -210.852766)
		(stroke
			(width 0.08255)
			(type default)
		)
		(layer "In2.Cu")
	)
	(gr_line
		(start 11.135106 -148.918168)
		(end 11.221212 -148.430488)
		(stroke
			(width 0.08255)
			(type default)
		)
		(layer "In2.Cu")
	)
	(gr_line
		(start 11.135106 -148.918168)
		(end 11.285982 -149.13356)
		(stroke
			(width 0.08255)
			(type default)
		)
		(layer "In2.Cu")
	)
	(gr_line
		(start 11.149838 -171.074334)
		(end 11.637518 -171.160186)
		(stroke
			(width 0.08255)
			(type default)
		)
		(layer "In2.Cu")
	)
	(gr_line
		(start 11.17092 -151.848566)
		(end 11.307826 -151.071326)
		(stroke
			(width 0.08255)
			(type default)
		)
		(layer "In2.Cu")
	)
	(gr_line
		(start 11.221212 -148.430488)
		(end 11.43635 -148.279866)
		(stroke
			(width 0.08255)
			(type default)
		)
		(layer "In2.Cu")
	)
	(gr_line
		(start 11.22934 -344.353896)
		(end 11.473688 -344.397076)
		(stroke
			(width 0.08255)
			(type default)
		)
		(layer "In2.Cu")
	)
	(gr_line
		(start 11.24458 -341.077296)
		(end 11.503152 -341.031576)
		(stroke
			(width 0.08255)
			(type default)
		)
		(layer "In2.Cu")
	)
	(gr_line
		(start 11.279632 -169.023284)
		(end 11.430254 -169.238168)
		(stroke
			(width 0.08255)
			(type default)
		)
		(layer "In2.Cu")
	)
	(gr_arc
		(start 11.287252 -427.038516)
		(mid 11.277174 -427.003982)
		(end 11.25982 -426.972476)
		(stroke
			(width 0.08255)
			(type default)
		)
		(layer "In2.Cu")
	)
	(gr_line
		(start 11.368278 -304.63871)
		(end 11.386566 -304.62601)
		(stroke
			(width 0.08255)
			(type default)
		)
		(layer "In2.Cu")
	)
	(gr_line
		(start 11.37539 -347.69933)
		(end 11.41857 -347.943678)
		(stroke
			(width 0.08255)
			(type default)
		)
		(layer "In2.Cu")
	)
	(gr_line
		(start 11.379708 -168.677082)
		(end 12.156186 -168.813988)
		(stroke
			(width 0.08255)
			(type default)
		)
		(layer "In2.Cu")
	)
	(gr_line
		(start 11.386566 -304.62601)
		(end 11.399266 -304.607722)
		(stroke
			(width 0.08255)
			(type default)
		)
		(layer "In2.Cu")
	)
	(gr_line
		(start 11.408156 -150.502874)
		(end 11.545062 -149.725634)
		(stroke
			(width 0.08255)
			(type default)
		)
		(layer "In2.Cu")
	)
	(gr_line
		(start 11.430254 -169.238168)
		(end 11.917934 -169.32402)
		(stroke
			(width 0.08255)
			(type default)
		)
		(layer "In2.Cu")
	)
	(gr_line
		(start 11.45667 -172.905928)
		(end 11.671554 -173.056296)
		(stroke
			(width 0.08255)
			(type default)
		)
		(layer "In2.Cu")
	)
	(gr_line
		(start 11.461496 -158.945834)
		(end 11.479784 -158.933134)
		(stroke
			(width 0.08255)
			(type default)
		)
		(layer "In2.Cu")
	)
	(gr_line
		(start 11.473688 -344.397076)
		(end 11.757914 -344.802968)
		(stroke
			(width 0.08255)
			(type default)
		)
		(layer "In2.Cu")
	)
	(gr_line
		(start 11.479784 -158.933134)
		(end 11.492484 -158.914846)
		(stroke
			(width 0.08255)
			(type default)
		)
		(layer "In2.Cu")
	)
	(gr_line
		(start 11.503152 -341.031576)
		(end 11.90879 -341.315802)
		(stroke
			(width 0.08255)
			(type default)
		)
		(layer "In2.Cu")
	)
	(gr_line
		(start 11.55573 -214.999062)
		(end 11.574018 -214.986362)
		(stroke
			(width 0.08255)
			(type default)
		)
		(layer "In2.Cu")
	)
	(gr_line
		(start 11.574018 -214.986362)
		(end 11.586718 -214.968074)
		(stroke
			(width 0.08255)
			(type default)
		)
		(layer "In2.Cu")
	)
	(gr_line
		(start 11.575034 -426.802296)
		(end 11.617452 -426.863002)
		(stroke
			(width 0.08255)
			(type default)
		)
		(layer "In2.Cu")
	)
	(gr_line
		(start 11.617452 -426.863002)
		(end 11.630152 -426.935392)
		(stroke
			(width 0.08255)
			(type default)
		)
		(layer "In2.Cu")
	)
	(gr_line
		(start 11.6332 -325.106284)
		(end 11.651488 -325.093584)
		(stroke
			(width 0.08255)
			(type default)
		)
		(layer "In2.Cu")
	)
	(gr_line
		(start 11.637518 -171.160186)
		(end 11.78814 -171.375324)
		(stroke
			(width 0.08255)
			(type default)
		)
		(layer "In2.Cu")
	)
	(gr_line
		(start 11.645392 -149.155658)
		(end 11.782044 -148.380196)
		(stroke
			(width 0.08255)
			(type default)
		)
		(layer "In2.Cu")
	)
	(gr_line
		(start 11.651488 -325.093584)
		(end 11.664188 -325.075296)
		(stroke
			(width 0.08255)
			(type default)
		)
		(layer "In2.Cu")
	)
	(gr_line
		(start 11.714734 -345.047316)
		(end 11.757914 -344.802968)
		(stroke
			(width 0.08255)
			(type default)
		)
		(layer "In2.Cu")
	)
	(gr_line
		(start 11.792712 -356.8573)
		(end 11.811 -356.87)
		(stroke
			(width 0.08255)
			(type default)
		)
		(layer "In2.Cu")
	)
	(gr_line
		(start 11.811 -356.87)
		(end 11.8237 -356.888288)
		(stroke
			(width 0.08255)
			(type default)
		)
		(layer "In2.Cu")
	)
	(gr_line
		(start 11.879326 -153.330148)
		(end 11.900408 -153.299922)
		(stroke
			(width 0.08255)
			(type default)
		)
		(layer "In2.Cu")
	)
	(gr_line
		(start 11.900408 -153.299922)
		(end 11.906758 -153.263854)
		(stroke
			(width 0.08255)
			(type default)
		)
		(layer "In2.Cu")
	)
	(gr_line
		(start 11.90879 -341.315802)
		(end 11.95451 -341.574374)
		(stroke
			(width 0.08255)
			(type default)
		)
		(layer "In2.Cu")
	)
	(gr_line
		(start 11.917934 -169.32402)
		(end 12.132818 -169.173652)
		(stroke
			(width 0.08255)
			(type default)
		)
		(layer "In2.Cu")
	)
	(gr_line
		(start 11.934444 -394.335762)
		(end 11.947144 -394.35405)
		(stroke
			(width 0.08255)
			(type default)
		)
		(layer "In2.Cu")
	)
	(gr_line
		(start 11.945112 -119.08028)
		(end 11.948668 -119.101108)
		(stroke
			(width 0.08255)
			(type default)
		)
		(layer "In2.Cu")
	)
	(gr_line
		(start 11.945112 -119.08028)
		(end 11.948668 -119.059706)
		(stroke
			(width 0.08255)
			(type default)
		)
		(layer "In2.Cu")
	)
	(gr_line
		(start 11.947144 -394.35405)
		(end 11.965432 -394.36675)
		(stroke
			(width 0.08255)
			(type default)
		)
		(layer "In2.Cu")
	)
	(gr_line
		(start 11.948668 -119.100854)
		(end 11.948668 -119.101616)
		(stroke
			(width 0.08255)
			(type default)
		)
		(layer "In2.Cu")
	)
	(gr_line
		(start 11.979656 -327.226422)
		(end 11.997944 -327.213722)
		(stroke
			(width 0.08255)
			(type default)
		)
		(layer "In2.Cu")
	)
	(gr_line
		(start 11.997944 -327.213722)
		(end 12.010644 -327.195434)
		(stroke
			(width 0.08255)
			(type default)
		)
		(layer "In2.Cu")
	)
	(gr_line
		(start 12.000484 -307.211984)
		(end 12.006834 -307.175916)
		(stroke
			(width 0.08255)
			(type default)
		)
		(layer "In2.Cu")
	)
	(gr_line
		(start 12.006834 -307.175916)
		(end 12.027916 -307.14569)
		(stroke
			(width 0.08255)
			(type default)
		)
		(layer "In2.Cu")
	)
	(gr_line
		(start 12.021566 -423.410126)
		(end 12.042648 -423.440352)
		(stroke
			(width 0.08255)
			(type default)
		)
		(layer "In2.Cu")
	)
	(gr_line
		(start 12.042648 -423.440352)
		(end 12.048998 -423.47642)
		(stroke
			(width 0.08255)
			(type default)
		)
		(layer "In2.Cu")
	)
	(gr_line
		(start 12.051284 -158.116778)
		(end 12.072366 -158.086552)
		(stroke
			(width 0.08255)
			(type default)
		)
		(layer "In2.Cu")
	)
	(gr_line
		(start 12.072366 -158.086552)
		(end 12.078716 -158.050484)
		(stroke
			(width 0.08255)
			(type default)
		)
		(layer "In2.Cu")
	)
	(gr_line
		(start 12.073636 -399.438876)
		(end 12.109704 -399.445226)
		(stroke
			(width 0.08255)
			(type default)
		)
		(layer "In2.Cu")
	)
	(gr_line
		(start 12.093956 -210.184492)
		(end 12.112244 -210.171792)
		(stroke
			(width 0.08255)
			(type default)
		)
		(layer "In2.Cu")
	)
	(gr_line
		(start 12.109704 -399.445226)
		(end 12.13993 -399.466308)
		(stroke
			(width 0.08255)
			(type default)
		)
		(layer "In2.Cu")
	)
	(gr_line
		(start 12.11199 -217.926412)
		(end 12.130278 -217.913712)
		(stroke
			(width 0.08255)
			(type default)
		)
		(layer "In2.Cu")
	)
	(gr_line
		(start 12.112244 -210.171792)
		(end 12.124944 -210.153504)
		(stroke
			(width 0.08255)
			(type default)
		)
		(layer "In2.Cu")
	)
	(gr_line
		(start 12.128246 -317.310262)
		(end 12.149328 -317.280036)
		(stroke
			(width 0.08255)
			(type default)
		)
		(layer "In2.Cu")
	)
	(gr_line
		(start 12.130278 -217.913712)
		(end 12.142978 -217.895424)
		(stroke
			(width 0.08255)
			(type default)
		)
		(layer "In2.Cu")
	)
	(gr_line
		(start 12.149328 -317.280036)
		(end 12.155678 -317.243968)
		(stroke
			(width 0.08255)
			(type default)
		)
		(layer "In2.Cu")
	)
	(gr_line
		(start 12.163806 -172.969428)
		(end 12.314682 -172.754544)
		(stroke
			(width 0.08255)
			(type default)
		)
		(layer "In2.Cu")
	)
	(gr_line
		(start 12.182856 -142.977108)
		(end 12.268962 -142.489428)
		(stroke
			(width 0.08255)
			(type default)
		)
		(layer "In2.Cu")
	)
	(gr_line
		(start 12.182856 -142.977108)
		(end 12.333478 -143.191992)
		(stroke
			(width 0.08255)
			(type default)
		)
		(layer "In2.Cu")
	)
	(gr_line
		(start 12.222988 -348.510098)
		(end 12.241276 -348.522798)
		(stroke
			(width 0.08255)
			(type default)
		)
		(layer "In2.Cu")
	)
	(gr_line
		(start 12.241276 -348.522798)
		(end 12.253976 -348.541086)
		(stroke
			(width 0.08255)
			(type default)
		)
		(layer "In2.Cu")
	)
	(gr_line
		(start 12.257278 -171.821602)
		(end 13.035026 -171.958762)
		(stroke
			(width 0.08255)
			(type default)
		)
		(layer "In2.Cu")
	)
	(gr_line
		(start 12.26312 -173.315884)
		(end 13.040614 -173.178724)
		(stroke
			(width 0.08255)
			(type default)
		)
		(layer "In2.Cu")
	)
	(gr_line
		(start 12.268962 -142.489428)
		(end 12.483846 -142.338806)
		(stroke
			(width 0.08255)
			(type default)
		)
		(layer "In2.Cu")
	)
	(gr_line
		(start 12.280646 -171.462192)
		(end 12.49553 -171.31157)
		(stroke
			(width 0.08255)
			(type default)
		)
		(layer "In2.Cu")
	)
	(gr_line
		(start 12.314682 -172.754544)
		(end 12.802362 -172.668692)
		(stroke
			(width 0.08255)
			(type default)
		)
		(layer "In2.Cu")
	)
	(gr_line
		(start 12.365228 -200.539858)
		(end 12.383516 -200.527158)
		(stroke
			(width 0.08255)
			(type default)
		)
		(layer "In2.Cu")
	)
	(gr_line
		(start 12.383516 -200.527158)
		(end 12.396216 -200.50887)
		(stroke
			(width 0.08255)
			(type default)
		)
		(layer "In2.Cu")
	)
	(gr_line
		(start 12.420092 -141.631416)
		(end 12.506198 -141.143736)
		(stroke
			(width 0.08255)
			(type default)
		)
		(layer "In2.Cu")
	)
	(gr_line
		(start 12.420092 -141.631416)
		(end 12.570714 -141.8463)
		(stroke
			(width 0.08255)
			(type default)
		)
		(layer "In2.Cu")
	)
	(gr_line
		(start 12.49553 -171.31157)
		(end 12.98321 -171.397422)
		(stroke
			(width 0.08255)
			(type default)
		)
		(layer "In2.Cu")
	)
	(gr_line
		(start 12.506198 -141.143736)
		(end 12.721082 -140.99286)
		(stroke
			(width 0.08255)
			(type default)
		)
		(layer "In2.Cu")
	)
	(gr_line
		(start 12.597384 -294.825674)
		(end 12.62126 -294.820594)
		(stroke
			(width 0.08255)
			(type default)
		)
		(layer "In2.Cu")
	)
	(gr_line
		(start 12.62126 -294.820594)
		(end 12.641072 -294.80764)
		(stroke
			(width 0.08255)
			(type default)
		)
		(layer "In2.Cu")
	)
	(gr_line
		(start 12.62507 -169.26052)
		(end 12.775946 -169.475404)
		(stroke
			(width 0.08255)
			(type default)
		)
		(layer "In2.Cu")
	)
	(gr_line
		(start 12.645136 -237.673134)
		(end 12.666218 -237.70336)
		(stroke
			(width 0.08255)
			(type default)
		)
		(layer "In2.Cu")
	)
	(gr_line
		(start 12.664948 -160.309814)
		(end 12.68603 -160.279588)
		(stroke
			(width 0.08255)
			(type default)
		)
		(layer "In2.Cu")
	)
	(gr_line
		(start 12.666218 -237.70336)
		(end 12.672568 -237.739428)
		(stroke
			(width 0.08255)
			(type default)
		)
		(layer "In2.Cu")
	)
	(gr_line
		(start 12.68603 -160.279588)
		(end 12.69238 -160.24352)
		(stroke
			(width 0.08255)
			(type default)
		)
		(layer "In2.Cu")
	)
	(gr_line
		(start 12.693142 -143.213074)
		(end 12.829286 -142.441168)
		(stroke
			(width 0.08255)
			(type default)
		)
		(layer "In2.Cu")
	)
	(gr_line
		(start 12.693396 -340.138004)
		(end 12.738862 -339.879178)
		(stroke
			(width 0.08255)
			(type default)
		)
		(layer "In2.Cu")
	)
	(gr_line
		(start 12.693396 -340.138004)
		(end 12.977368 -340.543642)
		(stroke
			(width 0.08255)
			(type default)
		)
		(layer "In2.Cu")
	)
	(gr_line
		(start 12.723368 -168.91381)
		(end 13.503402 -169.051478)
		(stroke
			(width 0.08255)
			(type default)
		)
		(layer "In2.Cu")
	)
	(gr_line
		(start 12.750546 -342.134698)
		(end 12.768834 -342.147398)
		(stroke
			(width 0.08255)
			(type default)
		)
		(layer "In2.Cu")
	)
	(gr_line
		(start 12.766294 -319.456816)
		(end 12.787376 -319.42659)
		(stroke
			(width 0.08255)
			(type default)
		)
		(layer "In2.Cu")
	)
	(gr_line
		(start 12.768834 -342.147398)
		(end 12.781534 -342.165686)
		(stroke
			(width 0.08255)
			(type default)
		)
		(layer "In2.Cu")
	)
	(gr_line
		(start 12.775946 -169.475404)
		(end 13.263626 -169.561256)
		(stroke
			(width 0.08255)
			(type default)
		)
		(layer "In2.Cu")
	)
	(gr_line
		(start 12.787376 -319.42659)
		(end 12.793726 -319.390522)
		(stroke
			(width 0.08255)
			(type default)
		)
		(layer "In2.Cu")
	)
	(gr_line
		(start 12.798806 -358.280716)
		(end 12.819888 -358.310942)
		(stroke
			(width 0.08255)
			(type default)
		)
		(layer "In2.Cu")
	)
	(gr_line
		(start 12.802362 -172.668692)
		(end 13.017246 -172.81906)
		(stroke
			(width 0.08255)
			(type default)
		)
		(layer "In2.Cu")
	)
	(gr_line
		(start 12.819888 -358.310942)
		(end 12.826238 -358.346756)
		(stroke
			(width 0.08255)
			(type default)
		)
		(layer "In2.Cu")
	)
	(gr_line
		(start 12.930378 -141.86789)
		(end 13.066776 -141.094206)
		(stroke
			(width 0.08255)
			(type default)
		)
		(layer "In2.Cu")
	)
	(gr_line
		(start 12.949682 -364.680246)
		(end 12.970764 -364.710472)
		(stroke
			(width 0.08255)
			(type default)
		)
		(layer "In2.Cu")
	)
	(gr_line
		(start 12.970764 -364.710472)
		(end 12.977114 -364.74654)
		(stroke
			(width 0.08255)
			(type default)
		)
		(layer "In2.Cu")
	)
	(gr_line
		(start 12.977368 -340.543642)
		(end 13.236194 -340.589362)
		(stroke
			(width 0.08255)
			(type default)
		)
		(layer "In2.Cu")
	)
	(gr_line
		(start 12.98321 -171.397422)
		(end 13.134086 -171.61256)
		(stroke
			(width 0.08255)
			(type default)
		)
		(layer "In2.Cu")
	)
	(gr_line
		(start 12.990068 -208.918302)
		(end 13.01115 -208.888076)
		(stroke
			(width 0.08255)
			(type default)
		)
		(layer "In2.Cu")
	)
	(gr_line
		(start 13.01115 -208.888076)
		(end 13.0175 -208.852008)
		(stroke
			(width 0.08255)
			(type default)
		)
		(layer "In2.Cu")
	)
	(gr_line
		(start 13.053568 -339.704426)
		(end 13.50645 -340.351364)
		(stroke
			(width 0.08255)
			(type default)
		)
		(layer "In2.Cu")
	)
	(gr_line
		(start 13.066776 -220.573092)
		(end 13.085064 -220.560392)
		(stroke
			(width 0.08255)
			(type default)
		)
		(layer "In2.Cu")
	)
	(gr_line
		(start 13.085064 -220.560392)
		(end 13.097764 -220.542104)
		(stroke
			(width 0.08255)
			(type default)
		)
		(layer "In2.Cu")
	)
	(gr_line
		(start 13.115544 -323.002656)
		(end 13.136626 -322.97243)
		(stroke
			(width 0.08255)
			(type default)
		)
		(layer "In2.Cu")
	)
	(gr_line
		(start 13.136626 -322.97243)
		(end 13.142976 -322.936362)
		(stroke
			(width 0.08255)
			(type default)
		)
		(layer "In2.Cu")
	)
	(gr_line
		(start 13.161264 -405.586692)
		(end 13.181838 -405.590248)
		(stroke
			(width 0.08255)
			(type default)
		)
		(layer "In2.Cu")
	)
	(gr_line
		(start 13.167614 -140.52423)
		(end 13.167614 -140.524484)
		(stroke
			(width 0.08255)
			(type default)
		)
		(layer "In2.Cu")
	)
	(gr_line
		(start 13.167614 -140.52423)
		(end 13.17117 -140.503402)
		(stroke
			(width 0.08255)
			(type default)
		)
		(layer "In2.Cu")
	)
	(gr_line
		(start 13.167614 -140.482828)
		(end 13.17117 -140.503402)
		(stroke
			(width 0.08255)
			(type default)
		)
		(layer "In2.Cu")
	)
	(gr_line
		(start 13.17117 -472.147138)
		(end 13.17752 -472.182952)
		(stroke
			(width 0.08255)
			(type default)
		)
		(layer "In2.Cu")
	)
	(gr_line
		(start 13.17752 -472.182952)
		(end 13.198602 -472.213178)
		(stroke
			(width 0.08255)
			(type default)
		)
		(layer "In2.Cu")
	)
	(gr_line
		(start 13.181838 -405.590248)
		(end 13.202412 -405.586692)
		(stroke
			(width 0.08255)
			(type default)
		)
		(layer "In2.Cu")
	)
	(gr_line
		(start 13.228828 -205.606142)
		(end 13.235178 -205.570074)
		(stroke
			(width 0.08255)
			(type default)
		)
		(layer "In2.Cu")
	)
	(gr_line
		(start 13.235178 -205.570074)
		(end 13.25626 -205.539848)
		(stroke
			(width 0.08255)
			(type default)
		)
		(layer "In2.Cu")
	)
	(gr_line
		(start 13.263626 -169.561256)
		(end 13.47851 -169.410888)
		(stroke
			(width 0.08255)
			(type default)
		)
		(layer "In2.Cu")
	)
	(gr_line
		(start 13.41374 -212.358732)
		(end 13.434822 -212.328506)
		(stroke
			(width 0.08255)
			(type default)
		)
		(layer "In2.Cu")
	)
	(gr_line
		(start 13.434822 -212.328506)
		(end 13.441172 -212.292692)
		(stroke
			(width 0.08255)
			(type default)
		)
		(layer "In2.Cu")
	)
	(gr_line
		(start 13.47724 -341.257382)
		(end 13.522706 -340.998556)
		(stroke
			(width 0.08255)
			(type default)
		)
		(layer "In2.Cu")
	)
	(gr_line
		(start 13.47724 -341.257382)
		(end 13.761212 -341.66302)
		(stroke
			(width 0.08255)
			(type default)
		)
		(layer "In2.Cu")
	)
	(gr_line
		(start 13.501624 -307.560726)
		(end 13.507974 -307.524658)
		(stroke
			(width 0.08255)
			(type default)
		)
		(layer "In2.Cu")
	)
	(gr_line
		(start 13.507974 -307.524658)
		(end 13.529056 -307.494432)
		(stroke
			(width 0.08255)
			(type default)
		)
		(layer "In2.Cu")
	)
	(gr_line
		(start 13.602462 -172.058838)
		(end 13.61694 -172.061378)
		(stroke
			(width 0.08255)
			(type default)
		)
		(layer "In2.Cu")
	)
	(gr_line
		(start 13.61694 -172.061378)
		(end 13.632434 -172.059346)
		(stroke
			(width 0.08255)
			(type default)
		)
		(layer "In2.Cu")
	)
	(gr_line
		(start 13.647674 -214.791544)
		(end 13.784072 -214.016844)
		(stroke
			(width 0.08255)
			(type default)
		)
		(layer "In2.Cu")
	)
	(gr_line
		(start 13.753338 -324.706742)
		(end 13.77442 -324.676516)
		(stroke
			(width 0.08255)
			(type default)
		)
		(layer "In2.Cu")
	)
	(gr_line
		(start 13.761212 -341.66302)
		(end 14.019784 -341.70874)
		(stroke
			(width 0.08255)
			(type default)
		)
		(layer "In2.Cu")
	)
	(gr_line
		(start 13.77442 -324.676516)
		(end 13.78077 -324.640448)
		(stroke
			(width 0.08255)
			(type default)
		)
		(layer "In2.Cu")
	)
	(gr_line
		(start 13.775436 -358.097074)
		(end 13.796518 -358.1273)
		(stroke
			(width 0.08255)
			(type default)
		)
		(layer "In2.Cu")
	)
	(gr_line
		(start 13.796518 -358.1273)
		(end 13.802868 -358.163368)
		(stroke
			(width 0.08255)
			(type default)
		)
		(layer "In2.Cu")
	)
	(gr_line
		(start 13.800836 -299.003466)
		(end 13.819124 -298.990766)
		(stroke
			(width 0.08255)
			(type default)
		)
		(layer "In2.Cu")
	)
	(gr_line
		(start 13.819124 -298.990766)
		(end 13.831824 -298.972478)
		(stroke
			(width 0.08255)
			(type default)
		)
		(layer "In2.Cu")
	)
	(gr_line
		(start 13.838682 -340.825836)
		(end 14.290294 -341.470742)
		(stroke
			(width 0.08255)
			(type default)
		)
		(layer "In2.Cu")
	)
	(gr_line
		(start 13.88364 -215.411812)
		(end 13.904468 -215.382348)
		(stroke
			(width 0.08255)
			(type default)
		)
		(layer "In2.Cu")
	)
	(gr_line
		(start 13.88491 -213.445344)
		(end 14.021816 -212.66912)
		(stroke
			(width 0.08255)
			(type default)
		)
		(layer "In2.Cu")
	)
	(gr_line
		(start 13.904468 -215.382348)
		(end 13.910818 -215.346534)
		(stroke
			(width 0.08255)
			(type default)
		)
		(layer "In2.Cu")
	)
	(gr_line
		(start 13.970762 -169.497502)
		(end 14.121638 -169.71264)
		(stroke
			(width 0.08255)
			(type default)
		)
		(layer "In2.Cu")
	)
	(gr_line
		(start 13.993368 -214.892636)
		(end 14.208252 -214.742014)
		(stroke
			(width 0.08255)
			(type default)
		)
		(layer "In2.Cu")
	)
	(gr_line
		(start 14.044168 -471.744548)
		(end 14.050518 -471.780616)
		(stroke
			(width 0.08255)
			(type default)
		)
		(layer "In2.Cu")
	)
	(gr_line
		(start 14.050518 -471.780616)
		(end 14.0716 -471.810842)
		(stroke
			(width 0.08255)
			(type default)
		)
		(layer "In2.Cu")
	)
	(gr_line
		(start 14.068298 -169.150792)
		(end 14.850364 -169.288714)
		(stroke
			(width 0.08255)
			(type default)
		)
		(layer "In2.Cu")
	)
	(gr_line
		(start 14.109192 -461.512666)
		(end 14.115542 -461.548734)
		(stroke
			(width 0.08255)
			(type default)
		)
		(layer "In2.Cu")
	)
	(gr_line
		(start 14.114272 -212.144356)
		(end 14.115288 -212.13826)
		(stroke
			(width 0.08255)
			(type default)
		)
		(layer "In2.Cu")
	)
	(gr_line
		(start 14.115542 -461.548734)
		(end 14.136624 -461.57896)
		(stroke
			(width 0.08255)
			(type default)
		)
		(layer "In2.Cu")
	)
	(gr_line
		(start 14.121638 -169.71264)
		(end 14.609318 -169.798746)
		(stroke
			(width 0.08255)
			(type default)
		)
		(layer "In2.Cu")
	)
	(gr_line
		(start 14.122146 -212.099398)
		(end 14.258798 -211.324444)
		(stroke
			(width 0.08255)
			(type default)
		)
		(layer "In2.Cu")
	)
	(gr_line
		(start 14.140688 -140.596874)
		(end 14.144244 -140.576046)
		(stroke
			(width 0.08255)
			(type default)
		)
		(layer "In2.Cu")
	)
	(gr_line
		(start 14.140688 -140.59662)
		(end 14.140688 -140.597382)
		(stroke
			(width 0.08255)
			(type default)
		)
		(layer "In2.Cu")
	)
	(gr_line
		(start 14.140688 -140.555472)
		(end 14.144244 -140.576046)
		(stroke
			(width 0.08255)
			(type default)
		)
		(layer "In2.Cu")
	)
	(gr_line
		(start 14.141704 -214.036656)
		(end 14.157452 -213.947502)
		(stroke
			(width 0.08255)
			(type default)
		)
		(layer "In2.Cu")
	)
	(gr_line
		(start 14.143736 -214.039704)
		(end 14.294358 -214.254334)
		(stroke
			(width 0.08255)
			(type default)
		)
		(layer "In2.Cu")
	)
	(gr_line
		(start 14.15796 -196.292724)
		(end 14.176248 -196.280024)
		(stroke
			(width 0.08255)
			(type default)
		)
		(layer "In2.Cu")
	)
	(gr_line
		(start 14.176248 -196.280024)
		(end 14.188948 -196.261736)
		(stroke
			(width 0.08255)
			(type default)
		)
		(layer "In2.Cu")
	)
	(gr_line
		(start 14.208252 -214.742014)
		(end 14.294358 -214.254334)
		(stroke
			(width 0.08255)
			(type default)
		)
		(layer "In2.Cu")
	)
	(gr_line
		(start 14.214094 -205.867254)
		(end 14.220444 -205.83144)
		(stroke
			(width 0.08255)
			(type default)
		)
		(layer "In2.Cu")
	)
	(gr_line
		(start 14.220444 -205.83144)
		(end 14.241526 -205.801214)
		(stroke
			(width 0.08255)
			(type default)
		)
		(layer "In2.Cu")
	)
	(gr_line
		(start 14.230604 -213.54669)
		(end 14.445488 -213.396322)
		(stroke
			(width 0.08255)
			(type default)
		)
		(layer "In2.Cu")
	)
	(gr_line
		(start 14.261084 -342.37676)
		(end 14.30655 -342.118188)
		(stroke
			(width 0.08255)
			(type default)
		)
		(layer "In2.Cu")
	)
	(gr_line
		(start 14.261084 -342.37676)
		(end 14.545056 -342.782398)
		(stroke
			(width 0.08255)
			(type default)
		)
		(layer "In2.Cu")
	)
	(gr_line
		(start 14.381226 -212.693758)
		(end 14.531594 -212.908642)
		(stroke
			(width 0.08255)
			(type default)
		)
		(layer "In2.Cu")
	)
	(gr_line
		(start 14.445488 -213.396322)
		(end 14.531594 -212.908642)
		(stroke
			(width 0.08255)
			(type default)
		)
		(layer "In2.Cu")
	)
	(gr_line
		(start 14.45895 -212.237574)
		(end 14.465046 -212.20303)
		(stroke
			(width 0.08255)
			(type default)
		)
		(layer "In2.Cu")
	)
	(gr_line
		(start 14.468094 -212.200998)
		(end 14.682978 -212.05063)
		(stroke
			(width 0.08255)
			(type default)
		)
		(layer "In2.Cu")
	)
	(gr_line
		(start 14.47165 -307.826156)
		(end 14.478 -307.790088)
		(stroke
			(width 0.08255)
			(type default)
		)
		(layer "In2.Cu")
	)
	(gr_line
		(start 14.478 -307.790088)
		(end 14.499082 -307.759862)
		(stroke
			(width 0.08255)
			(type default)
		)
		(layer "In2.Cu")
	)
	(gr_line
		(start 14.53261 -293.579804)
		(end 14.557248 -293.563802)
		(stroke
			(width 0.08255)
			(type default)
		)
		(layer "In2.Cu")
	)
	(gr_line
		(start 14.545056 -342.782398)
		(end 14.803628 -342.828118)
		(stroke
			(width 0.08255)
			(type default)
		)
		(layer "In2.Cu")
	)
	(gr_line
		(start 14.557248 -293.563802)
		(end 14.573504 -293.540688)
		(stroke
			(width 0.08255)
			(type default)
		)
		(layer "In2.Cu")
	)
	(gr_line
		(start 14.575282 -236.04982)
		(end 14.596364 -236.080046)
		(stroke
			(width 0.08255)
			(type default)
		)
		(layer "In2.Cu")
	)
	(gr_line
		(start 14.585696 -217.096848)
		(end 14.722348 -216.321132)
		(stroke
			(width 0.08255)
			(type default)
		)
		(layer "In2.Cu")
	)
	(gr_line
		(start 14.596364 -236.080046)
		(end 14.602714 -236.116114)
		(stroke
			(width 0.08255)
			(type default)
		)
		(layer "In2.Cu")
	)
	(gr_line
		(start 14.609318 -169.798746)
		(end 14.824202 -169.648124)
		(stroke
			(width 0.08255)
			(type default)
		)
		(layer "In2.Cu")
	)
	(gr_line
		(start 14.618462 -211.347812)
		(end 14.76883 -211.56295)
		(stroke
			(width 0.08255)
			(type default)
		)
		(layer "In2.Cu")
	)
	(gr_line
		(start 14.62278 -341.945976)
		(end 15.074138 -342.590374)
		(stroke
			(width 0.08255)
			(type default)
		)
		(layer "In2.Cu")
	)
	(gr_line
		(start 14.682978 -212.05063)
		(end 14.76883 -211.56295)
		(stroke
			(width 0.08255)
			(type default)
		)
		(layer "In2.Cu")
	)
	(gr_line
		(start 14.736318 -218.201494)
		(end 14.7574 -218.171268)
		(stroke
			(width 0.08255)
			(type default)
		)
		(layer "In2.Cu")
	)
	(gr_line
		(start 14.7574 -218.171268)
		(end 14.76375 -218.1352)
		(stroke
			(width 0.08255)
			(type default)
		)
		(layer "In2.Cu")
	)
	(gr_line
		(start 14.822932 -215.752426)
		(end 14.959584 -214.977218)
		(stroke
			(width 0.08255)
			(type default)
		)
		(layer "In2.Cu")
	)
	(gr_line
		(start 14.860016 -290.682426)
		(end 14.878304 -290.669726)
		(stroke
			(width 0.08255)
			(type default)
		)
		(layer "In2.Cu")
	)
	(gr_line
		(start 14.878304 -290.669726)
		(end 14.891004 -290.651438)
		(stroke
			(width 0.08255)
			(type default)
		)
		(layer "In2.Cu")
	)
	(gr_line
		(start 14.892274 -404.927308)
		(end 14.912848 -404.923752)
		(stroke
			(width 0.08255)
			(type default)
		)
		(layer "In2.Cu")
	)
	(gr_line
		(start 14.899386 -352.318574)
		(end 14.920468 -352.3488)
		(stroke
			(width 0.08255)
			(type default)
		)
		(layer "In2.Cu")
	)
	(gr_line
		(start 14.906498 -471.323924)
		(end 14.912848 -471.359738)
		(stroke
			(width 0.08255)
			(type default)
		)
		(layer "In2.Cu")
	)
	(gr_line
		(start 14.912848 -471.359738)
		(end 14.93393 -471.389964)
		(stroke
			(width 0.08255)
			(type default)
		)
		(layer "In2.Cu")
	)
	(gr_line
		(start 14.912848 -404.923752)
		(end 14.933422 -404.927308)
		(stroke
			(width 0.08255)
			(type default)
		)
		(layer "In2.Cu")
	)
	(gr_line
		(start 14.920468 -352.3488)
		(end 14.926818 -352.384868)
		(stroke
			(width 0.08255)
			(type default)
		)
		(layer "In2.Cu")
	)
	(gr_line
		(start 14.930882 -354.457508)
		(end 15.064232 -355.214174)
		(stroke
			(width 0.08255)
			(type default)
		)
		(layer "In2.Cu")
	)
	(gr_line
		(start 14.93139 -217.198194)
		(end 15.146528 -217.047826)
		(stroke
			(width 0.08255)
			(type default)
		)
		(layer "In2.Cu")
	)
	(gr_line
		(start 14.983968 -378.174758)
		(end 14.990318 -378.210826)
		(stroke
			(width 0.08255)
			(type default)
		)
		(layer "In2.Cu")
	)
	(gr_line
		(start 14.990318 -378.210826)
		(end 15.0114 -378.241052)
		(stroke
			(width 0.08255)
			(type default)
		)
		(layer "In2.Cu")
	)
	(gr_line
		(start 15.035276 -459.352142)
		(end 15.041626 -459.38821)
		(stroke
			(width 0.08255)
			(type default)
		)
		(layer "In2.Cu")
	)
	(gr_line
		(start 15.041626 -459.38821)
		(end 15.062708 -459.418436)
		(stroke
			(width 0.08255)
			(type default)
		)
		(layer "In2.Cu")
	)
	(gr_line
		(start 15.060422 -214.405464)
		(end 15.19682 -213.63178)
		(stroke
			(width 0.08255)
			(type default)
		)
		(layer "In2.Cu")
	)
	(gr_line
		(start 15.082012 -216.345008)
		(end 15.23238 -216.560146)
		(stroke
			(width 0.08255)
			(type default)
		)
		(layer "In2.Cu")
	)
	(gr_line
		(start 15.108174 -140.871194)
		(end 15.11173 -140.850366)
		(stroke
			(width 0.08255)
			(type default)
		)
		(layer "In2.Cu")
	)
	(gr_line
		(start 15.108174 -140.87094)
		(end 15.108174 -140.871702)
		(stroke
			(width 0.08255)
			(type default)
		)
		(layer "In2.Cu")
	)
	(gr_line
		(start 15.108174 -140.829792)
		(end 15.11173 -140.850366)
		(stroke
			(width 0.08255)
			(type default)
		)
		(layer "In2.Cu")
	)
	(gr_line
		(start 15.116302 -294.703246)
		(end 15.13459 -294.690292)
		(stroke
			(width 0.08255)
			(type default)
		)
		(layer "In2.Cu")
	)
	(gr_line
		(start 15.13459 -294.690292)
		(end 15.14729 -294.672004)
		(stroke
			(width 0.08255)
			(type default)
		)
		(layer "In2.Cu")
	)
	(gr_line
		(start 15.146528 -217.047826)
		(end 15.23238 -216.560146)
		(stroke
			(width 0.08255)
			(type default)
		)
		(layer "In2.Cu")
	)
	(gr_line
		(start 15.164308 -355.782372)
		(end 15.297658 -356.539292)
		(stroke
			(width 0.08255)
			(type default)
		)
		(layer "In2.Cu")
	)
	(gr_line
		(start 15.168626 -215.852756)
		(end 15.383764 -215.702134)
		(stroke
			(width 0.08255)
			(type default)
		)
		(layer "In2.Cu")
	)
	(gr_line
		(start 15.171166 -206.151226)
		(end 15.177516 -206.115158)
		(stroke
			(width 0.08255)
			(type default)
		)
		(layer "In2.Cu")
	)
	(gr_line
		(start 15.173706 -305.145694)
		(end 15.186406 -305.127406)
		(stroke
			(width 0.08255)
			(type default)
		)
		(layer "In2.Cu")
	)
	(gr_line
		(start 15.177516 -206.115158)
		(end 15.198598 -206.084932)
		(stroke
			(width 0.08255)
			(type default)
		)
		(layer "In2.Cu")
	)
	(gr_line
		(start 15.186406 -305.127406)
		(end 15.204694 -305.114706)
		(stroke
			(width 0.08255)
			(type default)
		)
		(layer "In2.Cu")
	)
	(gr_line
		(start 15.202916 -254.138176)
		(end 15.209266 -254.174244)
		(stroke
			(width 0.08255)
			(type default)
		)
		(layer "In2.Cu")
	)
	(gr_line
		(start 15.209266 -254.174244)
		(end 15.230348 -254.20447)
		(stroke
			(width 0.08255)
			(type default)
		)
		(layer "In2.Cu")
	)
	(gr_line
		(start 15.275814 -405.929084)
		(end 15.296388 -405.925528)
		(stroke
			(width 0.08255)
			(type default)
		)
		(layer "In2.Cu")
	)
	(gr_line
		(start 15.27683 -354.355908)
		(end 15.479776 -354.498148)
		(stroke
			(width 0.08255)
			(type default)
		)
		(layer "In2.Cu")
	)
	(gr_line
		(start 15.296388 -405.925528)
		(end 15.316962 -405.929084)
		(stroke
			(width 0.08255)
			(type default)
		)
		(layer "In2.Cu")
	)
	(gr_line
		(start 15.297912 -213.05901)
		(end 15.434056 -212.287612)
		(stroke
			(width 0.08255)
			(type default)
		)
		(layer "In2.Cu")
	)
	(gr_line
		(start 15.316454 -169.734738)
		(end 15.46733 -169.949876)
		(stroke
			(width 0.08255)
			(type default)
		)
		(layer "In2.Cu")
	)
	(gr_line
		(start 15.319248 -214.999316)
		(end 15.46987 -215.214454)
		(stroke
			(width 0.08255)
			(type default)
		)
		(layer "In2.Cu")
	)
	(gr_line
		(start 15.383764 -215.702134)
		(end 15.46987 -215.214454)
		(stroke
			(width 0.08255)
			(type default)
		)
		(layer "In2.Cu")
	)
	(gr_line
		(start 15.393162 -308.1274)
		(end 15.399512 -308.091332)
		(stroke
			(width 0.08255)
			(type default)
		)
		(layer "In2.Cu")
	)
	(gr_line
		(start 15.398242 -357.109014)
		(end 15.404592 -357.145082)
		(stroke
			(width 0.08255)
			(type default)
		)
		(layer "In2.Cu")
	)
	(gr_line
		(start 15.399512 -308.091332)
		(end 15.420594 -308.061106)
		(stroke
			(width 0.08255)
			(type default)
		)
		(layer "In2.Cu")
	)
	(gr_line
		(start 15.404592 -357.145082)
		(end 15.425674 -357.175308)
		(stroke
			(width 0.08255)
			(type default)
		)
		(layer "In2.Cu")
	)
	(gr_line
		(start 15.406116 -214.507064)
		(end 15.621 -214.356442)
		(stroke
			(width 0.08255)
			(type default)
		)
		(layer "In2.Cu")
	)
	(gr_line
		(start 15.413228 -169.387774)
		(end 16.196818 -169.52595)
		(stroke
			(width 0.08255)
			(type default)
		)
		(layer "In2.Cu")
	)
	(gr_line
		(start 15.423642 -355.189282)
		(end 15.565628 -354.986082)
		(stroke
			(width 0.08255)
			(type default)
		)
		(layer "In2.Cu")
	)
	(gr_line
		(start 15.46733 -169.949876)
		(end 15.95501 -170.035982)
		(stroke
			(width 0.08255)
			(type default)
		)
		(layer "In2.Cu")
	)
	(gr_line
		(start 15.472664 -343.779602)
		(end 15.48511 -343.797636)
		(stroke
			(width 0.08255)
			(type default)
		)
		(layer "In2.Cu")
	)
	(gr_line
		(start 15.479776 -354.498148)
		(end 15.565628 -354.986082)
		(stroke
			(width 0.08255)
			(type default)
		)
		(layer "In2.Cu")
	)
	(gr_line
		(start 15.48511 -343.797636)
		(end 15.503144 -343.810336)
		(stroke
			(width 0.08255)
			(type default)
		)
		(layer "In2.Cu")
	)
	(gr_line
		(start 15.510256 -355.681788)
		(end 15.713456 -355.824028)
		(stroke
			(width 0.08255)
			(type default)
		)
		(layer "In2.Cu")
	)
	(gr_line
		(start 15.556484 -213.653624)
		(end 15.707106 -213.868762)
		(stroke
			(width 0.08255)
			(type default)
		)
		(layer "In2.Cu")
	)
	(gr_line
		(start 15.621 -214.356442)
		(end 15.707106 -213.868762)
		(stroke
			(width 0.08255)
			(type default)
		)
		(layer "In2.Cu")
	)
	(gr_line
		(start 15.638272 -244.037612)
		(end 15.64386 -244.0686)
		(stroke
			(width 0.08255)
			(type default)
		)
		(layer "In2.Cu")
	)
	(gr_line
		(start 15.643352 -213.161118)
		(end 15.858236 -213.010496)
		(stroke
			(width 0.08255)
			(type default)
		)
		(layer "In2.Cu")
	)
	(gr_line
		(start 15.64386 -244.0686)
		(end 15.660624 -244.094254)
		(stroke
			(width 0.08255)
			(type default)
		)
		(layer "In2.Cu")
	)
	(gr_line
		(start 15.657322 -356.515162)
		(end 15.799308 -356.311962)
		(stroke
			(width 0.08255)
			(type default)
		)
		(layer "In2.Cu")
	)
	(gr_line
		(start 15.713456 -355.824028)
		(end 15.799308 -356.311962)
		(stroke
			(width 0.08255)
			(type default)
		)
		(layer "In2.Cu")
	)
	(gr_line
		(start 15.79372 -212.308186)
		(end 15.944342 -212.522816)
		(stroke
			(width 0.08255)
			(type default)
		)
		(layer "In2.Cu")
	)
	(gr_line
		(start 15.84071 -359.963212)
		(end 15.85341 -359.9815)
		(stroke
			(width 0.08255)
			(type default)
		)
		(layer "In2.Cu")
	)
	(gr_line
		(start 15.85341 -359.9815)
		(end 15.871698 -359.9942)
		(stroke
			(width 0.08255)
			(type default)
		)
		(layer "In2.Cu")
	)
	(gr_line
		(start 15.858236 -213.010496)
		(end 15.944342 -212.522816)
		(stroke
			(width 0.08255)
			(type default)
		)
		(layer "In2.Cu")
	)
	(gr_line
		(start 15.910052 -377.874022)
		(end 15.916402 -377.909836)
		(stroke
			(width 0.08255)
			(type default)
		)
		(layer "In2.Cu")
	)
	(gr_line
		(start 15.916402 -377.909836)
		(end 15.937484 -377.940062)
		(stroke
			(width 0.08255)
			(type default)
		)
		(layer "In2.Cu")
	)
	(gr_line
		(start 15.922752 -305.726338)
		(end 15.935452 -305.70805)
		(stroke
			(width 0.08255)
			(type default)
		)
		(layer "In2.Cu")
	)
	(gr_line
		(start 15.935452 -305.70805)
		(end 15.95374 -305.69535)
		(stroke
			(width 0.08255)
			(type default)
		)
		(layer "In2.Cu")
	)
	(gr_line
		(start 15.95501 -170.035982)
		(end 16.169894 -169.88536)
		(stroke
			(width 0.08255)
			(type default)
		)
		(layer "In2.Cu")
	)
	(gr_line
		(start 16.12519 -140.777214)
		(end 16.128746 -140.756386)
		(stroke
			(width 0.08255)
			(type default)
		)
		(layer "In2.Cu")
	)
	(gr_line
		(start 16.12519 -140.77696)
		(end 16.12519 -140.777722)
		(stroke
			(width 0.08255)
			(type default)
		)
		(layer "In2.Cu")
	)
	(gr_line
		(start 16.12519 -140.735812)
		(end 16.128746 -140.756386)
		(stroke
			(width 0.08255)
			(type default)
		)
		(layer "In2.Cu")
	)
	(gr_line
		(start 16.26362 -308.513734)
		(end 16.26997 -308.477666)
		(stroke
			(width 0.08255)
			(type default)
		)
		(layer "In2.Cu")
	)
	(gr_line
		(start 16.26997 -308.477666)
		(end 16.291052 -308.44744)
		(stroke
			(width 0.08255)
			(type default)
		)
		(layer "In2.Cu")
	)
	(gr_line
		(start 16.362934 -344.412062)
		(end 16.397224 -344.436192)
		(stroke
			(width 0.08255)
			(type default)
		)
		(layer "In2.Cu")
	)
	(gr_line
		(start 16.397224 -344.436192)
		(end 16.436848 -344.442796)
		(stroke
			(width 0.08255)
			(type default)
		)
		(layer "In2.Cu")
	)
	(gr_line
		(start 16.546068 -358.775)
		(end 16.558768 -358.793288)
		(stroke
			(width 0.08255)
			(type default)
		)
		(layer "In2.Cu")
	)
	(gr_line
		(start 16.558768 -358.793288)
		(end 16.577056 -358.806242)
		(stroke
			(width 0.08255)
			(type default)
		)
		(layer "In2.Cu")
	)
	(gr_line
		(start 16.583406 -205.767178)
		(end 16.589756 -205.73111)
		(stroke
			(width 0.08255)
			(type default)
		)
		(layer "In2.Cu")
	)
	(gr_line
		(start 16.589756 -205.73111)
		(end 16.610838 -205.700884)
		(stroke
			(width 0.08255)
			(type default)
		)
		(layer "In2.Cu")
	)
	(gr_line
		(start 16.6243 -306.342288)
		(end 16.637 -306.324)
		(stroke
			(width 0.08255)
			(type default)
		)
		(layer "In2.Cu")
	)
	(gr_line
		(start 16.637 -306.324)
		(end 16.655288 -306.3113)
		(stroke
			(width 0.08255)
			(type default)
		)
		(layer "In2.Cu")
	)
	(gr_line
		(start 16.66367 -80.612996)
		(end 16.67002 -80.576928)
		(stroke
			(width 0.08255)
			(type default)
		)
		(layer "In2.Cu")
	)
	(gr_line
		(start 16.67002 -80.576928)
		(end 16.691102 -80.546702)
		(stroke
			(width 0.08255)
			(type default)
		)
		(layer "In2.Cu")
	)
	(gr_line
		(start 16.698214 -200.624186)
		(end 16.710914 -200.605898)
		(stroke
			(width 0.08255)
			(type default)
		)
		(layer "In2.Cu")
	)
	(gr_line
		(start 16.710914 -200.605898)
		(end 16.729202 -200.593198)
		(stroke
			(width 0.08255)
			(type default)
		)
		(layer "In2.Cu")
	)
	(gr_line
		(start 16.829786 -256.054098)
		(end 16.860012 -256.07518)
		(stroke
			(width 0.08255)
			(type default)
		)
		(layer "In2.Cu")
	)
	(gr_line
		(start 16.860012 -256.07518)
		(end 16.895826 -256.08153)
		(stroke
			(width 0.08255)
			(type default)
		)
		(layer "In2.Cu")
	)
	(gr_line
		(start 16.864838 -377.574048)
		(end 16.871188 -377.610116)
		(stroke
			(width 0.08255)
			(type default)
		)
		(layer "In2.Cu")
	)
	(gr_line
		(start 16.871188 -377.610116)
		(end 16.89227 -377.640342)
		(stroke
			(width 0.08255)
			(type default)
		)
		(layer "In2.Cu")
	)
	(gr_line
		(start 16.876776 -462.009236)
		(end 16.889476 -462.027524)
		(stroke
			(width 0.08255)
			(type default)
		)
		(layer "In2.Cu")
	)
	(gr_line
		(start 16.887698 -344.520012)
		(end 17.040352 -344.733626)
		(stroke
			(width 0.08255)
			(type default)
		)
		(layer "In2.Cu")
	)
	(gr_line
		(start 16.889476 -462.027524)
		(end 16.907764 -462.040224)
		(stroke
			(width 0.08255)
			(type default)
		)
		(layer "In2.Cu")
	)
	(gr_line
		(start 16.983202 -381.057658)
		(end 16.995902 -381.075946)
		(stroke
			(width 0.08255)
			(type default)
		)
		(layer "In2.Cu")
	)
	(gr_line
		(start 16.984218 -344.173048)
		(end 17.764252 -344.302588)
		(stroke
			(width 0.08255)
			(type default)
		)
		(layer "In2.Cu")
	)
	(gr_line
		(start 16.995902 -381.075946)
		(end 17.01419 -381.088646)
		(stroke
			(width 0.08255)
			(type default)
		)
		(layer "In2.Cu")
	)
	(gr_line
		(start 17.040352 -344.733626)
		(end 17.529048 -344.814906)
		(stroke
			(width 0.08255)
			(type default)
		)
		(layer "In2.Cu")
	)
	(gr_line
		(start 17.205706 -246.473218)
		(end 17.22501 -246.502936)
		(stroke
			(width 0.08255)
			(type default)
		)
		(layer "In2.Cu")
	)
	(gr_line
		(start 17.22247 -359.2576)
		(end 17.252696 -359.278682)
		(stroke
			(width 0.08255)
			(type default)
		)
		(layer "In2.Cu")
	)
	(gr_line
		(start 17.22501 -246.502936)
		(end 17.254728 -246.52224)
		(stroke
			(width 0.08255)
			(type default)
		)
		(layer "In2.Cu")
	)
	(gr_line
		(start 17.252696 -359.278682)
		(end 17.288764 -359.285032)
		(stroke
			(width 0.08255)
			(type default)
		)
		(layer "In2.Cu")
	)
	(gr_line
		(start 17.314418 -349.259398)
		(end 17.327118 -349.277686)
		(stroke
			(width 0.08255)
			(type default)
		)
		(layer "In2.Cu")
	)
	(gr_line
		(start 17.327118 -349.277686)
		(end 17.345406 -349.290386)
		(stroke
			(width 0.08255)
			(type default)
		)
		(layer "In2.Cu")
	)
	(gr_line
		(start 17.329912 -306.963572)
		(end 17.342612 -306.945284)
		(stroke
			(width 0.08255)
			(type default)
		)
		(layer "In2.Cu")
	)
	(gr_line
		(start 17.342612 -306.945284)
		(end 17.3609 -306.932584)
		(stroke
			(width 0.08255)
			(type default)
		)
		(layer "In2.Cu")
	)
	(gr_line
		(start 17.4371 -201.237342)
		(end 17.4498 -201.219054)
		(stroke
			(width 0.08255)
			(type default)
		)
		(layer "In2.Cu")
	)
	(gr_line
		(start 17.4498 -201.219054)
		(end 17.468088 -201.206354)
		(stroke
			(width 0.08255)
			(type default)
		)
		(layer "In2.Cu")
	)
	(gr_line
		(start 17.529048 -344.814906)
		(end 17.742662 -344.661998)
		(stroke
			(width 0.08255)
			(type default)
		)
		(layer "In2.Cu")
	)
	(gr_line
		(start 17.573244 -380.276608)
		(end 17.585944 -380.294896)
		(stroke
			(width 0.08255)
			(type default)
		)
		(layer "In2.Cu")
	)
	(gr_line
		(start 17.585944 -380.294896)
		(end 17.604232 -380.307596)
		(stroke
			(width 0.08255)
			(type default)
		)
		(layer "In2.Cu")
	)
	(gr_line
		(start 17.590262 -81.220056)
		(end 17.591532 -81.223358)
		(stroke
			(width 0.08255)
			(type default)
		)
		(layer "In2.Cu")
	)
	(gr_line
		(start 17.590262 -81.220056)
		(end 17.60093 -81.204816)
		(stroke
			(width 0.08255)
			(type default)
		)
		(layer "In2.Cu")
	)
	(gr_line
		(start 17.708626 -178.65725)
		(end 17.744694 -178.6509)
		(stroke
			(width 0.08255)
			(type default)
		)
		(layer "In2.Cu")
	)
	(gr_line
		(start 17.744694 -178.6509)
		(end 17.77492 -178.629818)
		(stroke
			(width 0.08255)
			(type default)
		)
		(layer "In2.Cu")
	)
	(gr_line
		(start 17.8181 -349.621348)
		(end 18.462498 -350.072198)
		(stroke
			(width 0.08255)
			(type default)
		)
		(layer "In2.Cu")
	)
	(gr_line
		(start 17.903698 -283.39796)
		(end 17.921986 -283.38526)
		(stroke
			(width 0.08255)
			(type default)
		)
		(layer "In2.Cu")
	)
	(gr_line
		(start 17.920716 -462.749138)
		(end 17.951704 -462.770982)
		(stroke
			(width 0.08255)
			(type default)
		)
		(layer "In2.Cu")
	)
	(gr_line
		(start 17.921986 -283.38526)
		(end 17.934686 -283.366972)
		(stroke
			(width 0.08255)
			(type default)
		)
		(layer "In2.Cu")
	)
	(gr_line
		(start 17.951704 -462.770982)
		(end 17.990058 -462.77784)
		(stroke
			(width 0.08255)
			(type default)
		)
		(layer "In2.Cu")
	)
	(gr_line
		(start 17.991328 -349.305626)
		(end 18.250154 -349.26016)
		(stroke
			(width 0.08255)
			(type default)
		)
		(layer "In2.Cu")
	)
	(gr_line
		(start 18.108422 -475.923356)
		(end 18.121122 -475.941644)
		(stroke
			(width 0.08255)
			(type default)
		)
		(layer "In2.Cu")
	)
	(gr_line
		(start 18.117058 -201.917046)
		(end 18.129758 -201.898758)
		(stroke
			(width 0.08255)
			(type default)
		)
		(layer "In2.Cu")
	)
	(gr_line
		(start 18.121122 -475.941644)
		(end 18.13941 -475.954344)
		(stroke
			(width 0.08255)
			(type default)
		)
		(layer "In2.Cu")
	)
	(gr_line
		(start 18.129758 -201.898758)
		(end 18.148046 -201.886058)
		(stroke
			(width 0.08255)
			(type default)
		)
		(layer "In2.Cu")
	)
	(gr_line
		(start 18.162778 -379.454918)
		(end 18.175478 -379.473206)
		(stroke
			(width 0.08255)
			(type default)
		)
		(layer "In2.Cu")
	)
	(gr_line
		(start 18.175478 -379.473206)
		(end 18.193766 -379.485906)
		(stroke
			(width 0.08255)
			(type default)
		)
		(layer "In2.Cu")
	)
	(gr_line
		(start 18.250154 -349.26016)
		(end 18.655792 -349.544132)
		(stroke
			(width 0.08255)
			(type default)
		)
		(layer "In2.Cu")
	)
	(gr_line
		(start 18.378678 -170.272456)
		(end 18.401792 -170.27652)
		(stroke
			(width 0.08255)
			(type default)
		)
		(layer "In2.Cu")
	)
	(gr_line
		(start 18.401792 -170.27652)
		(end 18.423636 -170.272456)
		(stroke
			(width 0.08255)
			(type default)
		)
		(layer "In2.Cu")
	)
	(gr_line
		(start 18.410936 -355.234748)
		(end 18.423636 -355.253036)
		(stroke
			(width 0.08255)
			(type default)
		)
		(layer "In2.Cu")
	)
	(gr_line
		(start 18.423636 -355.253036)
		(end 18.441924 -355.265736)
		(stroke
			(width 0.08255)
			(type default)
		)
		(layer "In2.Cu")
	)
	(gr_line
		(start 18.486628 -81.983326)
		(end 18.493232 -81.945988)
		(stroke
			(width 0.08255)
			(type default)
		)
		(layer "In2.Cu")
	)
	(gr_line
		(start 18.493232 -81.945988)
		(end 18.514822 -81.915)
		(stroke
			(width 0.08255)
			(type default)
		)
		(layer "In2.Cu")
	)
	(gr_line
		(start 18.53311 -181.712108)
		(end 18.569178 -181.705758)
		(stroke
			(width 0.08255)
			(type default)
		)
		(layer "In2.Cu")
	)
	(gr_line
		(start 18.569178 -181.705758)
		(end 18.599404 -181.684676)
		(stroke
			(width 0.08255)
			(type default)
		)
		(layer "In2.Cu")
	)
	(gr_line
		(start 18.592546 -89.209626)
		(end 18.596102 -89.2302)
		(stroke
			(width 0.08255)
			(type default)
		)
		(layer "In2.Cu")
	)
	(gr_line
		(start 18.592546 -89.209626)
		(end 18.596102 -89.188798)
		(stroke
			(width 0.08255)
			(type default)
		)
		(layer "In2.Cu")
	)
	(gr_line
		(start 18.596102 -89.18829)
		(end 18.596102 -89.189052)
		(stroke
			(width 0.08255)
			(type default)
		)
		(layer "In2.Cu")
	)
	(gr_line
		(start 18.655792 -349.544132)
		(end 18.701512 -349.802704)
		(stroke
			(width 0.08255)
			(type default)
		)
		(layer "In2.Cu")
	)
	(gr_line
		(start 18.741898 -404.523448)
		(end 18.772124 -404.54453)
		(stroke
			(width 0.08255)
			(type default)
		)
		(layer "In2.Cu")
	)
	(gr_line
		(start 18.754852 -202.638914)
		(end 18.767552 -202.620626)
		(stroke
			(width 0.08255)
			(type default)
		)
		(layer "In2.Cu")
	)
	(gr_line
		(start 18.763742 -359.545382)
		(end 18.784316 -359.548938)
		(stroke
			(width 0.08255)
			(type default)
		)
		(layer "In2.Cu")
	)
	(gr_line
		(start 18.767552 -202.620626)
		(end 18.78584 -202.607926)
		(stroke
			(width 0.08255)
			(type default)
		)
		(layer "In2.Cu")
	)
	(gr_line
		(start 18.772124 -404.54453)
		(end 18.808192 -404.55088)
		(stroke
			(width 0.08255)
			(type default)
		)
		(layer "In2.Cu")
	)
	(gr_line
		(start 18.784316 -359.548938)
		(end 18.80489 -359.545382)
		(stroke
			(width 0.08255)
			(type default)
		)
		(layer "In2.Cu")
	)
	(gr_line
		(start 18.938494 -350.4057)
		(end 19.581876 -350.856042)
		(stroke
			(width 0.08255)
			(type default)
		)
		(layer "In2.Cu")
	)
	(gr_line
		(start 19.032982 -198.980044)
		(end 19.063208 -198.958962)
		(stroke
			(width 0.08255)
			(type default)
		)
		(layer "In2.Cu")
	)
	(gr_line
		(start 19.063208 -198.958962)
		(end 19.099276 -198.952612)
		(stroke
			(width 0.08255)
			(type default)
		)
		(layer "In2.Cu")
	)
	(gr_line
		(start 19.11096 -350.08947)
		(end 19.369532 -350.04375)
		(stroke
			(width 0.08255)
			(type default)
		)
		(layer "In2.Cu")
	)
	(gr_line
		(start 19.294348 -199.927718)
		(end 19.324574 -199.906636)
		(stroke
			(width 0.08255)
			(type default)
		)
		(layer "In2.Cu")
	)
	(gr_line
		(start 19.324574 -199.906636)
		(end 19.360388 -199.900286)
		(stroke
			(width 0.08255)
			(type default)
		)
		(layer "In2.Cu")
	)
	(gr_line
		(start 19.369532 -350.04375)
		(end 19.77517 -350.327976)
		(stroke
			(width 0.08255)
			(type default)
		)
		(layer "In2.Cu")
	)
	(gr_line
		(start 19.42465 -84.491068)
		(end 19.431 -84.455)
		(stroke
			(width 0.08255)
			(type default)
		)
		(layer "In2.Cu")
	)
	(gr_line
		(start 19.431 -84.455)
		(end 19.452082 -84.424774)
		(stroke
			(width 0.08255)
			(type default)
		)
		(layer "In2.Cu")
	)
	(gr_line
		(start 19.488658 -94.28988)
		(end 19.495008 -94.325694)
		(stroke
			(width 0.08255)
			(type default)
		)
		(layer "In2.Cu")
	)
	(gr_line
		(start 19.495008 -94.325694)
		(end 19.51609 -94.35592)
		(stroke
			(width 0.08255)
			(type default)
		)
		(layer "In2.Cu")
	)
	(gr_line
		(start 19.51355 -89.19718)
		(end 19.517106 -89.217754)
		(stroke
			(width 0.08255)
			(type default)
		)
		(layer "In2.Cu")
	)
	(gr_line
		(start 19.51355 -89.19718)
		(end 19.517106 -89.176352)
		(stroke
			(width 0.08255)
			(type default)
		)
		(layer "In2.Cu")
	)
	(gr_line
		(start 19.517106 -89.175844)
		(end 19.517106 -89.176606)
		(stroke
			(width 0.08255)
			(type default)
		)
		(layer "In2.Cu")
	)
	(gr_line
		(start 19.542506 -344.958416)
		(end 19.569176 -344.962988)
		(stroke
			(width 0.08255)
			(type default)
		)
		(layer "In2.Cu")
	)
	(gr_line
		(start 19.569176 -344.962988)
		(end 19.5961 -344.957146)
		(stroke
			(width 0.08255)
			(type default)
		)
		(layer "In2.Cu")
	)
	(gr_line
		(start 19.600418 -175.123602)
		(end 19.636486 -175.117252)
		(stroke
			(width 0.08255)
			(type default)
		)
		(layer "In2.Cu")
	)
	(gr_line
		(start 19.636486 -175.117252)
		(end 19.666712 -175.09617)
		(stroke
			(width 0.08255)
			(type default)
		)
		(layer "In2.Cu")
	)
	(gr_line
		(start 19.746722 -200.76668)
		(end 19.776948 -200.745598)
		(stroke
			(width 0.08255)
			(type default)
		)
		(layer "In2.Cu")
	)
	(gr_line
		(start 19.77517 -350.327976)
		(end 19.82089 -350.586294)
		(stroke
			(width 0.08255)
			(type default)
		)
		(layer "In2.Cu")
	)
	(gr_line
		(start 19.776948 -200.745598)
		(end 19.812762 -200.739248)
		(stroke
			(width 0.08255)
			(type default)
		)
		(layer "In2.Cu")
	)
	(gr_line
		(start 19.92249 -186.028584)
		(end 19.940778 -186.015884)
		(stroke
			(width 0.08255)
			(type default)
		)
		(layer "In2.Cu")
	)
	(gr_line
		(start 19.940778 -186.015884)
		(end 19.953478 -185.997596)
		(stroke
			(width 0.08255)
			(type default)
		)
		(layer "In2.Cu")
	)
	(gr_line
		(start 20.023328 -201.741532)
		(end 20.053554 -201.72045)
		(stroke
			(width 0.08255)
			(type default)
		)
		(layer "In2.Cu")
	)
	(gr_line
		(start 20.053554 -201.72045)
		(end 20.089622 -201.7141)
		(stroke
			(width 0.08255)
			(type default)
		)
		(layer "In2.Cu")
	)
	(gr_line
		(start 20.05711 -351.188782)
		(end 20.70227 -351.640648)
		(stroke
			(width 0.08255)
			(type default)
		)
		(layer "In2.Cu")
	)
	(gr_line
		(start 20.132802 -301.663608)
		(end 20.163028 -301.642526)
		(stroke
			(width 0.08255)
			(type default)
		)
		(layer "In2.Cu")
	)
	(gr_line
		(start 20.163028 -301.642526)
		(end 20.198842 -301.636176)
		(stroke
			(width 0.08255)
			(type default)
		)
		(layer "In2.Cu")
	)
	(gr_line
		(start 20.175728 -140.607796)
		(end 20.18411 -140.655802)
		(stroke
			(width 0.08255)
			(type default)
		)
		(layer "In2.Cu")
	)
	(gr_line
		(start 20.175728 -140.607796)
		(end 20.191222 -140.561568)
		(stroke
			(width 0.08255)
			(type default)
		)
		(layer "In2.Cu")
	)
	(gr_line
		(start 20.1803 -452.696072)
		(end 20.198588 -452.708772)
		(stroke
			(width 0.08255)
			(type default)
		)
		(layer "In2.Cu")
	)
	(gr_line
		(start 20.198588 -452.708772)
		(end 20.211288 -452.72706)
		(stroke
			(width 0.08255)
			(type default)
		)
		(layer "In2.Cu")
	)
	(gr_line
		(start 20.220432 -356.51059)
		(end 20.250658 -356.531672)
		(stroke
			(width 0.08255)
			(type default)
		)
		(layer "In2.Cu")
	)
	(gr_line
		(start 20.230592 -350.873314)
		(end 20.48891 -350.827594)
		(stroke
			(width 0.08255)
			(type default)
		)
		(layer "In2.Cu")
	)
	(gr_line
		(start 20.250658 -356.531672)
		(end 20.286472 -356.538022)
		(stroke
			(width 0.08255)
			(type default)
		)
		(layer "In2.Cu")
	)
	(gr_line
		(start 20.268184 -84.916518)
		(end 20.274534 -84.88045)
		(stroke
			(width 0.08255)
			(type default)
		)
		(layer "In2.Cu")
	)
	(gr_line
		(start 20.274534 -84.88045)
		(end 20.295616 -84.850224)
		(stroke
			(width 0.08255)
			(type default)
		)
		(layer "In2.Cu")
	)
	(gr_line
		(start 20.283424 -382.183386)
		(end 20.31365 -382.204468)
		(stroke
			(width 0.08255)
			(type default)
		)
		(layer "In2.Cu")
	)
	(gr_line
		(start 20.28444 -141.224508)
		(end 20.4216 -142.000986)
		(stroke
			(width 0.08255)
			(type default)
		)
		(layer "In2.Cu")
	)
	(gr_line
		(start 20.28825 -256.102612)
		(end 20.324064 -256.096262)
		(stroke
			(width 0.08255)
			(type default)
		)
		(layer "In2.Cu")
	)
	(gr_line
		(start 20.308062 -93.701616)
		(end 20.314412 -93.73743)
		(stroke
			(width 0.08255)
			(type default)
		)
		(layer "In2.Cu")
	)
	(gr_line
		(start 20.31365 -382.204468)
		(end 20.349464 -382.210818)
		(stroke
			(width 0.08255)
			(type default)
		)
		(layer "In2.Cu")
	)
	(gr_line
		(start 20.314412 -93.73743)
		(end 20.335494 -93.767656)
		(stroke
			(width 0.08255)
			(type default)
		)
		(layer "In2.Cu")
	)
	(gr_line
		(start 20.324064 -256.096262)
		(end 20.35429 -256.07518)
		(stroke
			(width 0.08255)
			(type default)
		)
		(layer "In2.Cu")
	)
	(gr_line
		(start 20.407122 -403.861016)
		(end 20.437348 -403.882098)
		(stroke
			(width 0.08255)
			(type default)
		)
		(layer "In2.Cu")
	)
	(gr_line
		(start 20.43176 -302.55972)
		(end 20.461986 -302.538638)
		(stroke
			(width 0.08255)
			(type default)
		)
		(layer "In2.Cu")
	)
	(gr_line
		(start 20.437348 -403.882098)
		(end 20.473416 -403.888448)
		(stroke
			(width 0.08255)
			(type default)
		)
		(layer "In2.Cu")
	)
	(gr_line
		(start 20.454874 -89.155016)
		(end 20.45843 -89.175844)
		(stroke
			(width 0.08255)
			(type default)
		)
		(layer "In2.Cu")
	)
	(gr_line
		(start 20.454874 -89.155016)
		(end 20.45843 -89.13368)
		(stroke
			(width 0.08255)
			(type default)
		)
		(layer "In2.Cu")
	)
	(gr_line
		(start 20.45843 -89.17559)
		(end 20.45843 -89.176352)
		(stroke
			(width 0.08255)
			(type default)
		)
		(layer "In2.Cu")
	)
	(gr_line
		(start 20.461986 -302.538638)
		(end 20.4978 -302.532288)
		(stroke
			(width 0.08255)
			(type default)
		)
		(layer "In2.Cu")
	)
	(gr_line
		(start 20.48891 -350.827594)
		(end 20.894802 -351.11182)
		(stroke
			(width 0.08255)
			(type default)
		)
		(layer "In2.Cu")
	)
	(gr_line
		(start 20.517358 -463.22361)
		(end 20.537932 -463.227166)
		(stroke
			(width 0.08255)
			(type default)
		)
		(layer "In2.Cu")
	)
	(gr_line
		(start 20.52193 -142.5702)
		(end 20.65909 -143.346678)
		(stroke
			(width 0.08255)
			(type default)
		)
		(layer "In2.Cu")
	)
	(gr_line
		(start 20.537932 -463.227166)
		(end 20.558506 -463.22361)
		(stroke
			(width 0.08255)
			(type default)
		)
		(layer "In2.Cu")
	)
	(gr_line
		(start 20.581112 -139.392406)
		(end 20.581874 -139.389612)
		(stroke
			(width 0.08255)
			(type default)
		)
		(layer "In2.Cu")
	)
	(gr_line
		(start 20.581874 -139.389612)
		(end 20.583652 -139.386564)
		(stroke
			(width 0.08255)
			(type default)
		)
		(layer "In2.Cu")
	)
	(gr_line
		(start 20.630642 -141.124178)
		(end 20.845526 -141.2748)
		(stroke
			(width 0.08255)
			(type default)
		)
		(layer "In2.Cu")
	)
	(gr_line
		(start 20.646644 -276.491446)
		(end 20.66544 -276.478238)
		(stroke
			(width 0.08255)
			(type default)
		)
		(layer "In2.Cu")
	)
	(gr_line
		(start 20.66544 -276.478238)
		(end 20.67814 -276.460204)
		(stroke
			(width 0.08255)
			(type default)
		)
		(layer "In2.Cu")
	)
	(gr_line
		(start 20.666456 -381.217424)
		(end 20.696682 -381.238506)
		(stroke
			(width 0.08255)
			(type default)
		)
		(layer "In2.Cu")
	)
	(gr_line
		(start 20.696682 -381.238506)
		(end 20.732496 -381.244856)
		(stroke
			(width 0.08255)
			(type default)
		)
		(layer "In2.Cu")
	)
	(gr_line
		(start 20.781264 -141.977618)
		(end 20.931632 -141.762734)
		(stroke
			(width 0.08255)
			(type default)
		)
		(layer "In2.Cu")
	)
	(gr_line
		(start 20.786598 -303.41824)
		(end 20.816824 -303.397158)
		(stroke
			(width 0.08255)
			(type default)
		)
		(layer "In2.Cu")
	)
	(gr_line
		(start 20.816824 -303.397158)
		(end 20.852892 -303.390808)
		(stroke
			(width 0.08255)
			(type default)
		)
		(layer "In2.Cu")
	)
	(gr_line
		(start 20.845526 -141.2748)
		(end 20.931632 -141.762734)
		(stroke
			(width 0.08255)
			(type default)
		)
		(layer "In2.Cu")
	)
	(gr_line
		(start 20.868132 -142.46987)
		(end 21.083016 -142.620492)
		(stroke
			(width 0.08255)
			(type default)
		)
		(layer "In2.Cu")
	)
	(gr_line
		(start 20.89023 -248.88317)
		(end 20.910042 -248.896124)
		(stroke
			(width 0.08255)
			(type default)
		)
		(layer "In2.Cu")
	)
	(gr_line
		(start 20.894802 -351.11182)
		(end 20.940268 -351.370138)
		(stroke
			(width 0.08255)
			(type default)
		)
		(layer "In2.Cu")
	)
	(gr_line
		(start 20.900644 -481.56368)
		(end 20.913344 -481.581968)
		(stroke
			(width 0.08255)
			(type default)
		)
		(layer "In2.Cu")
	)
	(gr_line
		(start 20.910042 -248.896124)
		(end 20.933664 -248.901204)
		(stroke
			(width 0.08255)
			(type default)
		)
		(layer "In2.Cu")
	)
	(gr_line
		(start 20.913344 -481.581968)
		(end 20.931632 -481.594668)
		(stroke
			(width 0.08255)
			(type default)
		)
		(layer "In2.Cu")
	)
	(gr_line
		(start 20.95627 -145.030698)
		(end 20.96262 -145.066512)
		(stroke
			(width 0.08255)
			(type default)
		)
		(layer "In2.Cu")
	)
	(gr_line
		(start 20.96262 -145.066512)
		(end 20.983702 -145.096738)
		(stroke
			(width 0.08255)
			(type default)
		)
		(layer "In2.Cu")
	)
	(gr_line
		(start 21.018754 -143.32331)
		(end 21.169122 -143.108426)
		(stroke
			(width 0.08255)
			(type default)
		)
		(layer "In2.Cu")
	)
	(gr_line
		(start 21.028406 -359.153206)
		(end 21.064474 -359.146856)
		(stroke
			(width 0.08255)
			(type default)
		)
		(layer "In2.Cu")
	)
	(gr_line
		(start 21.064474 -359.146856)
		(end 21.0947 -359.125774)
		(stroke
			(width 0.08255)
			(type default)
		)
		(layer "In2.Cu")
	)
	(gr_line
		(start 21.07565 -85.634068)
		(end 21.082 -85.598)
		(stroke
			(width 0.08255)
			(type default)
		)
		(layer "In2.Cu")
	)
	(gr_line
		(start 21.082 -85.598)
		(end 21.103082 -85.567774)
		(stroke
			(width 0.08255)
			(type default)
		)
		(layer "In2.Cu")
	)
	(gr_line
		(start 21.083016 -142.620492)
		(end 21.169122 -143.108426)
		(stroke
			(width 0.08255)
			(type default)
		)
		(layer "In2.Cu")
	)
	(gr_line
		(start 21.099018 -138.581892)
		(end 21.113496 -138.559286)
		(stroke
			(width 0.08255)
			(type default)
		)
		(layer "In2.Cu")
	)
	(gr_line
		(start 21.113496 -138.559286)
		(end 21.13534 -138.543792)
		(stroke
			(width 0.08255)
			(type default)
		)
		(layer "In2.Cu")
	)
	(gr_line
		(start 21.138642 -304.287682)
		(end 21.168868 -304.2666)
		(stroke
			(width 0.08255)
			(type default)
		)
		(layer "In2.Cu")
	)
	(gr_line
		(start 21.168868 -304.2666)
		(end 21.204682 -304.26025)
		(stroke
			(width 0.08255)
			(type default)
		)
		(layer "In2.Cu")
	)
	(gr_line
		(start 21.203666 -93.401134)
		(end 21.210016 -93.437202)
		(stroke
			(width 0.08255)
			(type default)
		)
		(layer "In2.Cu")
	)
	(gr_line
		(start 21.210016 -93.437202)
		(end 21.231098 -93.467428)
		(stroke
			(width 0.08255)
			(type default)
		)
		(layer "In2.Cu")
	)
	(gr_line
		(start 21.40077 -145.692114)
		(end 21.41347 -145.710402)
		(stroke
			(width 0.08255)
			(type default)
		)
		(layer "In2.Cu")
	)
	(gr_line
		(start 21.403564 -89.239598)
		(end 21.40712 -89.260172)
		(stroke
			(width 0.08255)
			(type default)
		)
		(layer "In2.Cu")
	)
	(gr_line
		(start 21.403564 -89.239598)
		(end 21.40712 -89.219786)
		(stroke
			(width 0.08255)
			(type default)
		)
		(layer "In2.Cu")
	)
	(gr_line
		(start 21.40712 -89.259918)
		(end 21.40712 -89.260172)
		(stroke
			(width 0.08255)
			(type default)
		)
		(layer "In2.Cu")
	)
	(gr_line
		(start 21.41347 -145.710402)
		(end 21.431758 -145.723102)
		(stroke
			(width 0.08255)
			(type default)
		)
		(layer "In2.Cu")
	)
	(gr_line
		(start 21.45919 -97.130362)
		(end 21.47189 -97.14865)
		(stroke
			(width 0.08255)
			(type default)
		)
		(layer "In2.Cu")
	)
	(gr_line
		(start 21.47189 -97.14865)
		(end 21.490178 -97.16135)
		(stroke
			(width 0.08255)
			(type default)
		)
		(layer "In2.Cu")
	)
	(gr_line
		(start 21.759926 -356.798118)
		(end 21.7805 -356.801674)
		(stroke
			(width 0.08255)
			(type default)
		)
		(layer "In2.Cu")
	)
	(gr_line
		(start 21.7805 -356.801674)
		(end 21.801074 -356.798118)
		(stroke
			(width 0.08255)
			(type default)
		)
		(layer "In2.Cu")
	)
	(gr_line
		(start 21.795994 -138.07567)
		(end 21.824696 -138.055096)
		(stroke
			(width 0.08255)
			(type default)
		)
		(layer "In2.Cu")
	)
	(gr_line
		(start 21.824696 -138.055096)
		(end 21.859748 -138.047984)
		(stroke
			(width 0.08255)
			(type default)
		)
		(layer "In2.Cu")
	)
	(gr_line
		(start 21.83765 -86.777068)
		(end 21.844 -86.741)
		(stroke
			(width 0.08255)
			(type default)
		)
		(layer "In2.Cu")
	)
	(gr_line
		(start 21.844 -86.741)
		(end 21.865082 -86.710774)
		(stroke
			(width 0.08255)
			(type default)
		)
		(layer "In2.Cu")
	)
	(gr_line
		(start 21.847302 -364.177834)
		(end 21.877528 -364.198916)
		(stroke
			(width 0.08255)
			(type default)
		)
		(layer "In2.Cu")
	)
	(gr_line
		(start 21.871686 -181.464204)
		(end 21.889974 -181.451504)
		(stroke
			(width 0.08255)
			(type default)
		)
		(layer "In2.Cu")
	)
	(gr_line
		(start 21.877528 -364.198916)
		(end 21.913596 -364.205266)
		(stroke
			(width 0.08255)
			(type default)
		)
		(layer "In2.Cu")
	)
	(gr_line
		(start 21.889974 -181.451504)
		(end 21.902674 -181.433216)
		(stroke
			(width 0.08255)
			(type default)
		)
		(layer "In2.Cu")
	)
	(gr_line
		(start 21.90242 -272.477992)
		(end 21.919692 -272.4658)
		(stroke
			(width 0.08255)
			(type default)
		)
		(layer "In2.Cu")
	)
	(gr_line
		(start 21.919692 -272.4658)
		(end 21.93163 -272.448782)
		(stroke
			(width 0.08255)
			(type default)
		)
		(layer "In2.Cu")
	)
	(gr_line
		(start 22.037294 -169.634916)
		(end 22.073108 -169.628566)
		(stroke
			(width 0.08255)
			(type default)
		)
		(layer "In2.Cu")
	)
	(gr_line
		(start 22.06244 -92.976192)
		(end 22.069044 -93.01353)
		(stroke
			(width 0.08255)
			(type default)
		)
		(layer "In2.Cu")
	)
	(gr_line
		(start 22.069044 -93.01353)
		(end 22.091396 -93.045534)
		(stroke
			(width 0.08255)
			(type default)
		)
		(layer "In2.Cu")
	)
	(gr_line
		(start 22.073108 -169.628566)
		(end 22.103334 -169.607484)
		(stroke
			(width 0.08255)
			(type default)
		)
		(layer "In2.Cu")
	)
	(gr_line
		(start 22.3393 -96.628712)
		(end 22.352 -96.647)
		(stroke
			(width 0.08255)
			(type default)
		)
		(layer "In2.Cu")
	)
	(gr_line
		(start 22.352 -96.647)
		(end 22.370288 -96.6597)
		(stroke
			(width 0.08255)
			(type default)
		)
		(layer "In2.Cu")
	)
	(gr_line
		(start 22.367494 -292.3794)
		(end 22.380194 -292.361112)
		(stroke
			(width 0.08255)
			(type default)
		)
		(layer "In2.Cu")
	)
	(gr_line
		(start 22.380194 -292.361112)
		(end 22.398482 -292.348412)
		(stroke
			(width 0.08255)
			(type default)
		)
		(layer "In2.Cu")
	)
	(gr_line
		(start 22.398228 -179.024534)
		(end 22.416516 -179.011834)
		(stroke
			(width 0.08255)
			(type default)
		)
		(layer "In2.Cu")
	)
	(gr_line
		(start 22.401784 -408.453336)
		(end 22.416516 -408.450796)
		(stroke
			(width 0.08255)
			(type default)
		)
		(layer "In2.Cu")
	)
	(gr_line
		(start 22.416516 -408.450796)
		(end 22.431248 -408.452828)
		(stroke
			(width 0.08255)
			(type default)
		)
		(layer "In2.Cu")
	)
	(gr_line
		(start 22.416516 -179.011834)
		(end 22.429216 -178.993546)
		(stroke
			(width 0.08255)
			(type default)
		)
		(layer "In2.Cu")
	)
	(gr_line
		(start 22.572218 -352.950018)
		(end 22.602444 -352.9711)
		(stroke
			(width 0.08255)
			(type default)
		)
		(layer "In2.Cu")
	)
	(gr_line
		(start 22.602444 -352.9711)
		(end 22.638258 -352.97745)
		(stroke
			(width 0.08255)
			(type default)
		)
		(layer "In2.Cu")
	)
	(gr_line
		(start 22.629622 -170.477434)
		(end 22.665436 -170.471084)
		(stroke
			(width 0.08255)
			(type default)
		)
		(layer "In2.Cu")
	)
	(gr_line
		(start 22.665436 -170.471084)
		(end 22.695662 -170.450002)
		(stroke
			(width 0.08255)
			(type default)
		)
		(layer "In2.Cu")
	)
	(gr_line
		(start 22.690582 -200.231756)
		(end 22.711156 -200.2282)
		(stroke
			(width 0.08255)
			(type default)
		)
		(layer "In2.Cu")
	)
	(gr_line
		(start 22.690836 -198.31939)
		(end 22.71141 -198.315834)
		(stroke
			(width 0.08255)
			(type default)
		)
		(layer "In2.Cu")
	)
	(gr_line
		(start 22.711156 -200.2282)
		(end 22.73173 -200.231756)
		(stroke
			(width 0.08255)
			(type default)
		)
		(layer "In2.Cu")
	)
	(gr_line
		(start 22.71141 -198.315834)
		(end 22.731984 -198.31939)
		(stroke
			(width 0.08255)
			(type default)
		)
		(layer "In2.Cu")
	)
	(gr_line
		(start 22.716236 -169.178224)
		(end 22.734524 -169.165524)
		(stroke
			(width 0.08255)
			(type default)
		)
		(layer "In2.Cu")
	)
	(gr_line
		(start 22.734524 -169.165524)
		(end 22.747224 -169.147236)
		(stroke
			(width 0.08255)
			(type default)
		)
		(layer "In2.Cu")
	)
	(gr_line
		(start 22.76475 -381.60325)
		(end 22.785324 -381.606806)
		(stroke
			(width 0.08255)
			(type default)
		)
		(layer "In2.Cu")
	)
	(gr_line
		(start 22.785324 -381.606806)
		(end 22.805898 -381.60325)
		(stroke
			(width 0.08255)
			(type default)
		)
		(layer "In2.Cu")
	)
	(gr_line
		(start 22.816312 -356.618794)
		(end 22.852126 -356.612444)
		(stroke
			(width 0.08255)
			(type default)
		)
		(layer "In2.Cu")
	)
	(gr_line
		(start 22.852126 -356.612444)
		(end 22.882352 -356.591362)
		(stroke
			(width 0.08255)
			(type default)
		)
		(layer "In2.Cu")
	)
	(gr_line
		(start 22.88159 -199.279002)
		(end 22.902164 -199.275446)
		(stroke
			(width 0.08255)
			(type default)
		)
		(layer "In2.Cu")
	)
	(gr_line
		(start 22.902164 -199.275446)
		(end 22.922738 -199.279002)
		(stroke
			(width 0.08255)
			(type default)
		)
		(layer "In2.Cu")
	)
	(gr_line
		(start 22.922738 -303.956974)
		(end 22.943312 -303.953418)
		(stroke
			(width 0.08255)
			(type default)
		)
		(layer "In2.Cu")
	)
	(gr_line
		(start 22.927056 -85.194394)
		(end 22.939756 -85.176106)
		(stroke
			(width 0.08255)
			(type default)
		)
		(layer "In2.Cu")
	)
	(gr_line
		(start 22.937724 -95.904558)
		(end 22.950424 -95.922846)
		(stroke
			(width 0.08255)
			(type default)
		)
		(layer "In2.Cu")
	)
	(gr_line
		(start 22.939756 -85.176106)
		(end 22.958044 -85.163406)
		(stroke
			(width 0.08255)
			(type default)
		)
		(layer "In2.Cu")
	)
	(gr_line
		(start 22.943312 -303.953418)
		(end 22.963886 -303.956974)
		(stroke
			(width 0.08255)
			(type default)
		)
		(layer "In2.Cu")
	)
	(gr_line
		(start 22.945852 -201.210418)
		(end 22.966426 -201.206862)
		(stroke
			(width 0.08255)
			(type default)
		)
		(layer "In2.Cu")
	)
	(gr_line
		(start 22.950424 -95.922846)
		(end 22.968712 -95.935546)
		(stroke
			(width 0.08255)
			(type default)
		)
		(layer "In2.Cu")
	)
	(gr_line
		(start 22.966426 -201.206862)
		(end 22.987 -201.210418)
		(stroke
			(width 0.08255)
			(type default)
		)
		(layer "In2.Cu")
	)
	(gr_line
		(start 23.004526 -171.421806)
		(end 23.040594 -171.415456)
		(stroke
			(width 0.08255)
			(type default)
		)
		(layer "In2.Cu")
	)
	(gr_line
		(start 23.026116 -403.32025)
		(end 23.056342 -403.341332)
		(stroke
			(width 0.08255)
			(type default)
		)
		(layer "In2.Cu")
	)
	(gr_line
		(start 23.040594 -171.415456)
		(end 23.070058 -171.394628)
		(stroke
			(width 0.08255)
			(type default)
		)
		(layer "In2.Cu")
	)
	(gr_line
		(start 23.056342 -403.341332)
		(end 23.09241 -403.347682)
		(stroke
			(width 0.08255)
			(type default)
		)
		(layer "In2.Cu")
	)
	(gr_line
		(start 23.093426 -301.125636)
		(end 23.114 -301.12208)
		(stroke
			(width 0.08255)
			(type default)
		)
		(layer "In2.Cu")
	)
	(gr_line
		(start 23.09368 -302.995838)
		(end 23.114254 -302.992282)
		(stroke
			(width 0.08255)
			(type default)
		)
		(layer "In2.Cu")
	)
	(gr_line
		(start 23.114 -301.12208)
		(end 23.134574 -301.125636)
		(stroke
			(width 0.08255)
			(type default)
		)
		(layer "In2.Cu")
	)
	(gr_line
		(start 23.114254 -302.992282)
		(end 23.134828 -302.995838)
		(stroke
			(width 0.08255)
			(type default)
		)
		(layer "In2.Cu")
	)
	(gr_line
		(start 23.118826 -355.988366)
		(end 23.164546 -355.730048)
		(stroke
			(width 0.08255)
			(type default)
		)
		(layer "In2.Cu")
	)
	(gr_line
		(start 23.134828 -302.06696)
		(end 23.155402 -302.063404)
		(stroke
			(width 0.08255)
			(type default)
		)
		(layer "In2.Cu")
	)
	(gr_line
		(start 23.155402 -302.063404)
		(end 23.175976 -302.06696)
		(stroke
			(width 0.08255)
			(type default)
		)
		(layer "In2.Cu")
	)
	(gr_line
		(start 23.156926 -168.56202)
		(end 23.178008 -168.531794)
		(stroke
			(width 0.08255)
			(type default)
		)
		(layer "In2.Cu")
	)
	(gr_line
		(start 23.164546 -355.730048)
		(end 23.570184 -355.445822)
		(stroke
			(width 0.08255)
			(type default)
		)
		(layer "In2.Cu")
	)
	(gr_line
		(start 23.178008 -168.531794)
		(end 23.184358 -168.495726)
		(stroke
			(width 0.08255)
			(type default)
		)
		(layer "In2.Cu")
	)
	(gr_line
		(start 23.356316 -356.25913)
		(end 24.001222 -355.807772)
		(stroke
			(width 0.08255)
			(type default)
		)
		(layer "In2.Cu")
	)
	(gr_line
		(start 23.507446 -402.447252)
		(end 23.537672 -402.468334)
		(stroke
			(width 0.08255)
			(type default)
		)
		(layer "In2.Cu")
	)
	(gr_line
		(start 23.537672 -402.468334)
		(end 23.57374 -402.474684)
		(stroke
			(width 0.08255)
			(type default)
		)
		(layer "In2.Cu")
	)
	(gr_line
		(start 23.570184 -355.445822)
		(end 23.828756 -355.491542)
		(stroke
			(width 0.08255)
			(type default)
		)
		(layer "In2.Cu")
	)
	(gr_line
		(start 23.605236 -169.813224)
		(end 23.623524 -169.800524)
		(stroke
			(width 0.08255)
			(type default)
		)
		(layer "In2.Cu")
	)
	(gr_line
		(start 23.623524 -169.800524)
		(end 23.636732 -169.781728)
		(stroke
			(width 0.08255)
			(type default)
		)
		(layer "In2.Cu")
	)
	(gr_line
		(start 23.626318 -270.028162)
		(end 23.647654 -269.997936)
		(stroke
			(width 0.08255)
			(type default)
		)
		(layer "In2.Cu")
	)
	(gr_line
		(start 23.647654 -269.997936)
		(end 23.654258 -269.961106)
		(stroke
			(width 0.08255)
			(type default)
		)
		(layer "In2.Cu")
	)
	(gr_line
		(start 23.647908 -146.840702)
		(end 23.666196 -146.853402)
		(stroke
			(width 0.08255)
			(type default)
		)
		(layer "In2.Cu")
	)
	(gr_line
		(start 23.666196 -146.853402)
		(end 23.678896 -146.87169)
		(stroke
			(width 0.08255)
			(type default)
		)
		(layer "In2.Cu")
	)
	(gr_line
		(start 23.669752 -95.29953)
		(end 23.682452 -95.317818)
		(stroke
			(width 0.08255)
			(type default)
		)
		(layer "In2.Cu")
	)
	(gr_line
		(start 23.682452 -95.317818)
		(end 23.70074 -95.330518)
		(stroke
			(width 0.08255)
			(type default)
		)
		(layer "In2.Cu")
	)
	(gr_line
		(start 23.849838 -462.271618)
		(end 23.8506 -462.27111)
		(stroke
			(width 0.08255)
			(type default)
		)
		(layer "In2.Cu")
	)
	(gr_line
		(start 23.955502 -169.326052)
		(end 23.976584 -169.295826)
		(stroke
			(width 0.08255)
			(type default)
		)
		(layer "In2.Cu")
	)
	(gr_line
		(start 23.976584 -169.295826)
		(end 23.982934 -169.260012)
		(stroke
			(width 0.08255)
			(type default)
		)
		(layer "In2.Cu")
	)
	(gr_line
		(start 24.021034 -462.583784)
		(end 24.021796 -462.583276)
		(stroke
			(width 0.08255)
			(type default)
		)
		(layer "In2.Cu")
	)
	(gr_line
		(start 24.112982 -487.801666)
		(end 24.125682 -487.819954)
		(stroke
			(width 0.08255)
			(type default)
		)
		(layer "In2.Cu")
	)
	(gr_line
		(start 24.125682 -487.819954)
		(end 24.14397 -487.832654)
		(stroke
			(width 0.08255)
			(type default)
		)
		(layer "In2.Cu")
	)
	(gr_line
		(start 24.134572 -353.241356)
		(end 24.155146 -353.244912)
		(stroke
			(width 0.08255)
			(type default)
		)
		(layer "In2.Cu")
	)
	(gr_line
		(start 24.155146 -353.244912)
		(end 24.17572 -353.241356)
		(stroke
			(width 0.08255)
			(type default)
		)
		(layer "In2.Cu")
	)
	(gr_line
		(start 24.238204 -355.204776)
		(end 24.283924 -354.946204)
		(stroke
			(width 0.08255)
			(type default)
		)
		(layer "In2.Cu")
	)
	(gr_line
		(start 24.239728 -170.575732)
		(end 24.258524 -170.562524)
		(stroke
			(width 0.08255)
			(type default)
		)
		(layer "In2.Cu")
	)
	(gr_line
		(start 24.258524 -170.562524)
		(end 24.270716 -170.544998)
		(stroke
			(width 0.08255)
			(type default)
		)
		(layer "In2.Cu")
	)
	(gr_line
		(start 24.283924 -354.946204)
		(end 24.689562 -354.661978)
		(stroke
			(width 0.08255)
			(type default)
		)
		(layer "In2.Cu")
	)
	(gr_line
		(start 24.382984 -249.634756)
		(end 24.416766 -249.641868)
		(stroke
			(width 0.08255)
			(type default)
		)
		(layer "In2.Cu")
	)
	(gr_line
		(start 24.392636 -271.15516)
		(end 24.414226 -271.124172)
		(stroke
			(width 0.08255)
			(type default)
		)
		(layer "In2.Cu")
	)
	(gr_line
		(start 24.414226 -271.124172)
		(end 24.42083 -271.087342)
		(stroke
			(width 0.08255)
			(type default)
		)
		(layer "In2.Cu")
	)
	(gr_line
		(start 24.416766 -249.641868)
		(end 24.450548 -249.634756)
		(stroke
			(width 0.08255)
			(type default)
		)
		(layer "In2.Cu")
	)
	(gr_line
		(start 24.47671 -355.474778)
		(end 25.121616 -355.023166)
		(stroke
			(width 0.08255)
			(type default)
		)
		(layer "In2.Cu")
	)
	(gr_line
		(start 24.52497 -480.426014)
		(end 24.555196 -480.447096)
		(stroke
			(width 0.08255)
			(type default)
		)
		(layer "In2.Cu")
	)
	(gr_line
		(start 24.555196 -480.447096)
		(end 24.591264 -480.453446)
		(stroke
			(width 0.08255)
			(type default)
		)
		(layer "In2.Cu")
	)
	(gr_line
		(start 24.561292 -99.311968)
		(end 24.591518 -99.33305)
		(stroke
			(width 0.08255)
			(type default)
		)
		(layer "In2.Cu")
	)
	(gr_line
		(start 24.575008 -287.367472)
		(end 24.587708 -287.349184)
		(stroke
			(width 0.08255)
			(type default)
		)
		(layer "In2.Cu")
	)
	(gr_line
		(start 24.587708 -287.349184)
		(end 24.605996 -287.336484)
		(stroke
			(width 0.08255)
			(type default)
		)
		(layer "In2.Cu")
	)
	(gr_line
		(start 24.591518 -99.33305)
		(end 24.627586 -99.3394)
		(stroke
			(width 0.08255)
			(type default)
		)
		(layer "In2.Cu")
	)
	(gr_line
		(start 24.689562 -354.661978)
		(end 24.948134 -354.707698)
		(stroke
			(width 0.08255)
			(type default)
		)
		(layer "In2.Cu")
	)
	(gr_line
		(start 24.700738 -343.469722)
		(end 24.763222 -343.456006)
		(stroke
			(width 0.08255)
			(type default)
		)
		(layer "In2.Cu")
	)
	(gr_line
		(start 24.763222 -343.456006)
		(end 24.821896 -343.478104)
		(stroke
			(width 0.08255)
			(type default)
		)
		(layer "In2.Cu")
	)
	(gr_line
		(start 24.808434 -148.485098)
		(end 24.829516 -148.515324)
		(stroke
			(width 0.08255)
			(type default)
		)
		(layer "In2.Cu")
	)
	(gr_line
		(start 24.829516 -148.515324)
		(end 24.835866 -148.551392)
		(stroke
			(width 0.08255)
			(type default)
		)
		(layer "In2.Cu")
	)
	(gr_line
		(start 24.87168 -137.440416)
		(end 24.9174 -137.431272)
		(stroke
			(width 0.08255)
			(type default)
		)
		(layer "In2.Cu")
	)
	(gr_line
		(start 24.876506 -98.414586)
		(end 24.906732 -98.435668)
		(stroke
			(width 0.08255)
			(type default)
		)
		(layer "In2.Cu")
	)
	(gr_line
		(start 24.89581 -169.652188)
		(end 24.916892 -169.621962)
		(stroke
			(width 0.08255)
			(type default)
		)
		(layer "In2.Cu")
	)
	(gr_line
		(start 24.906732 -98.435668)
		(end 24.942546 -98.442018)
		(stroke
			(width 0.08255)
			(type default)
		)
		(layer "In2.Cu")
	)
	(gr_line
		(start 24.916892 -169.621962)
		(end 24.923242 -169.586148)
		(stroke
			(width 0.08255)
			(type default)
		)
		(layer "In2.Cu")
	)
	(gr_line
		(start 24.9174 -137.431272)
		(end 24.962612 -137.444734)
		(stroke
			(width 0.08255)
			(type default)
		)
		(layer "In2.Cu")
	)
	(gr_line
		(start 24.941276 -151.19731)
		(end 25.077928 -151.972264)
		(stroke
			(width 0.08255)
			(type default)
		)
		(layer "In2.Cu")
	)
	(gr_line
		(start 24.99106 -171.36745)
		(end 25.009348 -171.35475)
		(stroke
			(width 0.08255)
			(type default)
		)
		(layer "In2.Cu")
	)
	(gr_line
		(start 24.997664 -173.571916)
		(end 25.015952 -173.559216)
		(stroke
			(width 0.08255)
			(type default)
		)
		(layer "In2.Cu")
	)
	(gr_line
		(start 25.009348 -171.35475)
		(end 25.022048 -171.336462)
		(stroke
			(width 0.08255)
			(type default)
		)
		(layer "In2.Cu")
	)
	(gr_line
		(start 25.015952 -173.559216)
		(end 25.028652 -173.540928)
		(stroke
			(width 0.08255)
			(type default)
		)
		(layer "In2.Cu")
	)
	(gr_line
		(start 25.16378 -97.4725)
		(end 25.194006 -97.493582)
		(stroke
			(width 0.08255)
			(type default)
		)
		(layer "In2.Cu")
	)
	(gr_line
		(start 25.178004 -152.540462)
		(end 25.315164 -153.31821)
		(stroke
			(width 0.08255)
			(type default)
		)
		(layer "In2.Cu")
	)
	(gr_line
		(start 25.194006 -97.493582)
		(end 25.230074 -97.499932)
		(stroke
			(width 0.08255)
			(type default)
		)
		(layer "In2.Cu")
	)
	(gr_line
		(start 25.273 -449.168774)
		(end 25.578562 -448.863212)
		(stroke
			(width 0.08255)
			(type default)
		)
		(layer "In2.Cu")
	)
	(gr_line
		(start 25.273 -448.051174)
		(end 25.578562 -448.356736)
		(stroke
			(width 0.08255)
			(type default)
		)
		(layer "In2.Cu")
	)
	(gr_line
		(start 25.273 -436.368952)
		(end 25.578562 -436.06339)
		(stroke
			(width 0.08255)
			(type default)
		)
		(layer "In2.Cu")
	)
	(gr_line
		(start 25.273 -435.251352)
		(end 25.578562 -435.556914)
		(stroke
			(width 0.08255)
			(type default)
		)
		(layer "In2.Cu")
	)
	(gr_line
		(start 25.273 -431.56886)
		(end 25.578562 -431.263298)
		(stroke
			(width 0.08255)
			(type default)
		)
		(layer "In2.Cu")
	)
	(gr_line
		(start 25.273 -430.45126)
		(end 25.578562 -430.756822)
		(stroke
			(width 0.08255)
			(type default)
		)
		(layer "In2.Cu")
	)
	(gr_line
		(start 25.273 -426.768768)
		(end 25.568402 -426.473366)
		(stroke
			(width 0.08255)
			(type default)
		)
		(layer "In2.Cu")
	)
	(gr_line
		(start 25.273 -425.651168)
		(end 25.737058 -426.115226)
		(stroke
			(width 0.08255)
			(type default)
		)
		(layer "In2.Cu")
	)
	(gr_line
		(start 25.273 -346.168726)
		(end 25.578562 -345.863164)
		(stroke
			(width 0.08255)
			(type default)
		)
		(layer "In2.Cu")
	)
	(gr_line
		(start 25.273 -345.051126)
		(end 25.578562 -345.356688)
		(stroke
			(width 0.08255)
			(type default)
		)
		(layer "In2.Cu")
	)
	(gr_line
		(start 25.273 -333.368904)
		(end 25.578562 -333.063342)
		(stroke
			(width 0.08255)
			(type default)
		)
		(layer "In2.Cu")
	)
	(gr_line
		(start 25.273 -332.251304)
		(end 25.578562 -332.556866)
		(stroke
			(width 0.08255)
			(type default)
		)
		(layer "In2.Cu")
	)
	(gr_line
		(start 25.273 -328.568812)
		(end 25.578562 -328.26325)
		(stroke
			(width 0.08255)
			(type default)
		)
		(layer "In2.Cu")
	)
	(gr_line
		(start 25.273 -327.451212)
		(end 25.578562 -327.756774)
		(stroke
			(width 0.08255)
			(type default)
		)
		(layer "In2.Cu")
	)
	(gr_line
		(start 25.273 -323.76872)
		(end 25.578562 -323.463158)
		(stroke
			(width 0.08255)
			(type default)
		)
		(layer "In2.Cu")
	)
	(gr_line
		(start 25.273 -322.65112)
		(end 25.578562 -322.956682)
		(stroke
			(width 0.08255)
			(type default)
		)
		(layer "In2.Cu")
	)
	(gr_line
		(start 25.273 -243.168678)
		(end 25.578562 -242.863116)
		(stroke
			(width 0.08255)
			(type default)
		)
		(layer "In2.Cu")
	)
	(gr_line
		(start 25.273 -242.051078)
		(end 25.578562 -242.35664)
		(stroke
			(width 0.08255)
			(type default)
		)
		(layer "In2.Cu")
	)
	(gr_line
		(start 25.273 -230.368856)
		(end 25.578562 -230.063294)
		(stroke
			(width 0.08255)
			(type default)
		)
		(layer "In2.Cu")
	)
	(gr_line
		(start 25.273 -229.251256)
		(end 25.578562 -229.556818)
		(stroke
			(width 0.08255)
			(type default)
		)
		(layer "In2.Cu")
	)
	(gr_line
		(start 25.273 -225.568764)
		(end 25.578562 -225.263202)
		(stroke
			(width 0.08255)
			(type default)
		)
		(layer "In2.Cu")
	)
	(gr_line
		(start 25.273 -224.451164)
		(end 25.578562 -224.756726)
		(stroke
			(width 0.08255)
			(type default)
		)
		(layer "In2.Cu")
	)
	(gr_line
		(start 25.273 -220.768672)
		(end 25.578562 -220.46311)
		(stroke
			(width 0.08255)
			(type default)
		)
		(layer "In2.Cu")
	)
	(gr_line
		(start 25.273 -219.651072)
		(end 25.578562 -219.956634)
		(stroke
			(width 0.08255)
			(type default)
		)
		(layer "In2.Cu")
	)
	(gr_line
		(start 25.273 -140.16863)
		(end 25.578562 -139.863068)
		(stroke
			(width 0.08255)
			(type default)
		)
		(layer "In2.Cu")
	)
	(gr_line
		(start 25.273 -139.05103)
		(end 25.578562 -139.356592)
		(stroke
			(width 0.08255)
			(type default)
		)
		(layer "In2.Cu")
	)
	(gr_line
		(start 25.273 -127.368808)
		(end 25.578562 -127.063246)
		(stroke
			(width 0.08255)
			(type default)
		)
		(layer "In2.Cu")
	)
	(gr_line
		(start 25.273 -126.251208)
		(end 25.578562 -126.55677)
		(stroke
			(width 0.08255)
			(type default)
		)
		(layer "In2.Cu")
	)
	(gr_line
		(start 25.273 -122.568716)
		(end 25.578562 -122.263154)
		(stroke
			(width 0.08255)
			(type default)
		)
		(layer "In2.Cu")
	)
	(gr_line
		(start 25.273 -121.451116)
		(end 25.578562 -121.756678)
		(stroke
			(width 0.08255)
			(type default)
		)
		(layer "In2.Cu")
	)
	(gr_line
		(start 25.273 -117.768624)
		(end 25.578562 -117.463062)
		(stroke
			(width 0.08255)
			(type default)
		)
		(layer "In2.Cu")
	)
	(gr_line
		(start 25.273 -116.651024)
		(end 25.578562 -116.956586)
		(stroke
			(width 0.08255)
			(type default)
		)
		(layer "In2.Cu")
	)
	(gr_line
		(start 25.273 -37.168582)
		(end 25.578562 -36.86302)
		(stroke
			(width 0.08255)
			(type default)
		)
		(layer "In2.Cu")
	)
	(gr_line
		(start 25.273 -36.050982)
		(end 25.578562 -36.356544)
		(stroke
			(width 0.08255)
			(type default)
		)
		(layer "In2.Cu")
	)
	(gr_line
		(start 25.273 -24.36876)
		(end 25.578562 -24.063198)
		(stroke
			(width 0.08255)
			(type default)
		)
		(layer "In2.Cu")
	)
	(gr_line
		(start 25.273 -23.25116)
		(end 25.578562 -23.556722)
		(stroke
			(width 0.08255)
			(type default)
		)
		(layer "In2.Cu")
	)
	(gr_line
		(start 25.273 -19.568668)
		(end 25.578562 -19.263106)
		(stroke
			(width 0.08255)
			(type default)
		)
		(layer "In2.Cu")
	)
	(gr_line
		(start 25.273 -18.451068)
		(end 25.578562 -18.75663)
		(stroke
			(width 0.08255)
			(type default)
		)
		(layer "In2.Cu")
	)
	(gr_line
		(start 25.273 -14.793976)
		(end 25.578562 -14.488414)
		(stroke
			(width 0.08255)
			(type default)
		)
		(layer "In2.Cu")
	)
	(gr_line
		(start 25.273 -13.676376)
		(end 25.578562 -13.981938)
		(stroke
			(width 0.08255)
			(type default)
		)
		(layer "In2.Cu")
	)
	(gr_line
		(start 25.28697 -151.09571)
		(end 25.502108 -151.246078)
		(stroke
			(width 0.08255)
			(type default)
		)
		(layer "In2.Cu")
	)
	(gr_line
		(start 25.328626 -96.470216)
		(end 25.358852 -96.491298)
		(stroke
			(width 0.08255)
			(type default)
		)
		(layer "In2.Cu")
	)
	(gr_line
		(start 25.357582 -354.420932)
		(end 25.403302 -354.16236)
		(stroke
			(width 0.08255)
			(type default)
		)
		(layer "In2.Cu")
	)
	(gr_line
		(start 25.358852 -96.491298)
		(end 25.394666 -96.497648)
		(stroke
			(width 0.08255)
			(type default)
		)
		(layer "In2.Cu")
	)
	(gr_line
		(start 25.403302 -354.16236)
		(end 25.80894 -353.878388)
		(stroke
			(width 0.08255)
			(type default)
		)
		(layer "In2.Cu")
	)
	(gr_line
		(start 25.437592 -151.948896)
		(end 25.58796 -151.733758)
		(stroke
			(width 0.08255)
			(type default)
		)
		(layer "In2.Cu")
	)
	(gr_line
		(start 25.502108 -151.246078)
		(end 25.58796 -151.733758)
		(stroke
			(width 0.08255)
			(type default)
		)
		(layer "In2.Cu")
	)
	(gr_line
		(start 25.524206 -152.441148)
		(end 25.739344 -152.592024)
		(stroke
			(width 0.08255)
			(type default)
		)
		(layer "In2.Cu")
	)
	(gr_line
		(start 25.596342 -354.69068)
		(end 26.241248 -354.239322)
		(stroke
			(width 0.08255)
			(type default)
		)
		(layer "In2.Cu")
	)
	(gr_line
		(start 25.674828 -153.294588)
		(end 25.825196 -153.079704)
		(stroke
			(width 0.08255)
			(type default)
		)
		(layer "In2.Cu")
	)
	(gr_line
		(start 25.682956 -256.411476)
		(end 25.689306 -256.375662)
		(stroke
			(width 0.08255)
			(type default)
		)
		(layer "In2.Cu")
	)
	(gr_line
		(start 25.689306 -256.375662)
		(end 25.710388 -256.345436)
		(stroke
			(width 0.08255)
			(type default)
		)
		(layer "In2.Cu")
	)
	(gr_line
		(start 25.739344 -152.592024)
		(end 25.825196 -153.079704)
		(stroke
			(width 0.08255)
			(type default)
		)
		(layer "In2.Cu")
	)
	(gr_line
		(start 25.764998 -153.861008)
		(end 25.768554 -153.840434)
		(stroke
			(width 0.08255)
			(type default)
		)
		(layer "In2.Cu")
	)
	(gr_line
		(start 25.764998 -153.819606)
		(end 25.768554 -153.840434)
		(stroke
			(width 0.08255)
			(type default)
		)
		(layer "In2.Cu")
	)
	(gr_line
		(start 25.764998 -153.819098)
		(end 25.764998 -153.81986)
		(stroke
			(width 0.08255)
			(type default)
		)
		(layer "In2.Cu")
	)
	(gr_line
		(start 25.789128 -170.24096)
		(end 25.81021 -170.210734)
		(stroke
			(width 0.08255)
			(type default)
		)
		(layer "In2.Cu")
	)
	(gr_line
		(start 25.80894 -353.878388)
		(end 26.067512 -353.923854)
		(stroke
			(width 0.08255)
			(type default)
		)
		(layer "In2.Cu")
	)
	(gr_line
		(start 25.81021 -170.210734)
		(end 25.81656 -170.174666)
		(stroke
			(width 0.08255)
			(type default)
		)
		(layer "In2.Cu")
	)
	(gr_line
		(start 25.83688 -387.26618)
		(end 25.867106 -387.287262)
		(stroke
			(width 0.08255)
			(type default)
		)
		(layer "In2.Cu")
	)
	(gr_line
		(start 25.867106 -387.287262)
		(end 25.903174 -387.293612)
		(stroke
			(width 0.08255)
			(type default)
		)
		(layer "In2.Cu")
	)
	(gr_line
		(start 26.052018 -137.77214)
		(end 26.05532 -137.773156)
		(stroke
			(width 0.08255)
			(type default)
		)
		(layer "In2.Cu")
	)
	(gr_line
		(start 26.05532 -137.773156)
		(end 26.058368 -137.774934)
		(stroke
			(width 0.08255)
			(type default)
		)
		(layer "In2.Cu")
	)
	(gr_line
		(start 26.246836 -249.25274)
		(end 26.270712 -249.24766)
		(stroke
			(width 0.08255)
			(type default)
		)
		(layer "In2.Cu")
	)
	(gr_line
		(start 26.270712 -249.24766)
		(end 26.290524 -249.234706)
		(stroke
			(width 0.08255)
			(type default)
		)
		(layer "In2.Cu")
	)
	(gr_line
		(start 26.28011 -344.024712)
		(end 26.365708 -344.056716)
		(stroke
			(width 0.08255)
			(type default)
		)
		(layer "In2.Cu")
	)
	(gr_line
		(start 26.365708 -344.056716)
		(end 26.409904 -344.136726)
		(stroke
			(width 0.08255)
			(type default)
		)
		(layer "In2.Cu")
	)
	(gr_line
		(start 26.441654 -65.319402)
		(end 26.462736 -65.289176)
		(stroke
			(width 0.08255)
			(type default)
		)
		(layer "In2.Cu")
	)
	(gr_line
		(start 26.462736 -65.289176)
		(end 26.469086 -65.253108)
		(stroke
			(width 0.08255)
			(type default)
		)
		(layer "In2.Cu")
	)
	(gr_line
		(start 26.526998 -352.826574)
		(end 26.562812 -352.820224)
		(stroke
			(width 0.08255)
			(type default)
		)
		(layer "In2.Cu")
	)
	(gr_line
		(start 26.562812 -352.820224)
		(end 26.593038 -352.799142)
		(stroke
			(width 0.08255)
			(type default)
		)
		(layer "In2.Cu")
	)
	(gr_line
		(start 26.578052 -256.80162)
		(end 26.584402 -256.765552)
		(stroke
			(width 0.08255)
			(type default)
		)
		(layer "In2.Cu")
	)
	(gr_line
		(start 26.584402 -256.765552)
		(end 26.605484 -256.735326)
		(stroke
			(width 0.08255)
			(type default)
		)
		(layer "In2.Cu")
	)
	(gr_line
		(start 26.608278 -138.10488)
		(end 26.651204 -138.130788)
		(stroke
			(width 0.08255)
			(type default)
		)
		(layer "In2.Cu")
	)
	(gr_line
		(start 26.651204 -138.130788)
		(end 26.676604 -138.174222)
		(stroke
			(width 0.08255)
			(type default)
		)
		(layer "In2.Cu")
	)
	(gr_line
		(start 26.699972 -485.633522)
		(end 26.730198 -485.654604)
		(stroke
			(width 0.08255)
			(type default)
		)
		(layer "In2.Cu")
	)
	(gr_line
		(start 26.71064 -270.834358)
		(end 26.731722 -270.804132)
		(stroke
			(width 0.08255)
			(type default)
		)
		(layer "In2.Cu")
	)
	(gr_line
		(start 26.730198 -485.654604)
		(end 26.766266 -485.660954)
		(stroke
			(width 0.08255)
			(type default)
		)
		(layer "In2.Cu")
	)
	(gr_line
		(start 26.731722 -270.804132)
		(end 26.738072 -270.768064)
		(stroke
			(width 0.08255)
			(type default)
		)
		(layer "In2.Cu")
	)
	(gr_line
		(start 26.74747 -344.748104)
		(end 26.7716 -344.791792)
		(stroke
			(width 0.08255)
			(type default)
		)
		(layer "In2.Cu")
	)
	(gr_line
		(start 26.946606 -170.801538)
		(end 26.967688 -170.771312)
		(stroke
			(width 0.08255)
			(type default)
		)
		(layer "In2.Cu")
	)
	(gr_line
		(start 26.947622 -138.638788)
		(end 26.9748 -138.685524)
		(stroke
			(width 0.08255)
			(type default)
		)
		(layer "In2.Cu")
	)
	(gr_line
		(start 26.964386 -180.91531)
		(end 26.977086 -180.897022)
		(stroke
			(width 0.08255)
			(type default)
		)
		(layer "In2.Cu")
	)
	(gr_line
		(start 26.967688 -170.771312)
		(end 26.974038 -170.735244)
		(stroke
			(width 0.08255)
			(type default)
		)
		(layer "In2.Cu")
	)
	(gr_line
		(start 26.977086 -180.897022)
		(end 26.995374 -180.884322)
		(stroke
			(width 0.08255)
			(type default)
		)
		(layer "In2.Cu")
	)
	(gr_line
		(start 27.044904 -149.851618)
		(end 27.051254 -149.815804)
		(stroke
			(width 0.08255)
			(type default)
		)
		(layer "In2.Cu")
	)
	(gr_line
		(start 27.051254 -149.815804)
		(end 27.072336 -149.785578)
		(stroke
			(width 0.08255)
			(type default)
		)
		(layer "In2.Cu")
	)
	(gr_line
		(start 27.09037 -242.716558)
		(end 27.126438 -242.710208)
		(stroke
			(width 0.08255)
			(type default)
		)
		(layer "In2.Cu")
	)
	(gr_line
		(start 27.126438 -242.710208)
		(end 27.156664 -242.689126)
		(stroke
			(width 0.08255)
			(type default)
		)
		(layer "In2.Cu")
	)
	(gr_line
		(start 27.14879 -19.276822)
		(end 27.299666 -19.49196)
		(stroke
			(width 0.08255)
			(type default)
		)
		(layer "In2.Cu")
	)
	(gr_line
		(start 27.24785 -18.93062)
		(end 28.026106 -19.06778)
		(stroke
			(width 0.08255)
			(type default)
		)
		(layer "In2.Cu")
	)
	(gr_line
		(start 27.299666 -19.49196)
		(end 27.787346 -19.577812)
		(stroke
			(width 0.08255)
			(type default)
		)
		(layer "In2.Cu")
	)
	(gr_line
		(start 27.305254 -272.922238)
		(end 27.326336 -272.892012)
		(stroke
			(width 0.08255)
			(type default)
		)
		(layer "In2.Cu")
	)
	(gr_line
		(start 27.326336 -272.892012)
		(end 27.332686 -272.855944)
		(stroke
			(width 0.08255)
			(type default)
		)
		(layer "In2.Cu")
	)
	(gr_line
		(start 27.327606 -65.977008)
		(end 27.348688 -65.946782)
		(stroke
			(width 0.08255)
			(type default)
		)
		(layer "In2.Cu")
	)
	(gr_line
		(start 27.348688 -65.946782)
		(end 27.355038 -65.910714)
		(stroke
			(width 0.08255)
			(type default)
		)
		(layer "In2.Cu")
	)
	(gr_line
		(start 27.451558 -121.966736)
		(end 27.487626 -121.973086)
		(stroke
			(width 0.08255)
			(type default)
		)
		(layer "In2.Cu")
	)
	(gr_line
		(start 27.487626 -121.973086)
		(end 27.517852 -121.994168)
		(stroke
			(width 0.08255)
			(type default)
		)
		(layer "In2.Cu")
	)
	(gr_line
		(start 27.501342 -323.19087)
		(end 27.537156 -323.19722)
		(stroke
			(width 0.08255)
			(type default)
		)
		(layer "In2.Cu")
	)
	(gr_line
		(start 27.537156 -323.19722)
		(end 27.567382 -323.218302)
		(stroke
			(width 0.08255)
			(type default)
		)
		(layer "In2.Cu")
	)
	(gr_line
		(start 27.55773 -148.764752)
		(end 27.60345 -149.022816)
		(stroke
			(width 0.08255)
			(type default)
		)
		(layer "In2.Cu")
	)
	(gr_line
		(start 27.55773 -148.764752)
		(end 27.841702 -148.35886)
		(stroke
			(width 0.08255)
			(type default)
		)
		(layer "In2.Cu")
	)
	(gr_line
		(start 27.606244 -117.209316)
		(end 27.642058 -117.215666)
		(stroke
			(width 0.08255)
			(type default)
		)
		(layer "In2.Cu")
	)
	(gr_line
		(start 27.642058 -117.215666)
		(end 27.672284 -117.236748)
		(stroke
			(width 0.08255)
			(type default)
		)
		(layer "In2.Cu")
	)
	(gr_line
		(start 27.713178 -274.157186)
		(end 27.713432 -274.157186)
		(stroke
			(width 0.08255)
			(type default)
		)
		(layer "In2.Cu")
	)
	(gr_line
		(start 27.734006 -332.840838)
		(end 27.770074 -332.847188)
		(stroke
			(width 0.08255)
			(type default)
		)
		(layer "In2.Cu")
	)
	(gr_line
		(start 27.751532 -183.960008)
		(end 27.82189 -183.947562)
		(stroke
			(width 0.08255)
			(type default)
		)
		(layer "In2.Cu")
	)
	(gr_line
		(start 27.754326 -122.597164)
		(end 27.800046 -122.855482)
		(stroke
			(width 0.08255)
			(type default)
		)
		(layer "In2.Cu")
	)
	(gr_line
		(start 27.770074 -332.847188)
		(end 27.8003 -332.86827)
		(stroke
			(width 0.08255)
			(type default)
		)
		(layer "In2.Cu")
	)
	(gr_line
		(start 27.787346 -19.577812)
		(end 28.00223 -19.42719)
		(stroke
			(width 0.08255)
			(type default)
		)
		(layer "In2.Cu")
	)
	(gr_line
		(start 27.791664 -242.244626)
		(end 27.809952 -242.231926)
		(stroke
			(width 0.08255)
			(type default)
		)
		(layer "In2.Cu")
	)
	(gr_line
		(start 27.792426 -241.30889)
		(end 27.838146 -241.567462)
		(stroke
			(width 0.08255)
			(type default)
		)
		(layer "In2.Cu")
	)
	(gr_line
		(start 27.792426 -241.30889)
		(end 28.076652 -240.903252)
		(stroke
			(width 0.08255)
			(type default)
		)
		(layer "In2.Cu")
	)
	(gr_line
		(start 27.800046 -122.855482)
		(end 28.205684 -123.139708)
		(stroke
			(width 0.08255)
			(type default)
		)
		(layer "In2.Cu")
	)
	(gr_line
		(start 27.809952 -242.231926)
		(end 27.822652 -242.213638)
		(stroke
			(width 0.08255)
			(type default)
		)
		(layer "In2.Cu")
	)
	(gr_line
		(start 27.841702 -148.35886)
		(end 28.100274 -148.31314)
		(stroke
			(width 0.08255)
			(type default)
		)
		(layer "In2.Cu")
	)
	(gr_line
		(start 27.8511 -430.982374)
		(end 27.887168 -430.976024)
		(stroke
			(width 0.08255)
			(type default)
		)
		(layer "In2.Cu")
	)
	(gr_line
		(start 27.871674 -171.221654)
		(end 27.892756 -171.191428)
		(stroke
			(width 0.08255)
			(type default)
		)
		(layer "In2.Cu")
	)
	(gr_line
		(start 27.887168 -430.976024)
		(end 27.917394 -430.954942)
		(stroke
			(width 0.08255)
			(type default)
		)
		(layer "In2.Cu")
	)
	(gr_line
		(start 27.892756 -171.191428)
		(end 27.899106 -171.155614)
		(stroke
			(width 0.08255)
			(type default)
		)
		(layer "In2.Cu")
	)
	(gr_line
		(start 27.907742 -328.04735)
		(end 27.943556 -328.0537)
		(stroke
			(width 0.08255)
			(type default)
		)
		(layer "In2.Cu")
	)
	(gr_line
		(start 27.920188 -149.19452)
		(end 28.369514 -148.552408)
		(stroke
			(width 0.08255)
			(type default)
		)
		(layer "In2.Cu")
	)
	(gr_line
		(start 27.943556 -328.0537)
		(end 27.973782 -328.074782)
		(stroke
			(width 0.08255)
			(type default)
		)
		(layer "In2.Cu")
	)
	(gr_line
		(start 27.98572 -150.176992)
		(end 27.99207 -150.141178)
		(stroke
			(width 0.08255)
			(type default)
		)
		(layer "In2.Cu")
	)
	(gr_line
		(start 27.989022 -126.8857)
		(end 28.02509 -126.89205)
		(stroke
			(width 0.08255)
			(type default)
		)
		(layer "In2.Cu")
	)
	(gr_line
		(start 27.9908 -73.860152)
		(end 28.0035 -73.841864)
		(stroke
			(width 0.08255)
			(type default)
		)
		(layer "In2.Cu")
	)
	(gr_line
		(start 27.991816 -122.3264)
		(end 28.635706 -122.77725)
		(stroke
			(width 0.08255)
			(type default)
		)
		(layer "In2.Cu")
	)
	(gr_line
		(start 27.99207 -150.141178)
		(end 28.013152 -150.110952)
		(stroke
			(width 0.08255)
			(type default)
		)
		(layer "In2.Cu")
	)
	(gr_line
		(start 28.0035 -73.841864)
		(end 28.021788 -73.829164)
		(stroke
			(width 0.08255)
			(type default)
		)
		(layer "In2.Cu")
	)
	(gr_line
		(start 28.02509 -126.89205)
		(end 28.055316 -126.913132)
		(stroke
			(width 0.08255)
			(type default)
		)
		(layer "In2.Cu")
	)
	(gr_line
		(start 28.028392 -274.327874)
		(end 28.049982 -274.296886)
		(stroke
			(width 0.08255)
			(type default)
		)
		(layer "In2.Cu")
	)
	(gr_line
		(start 28.043632 -435.7243)
		(end 28.0797 -435.71795)
		(stroke
			(width 0.08255)
			(type default)
		)
		(layer "In2.Cu")
	)
	(gr_line
		(start 28.049982 -274.296632)
		(end 28.049982 -274.296886)
		(stroke
			(width 0.08255)
			(type default)
		)
		(layer "In2.Cu")
	)
	(gr_line
		(start 28.049982 -274.296632)
		(end 28.056332 -274.260818)
		(stroke
			(width 0.08255)
			(type default)
		)
		(layer "In2.Cu")
	)
	(gr_line
		(start 28.076652 -240.903252)
		(end 28.335224 -240.857532)
		(stroke
			(width 0.08255)
			(type default)
		)
		(layer "In2.Cu")
	)
	(gr_line
		(start 28.0797 -435.71795)
		(end 28.109926 -435.696868)
		(stroke
			(width 0.08255)
			(type default)
		)
		(layer "In2.Cu")
	)
	(gr_line
		(start 28.08986 -14.294358)
		(end 28.125928 -14.300708)
		(stroke
			(width 0.08255)
			(type default)
		)
		(layer "In2.Cu")
	)
	(gr_line
		(start 28.103576 -229.713536)
		(end 28.139644 -229.707186)
		(stroke
			(width 0.08255)
			(type default)
		)
		(layer "In2.Cu")
	)
	(gr_line
		(start 28.112974 -459.732888)
		(end 28.131262 -459.720188)
		(stroke
			(width 0.08255)
			(type default)
		)
		(layer "In2.Cu")
	)
	(gr_line
		(start 28.125928 -14.300708)
		(end 28.156154 -14.32179)
		(stroke
			(width 0.08255)
			(type default)
		)
		(layer "In2.Cu")
	)
	(gr_line
		(start 28.131262 -459.720188)
		(end 28.143962 -459.7019)
		(stroke
			(width 0.08255)
			(type default)
		)
		(layer "In2.Cu")
	)
	(gr_line
		(start 28.139644 -229.707186)
		(end 28.139898 -229.707186)
		(stroke
			(width 0.08255)
			(type default)
		)
		(layer "In2.Cu")
	)
	(gr_line
		(start 28.139898 -229.707186)
		(end 28.170886 -229.685596)
		(stroke
			(width 0.08255)
			(type default)
		)
		(layer "In2.Cu")
	)
	(gr_line
		(start 28.154376 -241.739674)
		(end 28.605226 -241.095784)
		(stroke
			(width 0.08255)
			(type default)
		)
		(layer "In2.Cu")
	)
	(gr_line
		(start 28.190444 -66.705226)
		(end 28.211526 -66.675)
		(stroke
			(width 0.08255)
			(type default)
		)
		(layer "In2.Cu")
	)
	(gr_line
		(start 28.205684 -123.139708)
		(end 28.464002 -123.093988)
		(stroke
			(width 0.08255)
			(type default)
		)
		(layer "In2.Cu")
	)
	(gr_line
		(start 28.211526 -66.675)
		(end 28.217876 -66.638932)
		(stroke
			(width 0.08255)
			(type default)
		)
		(layer "In2.Cu")
	)
	(gr_line
		(start 28.219654 -490.686344)
		(end 28.24988 -490.707426)
		(stroke
			(width 0.08255)
			(type default)
		)
		(layer "In2.Cu")
	)
	(gr_line
		(start 28.24988 -490.707426)
		(end 28.285948 -490.713776)
		(stroke
			(width 0.08255)
			(type default)
		)
		(layer "In2.Cu")
	)
	(gr_line
		(start 28.258516 -430.278794)
		(end 28.301696 -430.0347)
		(stroke
			(width 0.08255)
			(type default)
		)
		(layer "In2.Cu")
	)
	(gr_line
		(start 28.301696 -430.0347)
		(end 28.707334 -429.750474)
		(stroke
			(width 0.08255)
			(type default)
		)
		(layer "In2.Cu")
	)
	(gr_line
		(start 28.34132 -147.645374)
		(end 28.38704 -147.903692)
		(stroke
			(width 0.08255)
			(type default)
		)
		(layer "In2.Cu")
	)
	(gr_line
		(start 28.34132 -147.645374)
		(end 28.625292 -147.239482)
		(stroke
			(width 0.08255)
			(type default)
		)
		(layer "In2.Cu")
	)
	(gr_line
		(start 28.3464 -435.093872)
		(end 28.39212 -434.835554)
		(stroke
			(width 0.08255)
			(type default)
		)
		(layer "In2.Cu")
	)
	(gr_line
		(start 28.39212 -434.835554)
		(end 28.797758 -434.551328)
		(stroke
			(width 0.08255)
			(type default)
		)
		(layer "In2.Cu")
	)
	(gr_line
		(start 28.406344 -229.083362)
		(end 28.452064 -228.82479)
		(stroke
			(width 0.08255)
			(type default)
		)
		(layer "In2.Cu")
	)
	(gr_line
		(start 28.452064 -228.82479)
		(end 28.857702 -228.540564)
		(stroke
			(width 0.08255)
			(type default)
		)
		(layer "In2.Cu")
	)
	(gr_line
		(start 28.493466 -14.995144)
		(end 28.535884 -15.238222)
		(stroke
			(width 0.08255)
			(type default)
		)
		(layer "In2.Cu")
	)
	(gr_line
		(start 28.496006 -430.549812)
		(end 29.125164 -430.109376)
		(stroke
			(width 0.08255)
			(type default)
		)
		(layer "In2.Cu")
	)
	(gr_line
		(start 28.535884 -15.238222)
		(end 28.983432 -15.551912)
		(stroke
			(width 0.08255)
			(type default)
		)
		(layer "In2.Cu")
	)
	(gr_line
		(start 28.538424 -340.689692)
		(end 28.54198 -340.71052)
		(stroke
			(width 0.08255)
			(type default)
		)
		(layer "In2.Cu")
	)
	(gr_line
		(start 28.538424 -340.689692)
		(end 28.54198 -340.669118)
		(stroke
			(width 0.08255)
			(type default)
		)
		(layer "In2.Cu")
	)
	(gr_line
		(start 28.54198 -340.710266)
		(end 28.54198 -340.711028)
		(stroke
			(width 0.08255)
			(type default)
		)
		(layer "In2.Cu")
	)
	(gr_line
		(start 28.56611 -24.001476)
		(end 28.602178 -24.007826)
		(stroke
			(width 0.08255)
			(type default)
		)
		(layer "In2.Cu")
	)
	(gr_line
		(start 28.584398 -435.364636)
		(end 29.229812 -434.912516)
		(stroke
			(width 0.08255)
			(type default)
		)
		(layer "In2.Cu")
	)
	(gr_line
		(start 28.602178 -24.007826)
		(end 28.632404 -24.028908)
		(stroke
			(width 0.08255)
			(type default)
		)
		(layer "In2.Cu")
	)
	(gr_line
		(start 28.625292 -147.239482)
		(end 28.883864 -147.193762)
		(stroke
			(width 0.08255)
			(type default)
		)
		(layer "In2.Cu")
	)
	(gr_line
		(start 28.629864 -176.704498)
		(end 28.642564 -176.68621)
		(stroke
			(width 0.08255)
			(type default)
		)
		(layer "In2.Cu")
	)
	(gr_line
		(start 28.642564 -176.68621)
		(end 28.660852 -176.67351)
		(stroke
			(width 0.08255)
			(type default)
		)
		(layer "In2.Cu")
	)
	(gr_line
		(start 28.643072 -229.354888)
		(end 29.29001 -228.901752)
		(stroke
			(width 0.08255)
			(type default)
		)
		(layer "In2.Cu")
	)
	(gr_line
		(start 28.685236 -333.487776)
		(end 28.703524 -333.500476)
		(stroke
			(width 0.08255)
			(type default)
		)
		(layer "In2.Cu")
	)
	(gr_line
		(start 28.703524 -333.500476)
		(end 28.716224 -333.518764)
		(stroke
			(width 0.08255)
			(type default)
		)
		(layer "In2.Cu")
	)
	(gr_line
		(start 28.703778 -148.075142)
		(end 29.153358 -147.432776)
		(stroke
			(width 0.08255)
			(type default)
		)
		(layer "In2.Cu")
	)
	(gr_line
		(start 28.707334 -429.750474)
		(end 28.951428 -429.793654)
		(stroke
			(width 0.08255)
			(type default)
		)
		(layer "In2.Cu")
	)
	(gr_line
		(start 28.728162 -279.238964)
		(end 28.740862 -279.220676)
		(stroke
			(width 0.08255)
			(type default)
		)
		(layer "In2.Cu")
	)
	(gr_line
		(start 28.730194 -14.723618)
		(end 29.400246 -15.19301)
		(stroke
			(width 0.08255)
			(type default)
		)
		(layer "In2.Cu")
	)
	(gr_line
		(start 28.740862 -279.220676)
		(end 28.75915 -279.207976)
		(stroke
			(width 0.08255)
			(type default)
		)
		(layer "In2.Cu")
	)
	(gr_line
		(start 28.763976 -171.634658)
		(end 28.785058 -171.604432)
		(stroke
			(width 0.08255)
			(type default)
		)
		(layer "In2.Cu")
	)
	(gr_line
		(start 28.785058 -171.604432)
		(end 28.791408 -171.568364)
		(stroke
			(width 0.08255)
			(type default)
		)
		(layer "In2.Cu")
	)
	(gr_line
		(start 28.79598 -48.923194)
		(end 28.882086 -48.435514)
		(stroke
			(width 0.08255)
			(type default)
		)
		(layer "In2.Cu")
	)
	(gr_line
		(start 28.79598 -48.923194)
		(end 28.946602 -49.138078)
		(stroke
			(width 0.08255)
			(type default)
		)
		(layer "In2.Cu")
	)
	(gr_line
		(start 28.797758 -434.551328)
		(end 29.05633 -434.597048)
		(stroke
			(width 0.08255)
			(type default)
		)
		(layer "In2.Cu")
	)
	(gr_line
		(start 28.804108 -224.886012)
		(end 28.840176 -224.879662)
		(stroke
			(width 0.08255)
			(type default)
		)
		(layer "In2.Cu")
	)
	(gr_line
		(start 28.812236 -328.661776)
		(end 28.830524 -328.674476)
		(stroke
			(width 0.08255)
			(type default)
		)
		(layer "In2.Cu")
	)
	(gr_line
		(start 28.812236 -324.089522)
		(end 28.830524 -324.102476)
		(stroke
			(width 0.08255)
			(type default)
		)
		(layer "In2.Cu")
	)
	(gr_line
		(start 28.830524 -328.674476)
		(end 28.843224 -328.692764)
		(stroke
			(width 0.08255)
			(type default)
		)
		(layer "In2.Cu")
	)
	(gr_line
		(start 28.830524 -324.102476)
		(end 28.843224 -324.120764)
		(stroke
			(width 0.08255)
			(type default)
		)
		(layer "In2.Cu")
	)
	(gr_line
		(start 28.840176 -224.879662)
		(end 28.870402 -224.85858)
		(stroke
			(width 0.08255)
			(type default)
		)
		(layer "In2.Cu")
	)
	(gr_line
		(start 28.84424 -217.061542)
		(end 28.850082 -217.054176)
		(stroke
			(width 0.08255)
			(type default)
		)
		(layer "In2.Cu")
	)
	(gr_line
		(start 28.850082 -217.054176)
		(end 28.857956 -217.048588)
		(stroke
			(width 0.08255)
			(type default)
		)
		(layer "In2.Cu")
	)
	(gr_line
		(start 28.857702 -228.540564)
		(end 29.116528 -228.586284)
		(stroke
			(width 0.08255)
			(type default)
		)
		(layer "In2.Cu")
	)
	(gr_line
		(start 28.868116 -335.482184)
		(end 28.953968 -335.969864)
		(stroke
			(width 0.08255)
			(type default)
		)
		(layer "In2.Cu")
	)
	(gr_line
		(start 28.868116 -335.482184)
		(end 29.018484 -335.2673)
		(stroke
			(width 0.08255)
			(type default)
		)
		(layer "In2.Cu")
	)
	(gr_line
		(start 28.882086 -48.435514)
		(end 29.09697 -48.284892)
		(stroke
			(width 0.08255)
			(type default)
		)
		(layer "In2.Cu")
	)
	(gr_line
		(start 28.88996 -275.03755)
		(end 28.910534 -275.00834)
		(stroke
			(width 0.08255)
			(type default)
		)
		(layer "In2.Cu")
	)
	(gr_line
		(start 28.890468 -36.751514)
		(end 28.926282 -36.757864)
		(stroke
			(width 0.08255)
			(type default)
		)
		(layer "In2.Cu")
	)
	(gr_line
		(start 28.899612 -445.516254)
		(end 28.985718 -445.028574)
		(stroke
			(width 0.08255)
			(type default)
		)
		(layer "In2.Cu")
	)
	(gr_line
		(start 28.899612 -445.516254)
		(end 29.050234 -445.731392)
		(stroke
			(width 0.08255)
			(type default)
		)
		(layer "In2.Cu")
	)
	(gr_line
		(start 28.910534 -275.00834)
		(end 28.917138 -274.97151)
		(stroke
			(width 0.08255)
			(type default)
		)
		(layer "In2.Cu")
	)
	(gr_line
		(start 28.919678 -118.547134)
		(end 28.965144 -118.805452)
		(stroke
			(width 0.08255)
			(type default)
		)
		(layer "In2.Cu")
	)
	(gr_line
		(start 28.926282 -36.757864)
		(end 28.956508 -36.778946)
		(stroke
			(width 0.08255)
			(type default)
		)
		(layer "In2.Cu")
	)
	(gr_line
		(start 28.93695 -150.43277)
		(end 28.9433 -150.396702)
		(stroke
			(width 0.08255)
			(type default)
		)
		(layer "In2.Cu")
	)
	(gr_line
		(start 28.9433 -150.396702)
		(end 28.964382 -150.366476)
		(stroke
			(width 0.08255)
			(type default)
		)
		(layer "In2.Cu")
	)
	(gr_line
		(start 28.953968 -335.969864)
		(end 29.168852 -336.12074)
		(stroke
			(width 0.08255)
			(type default)
		)
		(layer "In2.Cu")
	)
	(gr_line
		(start 28.965144 -118.805452)
		(end 29.371036 -119.089678)
		(stroke
			(width 0.08255)
			(type default)
		)
		(layer "In2.Cu")
	)
	(gr_line
		(start 28.983432 -15.551912)
		(end 29.22651 -15.508478)
		(stroke
			(width 0.08255)
			(type default)
		)
		(layer "In2.Cu")
	)
	(gr_line
		(start 28.985718 -445.028574)
		(end 29.200602 -444.878206)
		(stroke
			(width 0.08255)
			(type default)
		)
		(layer "In2.Cu")
	)
	(gr_line
		(start 29.033216 -47.577248)
		(end 29.119322 -47.089568)
		(stroke
			(width 0.08255)
			(type default)
		)
		(layer "In2.Cu")
	)
	(gr_line
		(start 29.033216 -47.577248)
		(end 29.183838 -47.792386)
		(stroke
			(width 0.08255)
			(type default)
		)
		(layer "In2.Cu")
	)
	(gr_line
		(start 29.05887 -330.397358)
		(end 29.144976 -330.885292)
		(stroke
			(width 0.08255)
			(type default)
		)
		(layer "In2.Cu")
	)
	(gr_line
		(start 29.05887 -330.397358)
		(end 29.200856 -330.194158)
		(stroke
			(width 0.08255)
			(type default)
		)
		(layer "In2.Cu")
	)
	(gr_line
		(start 29.066236 -127.620776)
		(end 29.084524 -127.633476)
		(stroke
			(width 0.08255)
			(type default)
		)
		(layer "In2.Cu")
	)
	(gr_line
		(start 29.07665 -255.44526)
		(end 29.078936 -255.432306)
		(stroke
			(width 0.08255)
			(type default)
		)
		(layer "In2.Cu")
	)
	(gr_line
		(start 29.084524 -127.633476)
		(end 29.097224 -127.651764)
		(stroke
			(width 0.08255)
			(type default)
		)
		(layer "In2.Cu")
	)
	(gr_line
		(start 29.084524 -67.440048)
		(end 29.105606 -67.409822)
		(stroke
			(width 0.08255)
			(type default)
		)
		(layer "In2.Cu")
	)
	(gr_line
		(start 29.084778 -255.398778)
		(end 29.091382 -255.361694)
		(stroke
			(width 0.08255)
			(type default)
		)
		(layer "In2.Cu")
	)
	(gr_line
		(start 29.091382 -255.361694)
		(end 29.091636 -255.361694)
		(stroke
			(width 0.08255)
			(type default)
		)
		(layer "In2.Cu")
	)
	(gr_line
		(start 29.091636 -255.361694)
		(end 29.09189 -255.36144)
		(stroke
			(width 0.08255)
			(type default)
		)
		(layer "In2.Cu")
	)
	(gr_line
		(start 29.09189 -255.36144)
		(end 29.112718 -255.331468)
		(stroke
			(width 0.08255)
			(type default)
		)
		(layer "In2.Cu")
	)
	(gr_line
		(start 29.105606 -67.409822)
		(end 29.111956 -67.373754)
		(stroke
			(width 0.08255)
			(type default)
		)
		(layer "In2.Cu")
	)
	(gr_line
		(start 29.106876 -224.255584)
		(end 29.152596 -223.997266)
		(stroke
			(width 0.08255)
			(type default)
		)
		(layer "In2.Cu")
	)
	(gr_line
		(start 29.119322 -47.089568)
		(end 29.334206 -46.9392)
		(stroke
			(width 0.08255)
			(type default)
		)
		(layer "In2.Cu")
	)
	(gr_line
		(start 29.125164 -146.525996)
		(end 29.17063 -146.784314)
		(stroke
			(width 0.08255)
			(type default)
		)
		(layer "In2.Cu")
	)
	(gr_line
		(start 29.125164 -146.525996)
		(end 29.409136 -146.120104)
		(stroke
			(width 0.08255)
			(type default)
		)
		(layer "In2.Cu")
	)
	(gr_line
		(start 29.136848 -444.170562)
		(end 29.222954 -443.682882)
		(stroke
			(width 0.08255)
			(type default)
		)
		(layer "In2.Cu")
	)
	(gr_line
		(start 29.136848 -444.170562)
		(end 29.28747 -444.385446)
		(stroke
			(width 0.08255)
			(type default)
		)
		(layer "In2.Cu")
	)
	(gr_line
		(start 29.144976 -330.885292)
		(end 29.348176 -331.027278)
		(stroke
			(width 0.08255)
			(type default)
		)
		(layer "In2.Cu")
	)
	(gr_line
		(start 29.152596 -223.997266)
		(end 29.558234 -223.71304)
		(stroke
			(width 0.08255)
			(type default)
		)
		(layer "In2.Cu")
	)
	(gr_line
		(start 29.157168 -118.27637)
		(end 29.80309 -118.728236)
		(stroke
			(width 0.08255)
			(type default)
		)
		(layer "In2.Cu")
	)
	(gr_line
		(start 29.17317 -334.17129)
		(end 29.194252 -334.201516)
		(stroke
			(width 0.08255)
			(type default)
		)
		(layer "In2.Cu")
	)
	(gr_line
		(start 29.194252 -334.201516)
		(end 29.200602 -334.237584)
		(stroke
			(width 0.08255)
			(type default)
		)
		(layer "In2.Cu")
	)
	(gr_line
		(start 29.209746 -350.967548)
		(end 29.228034 -350.954848)
		(stroke
			(width 0.08255)
			(type default)
		)
		(layer "In2.Cu")
	)
	(gr_line
		(start 29.222954 -443.682882)
		(end 29.437838 -443.53226)
		(stroke
			(width 0.08255)
			(type default)
		)
		(layer "In2.Cu")
	)
	(gr_line
		(start 29.228034 -350.954848)
		(end 29.240734 -350.93656)
		(stroke
			(width 0.08255)
			(type default)
		)
		(layer "In2.Cu")
	)
	(gr_line
		(start 29.263086 -133.335014)
		(end 29.349192 -133.822948)
		(stroke
			(width 0.08255)
			(type default)
		)
		(layer "In2.Cu")
	)
	(gr_line
		(start 29.263086 -133.335014)
		(end 29.413454 -133.12013)
		(stroke
			(width 0.08255)
			(type default)
		)
		(layer "In2.Cu")
	)
	(gr_line
		(start 29.293058 -331.722984)
		(end 29.379164 -332.210918)
		(stroke
			(width 0.08255)
			(type default)
		)
		(layer "In2.Cu")
	)
	(gr_line
		(start 29.293058 -331.722984)
		(end 29.435298 -331.519784)
		(stroke
			(width 0.08255)
			(type default)
		)
		(layer "In2.Cu")
	)
	(gr_line
		(start 29.306266 -49.160176)
		(end 29.442664 -48.386492)
		(stroke
			(width 0.08255)
			(type default)
		)
		(layer "In2.Cu")
	)
	(gr_line
		(start 29.322268 -132.588762)
		(end 29.325824 -132.60959)
		(stroke
			(width 0.08255)
			(type default)
		)
		(layer "In2.Cu")
	)
	(gr_line
		(start 29.322268 -132.588762)
		(end 29.325824 -132.568188)
		(stroke
			(width 0.08255)
			(type default)
		)
		(layer "In2.Cu")
	)
	(gr_line
		(start 29.325824 -132.609336)
		(end 29.325824 -132.610098)
		(stroke
			(width 0.08255)
			(type default)
		)
		(layer "In2.Cu")
	)
	(gr_line
		(start 29.337254 -46.937168)
		(end 29.337508 -46.936914)
		(stroke
			(width 0.08255)
			(type default)
		)
		(layer "In2.Cu")
	)
	(gr_line
		(start 29.337508 -80.696562)
		(end 29.367734 -80.67548)
		(stroke
			(width 0.08255)
			(type default)
		)
		(layer "In2.Cu")
	)
	(gr_line
		(start 29.337508 -46.93666)
		(end 29.337254 -46.93666)
		(stroke
			(width 0.08255)
			(type default)
		)
		(layer "In2.Cu")
	)
	(gr_line
		(start 29.337508 -46.93666)
		(end 29.337508 -46.936914)
		(stroke
			(width 0.08255)
			(type default)
		)
		(layer "In2.Cu")
	)
	(gr_line
		(start 29.344874 -224.526348)
		(end 29.990288 -224.074228)
		(stroke
			(width 0.08255)
			(type default)
		)
		(layer "In2.Cu")
	)
	(gr_line
		(start 29.349192 -133.822948)
		(end 29.564076 -133.973316)
		(stroke
			(width 0.08255)
			(type default)
		)
		(layer "In2.Cu")
	)
	(gr_line
		(start 29.36113 -429.506634)
		(end 29.40431 -429.26254)
		(stroke
			(width 0.08255)
			(type default)
		)
		(layer "In2.Cu")
	)
	(gr_line
		(start 29.367734 -80.67548)
		(end 29.403802 -80.66913)
		(stroke
			(width 0.08255)
			(type default)
		)
		(layer "In2.Cu")
	)
	(gr_line
		(start 29.371036 -119.089678)
		(end 29.629608 -119.043958)
		(stroke
			(width 0.08255)
			(type default)
		)
		(layer "In2.Cu")
	)
	(gr_line
		(start 29.374084 -442.82487)
		(end 29.46019 -442.336936)
		(stroke
			(width 0.08255)
			(type default)
		)
		(layer "In2.Cu")
	)
	(gr_line
		(start 29.374084 -442.82487)
		(end 29.524706 -443.0395)
		(stroke
			(width 0.08255)
			(type default)
		)
		(layer "In2.Cu")
	)
	(gr_line
		(start 29.376878 -247.230392)
		(end 29.399484 -247.21566)
		(stroke
			(width 0.08255)
			(type default)
		)
		(layer "In2.Cu")
	)
	(gr_line
		(start 29.378148 -335.243678)
		(end 29.5148 -336.02041)
		(stroke
			(width 0.08255)
			(type default)
		)
		(layer "In2.Cu")
	)
	(gr_line
		(start 29.379164 -332.210918)
		(end 29.582364 -332.352904)
		(stroke
			(width 0.08255)
			(type default)
		)
		(layer "In2.Cu")
	)
	(gr_line
		(start 29.394912 -19.30908)
		(end 29.433774 -19.315938)
		(stroke
			(width 0.08255)
			(type default)
		)
		(layer "In2.Cu")
	)
	(gr_line
		(start 29.399484 -247.21566)
		(end 29.414978 -247.193562)
		(stroke
			(width 0.08255)
			(type default)
		)
		(layer "In2.Cu")
	)
	(gr_line
		(start 29.40431 -429.26254)
		(end 29.809948 -428.978314)
		(stroke
			(width 0.08255)
			(type default)
		)
		(layer "In2.Cu")
	)
	(gr_line
		(start 29.409136 -146.120104)
		(end 29.667454 -146.074384)
		(stroke
			(width 0.08255)
			(type default)
		)
		(layer "In2.Cu")
	)
	(gr_line
		(start 29.409898 -445.754506)
		(end 29.416248 -445.718184)
		(stroke
			(width 0.08255)
			(type default)
		)
		(layer "In2.Cu")
	)
	(gr_arc
		(start 29.416248 -445.718184)
		(mid 29.416783 -445.715268)
		(end 29.417264 -445.712342)
		(stroke
			(width 0.08255)
			(type default)
		)
		(layer "In2.Cu")
	)
	(gr_line
		(start 29.417264 -445.712342)
		(end 29.54655 -444.97879)
		(stroke
			(width 0.08255)
			(type default)
		)
		(layer "In2.Cu")
	)
	(gr_line
		(start 29.427678 -255.502156)
		(end 29.427932 -255.502156)
		(stroke
			(width 0.08255)
			(type default)
		)
		(layer "In2.Cu")
	)
	(gr_line
		(start 29.43225 -329.534012)
		(end 29.453332 -329.564238)
		(stroke
			(width 0.08255)
			(type default)
		)
		(layer "In2.Cu")
	)
	(gr_line
		(start 29.433774 -19.315938)
		(end 29.466032 -19.338544)
		(stroke
			(width 0.08255)
			(type default)
		)
		(layer "In2.Cu")
	)
	(gr_line
		(start 29.453332 -329.564238)
		(end 29.459682 -329.600052)
		(stroke
			(width 0.08255)
			(type default)
		)
		(layer "In2.Cu")
	)
	(gr_line
		(start 29.46019 -442.336936)
		(end 29.675074 -442.186568)
		(stroke
			(width 0.08255)
			(type default)
		)
		(layer "In2.Cu")
	)
	(gr_line
		(start 29.465778 -434.310282)
		(end 29.511498 -434.05171)
		(stroke
			(width 0.08255)
			(type default)
		)
		(layer "In2.Cu")
	)
	(gr_line
		(start 29.48686 -146.95678)
		(end 29.937202 -146.313398)
		(stroke
			(width 0.08255)
			(type default)
		)
		(layer "In2.Cu")
	)
	(gr_line
		(start 29.511498 -434.05171)
		(end 29.917136 -433.767738)
		(stroke
			(width 0.08255)
			(type default)
		)
		(layer "In2.Cu")
	)
	(gr_line
		(start 29.514292 -239.798098)
		(end 29.535374 -239.767872)
		(stroke
			(width 0.08255)
			(type default)
		)
		(layer "In2.Cu")
	)
	(gr_line
		(start 29.516832 -340.952328)
		(end 29.520388 -340.973156)
		(stroke
			(width 0.08255)
			(type default)
		)
		(layer "In2.Cu")
	)
	(gr_line
		(start 29.516832 -340.952328)
		(end 29.520388 -340.931754)
		(stroke
			(width 0.08255)
			(type default)
		)
		(layer "In2.Cu")
	)
	(gr_line
		(start 29.520388 -340.972902)
		(end 29.520388 -340.973664)
		(stroke
			(width 0.08255)
			(type default)
		)
		(layer "In2.Cu")
	)
	(gr_line
		(start 29.525722 -228.299518)
		(end 29.571442 -228.040946)
		(stroke
			(width 0.08255)
			(type default)
		)
		(layer "In2.Cu")
	)
	(gr_line
		(start 29.527246 -333.04861)
		(end 29.613352 -333.536544)
		(stroke
			(width 0.08255)
			(type default)
		)
		(layer "In2.Cu")
	)
	(gr_line
		(start 29.527246 -333.04861)
		(end 29.669486 -332.84541)
		(stroke
			(width 0.08255)
			(type default)
		)
		(layer "In2.Cu")
	)
	(gr_line
		(start 29.535374 -239.767872)
		(end 29.541724 -239.732058)
		(stroke
			(width 0.08255)
			(type default)
		)
		(layer "In2.Cu")
	)
	(gr_line
		(start 29.543502 -47.814738)
		(end 29.679392 -47.043848)
		(stroke
			(width 0.08255)
			(type default)
		)
		(layer "In2.Cu")
	)
	(gr_line
		(start 29.544772 -37.19068)
		(end 29.56306 -37.203634)
		(stroke
			(width 0.08255)
			(type default)
		)
		(layer "In2.Cu")
	)
	(gr_line
		(start 29.558234 -223.71304)
		(end 29.816806 -223.75876)
		(stroke
			(width 0.08255)
			(type default)
		)
		(layer "In2.Cu")
	)
	(gr_line
		(start 29.56052 -330.170282)
		(end 29.694378 -330.927202)
		(stroke
			(width 0.08255)
			(type default)
		)
		(layer "In2.Cu")
	)
	(gr_line
		(start 29.56306 -37.203634)
		(end 29.57576 -37.221922)
		(stroke
			(width 0.08255)
			(type default)
		)
		(layer "In2.Cu")
	)
	(gr_line
		(start 29.571442 -228.040946)
		(end 29.97708 -227.756974)
		(stroke
			(width 0.08255)
			(type default)
		)
		(layer "In2.Cu")
	)
	(gr_line
		(start 29.597096 -429.778922)
		(end 30.229048 -429.336454)
		(stroke
			(width 0.08255)
			(type default)
		)
		(layer "In2.Cu")
	)
	(gr_line
		(start 29.613352 -333.536544)
		(end 29.816552 -333.678784)
		(stroke
			(width 0.08255)
			(type default)
		)
		(layer "In2.Cu")
	)
	(gr_line
		(start 29.615384 -336.631026)
		(end 29.61894 -336.610198)
		(stroke
			(width 0.08255)
			(type default)
		)
		(layer "In2.Cu")
	)
	(gr_line
		(start 29.615384 -336.630772)
		(end 29.615384 -336.631534)
		(stroke
			(width 0.08255)
			(type default)
		)
		(layer "In2.Cu")
	)
	(gr_line
		(start 29.615384 -336.589624)
		(end 29.61894 -336.610198)
		(stroke
			(width 0.08255)
			(type default)
		)
		(layer "In2.Cu")
	)
	(gr_line
		(start 29.628084 -326.663304)
		(end 29.71419 -327.150984)
		(stroke
			(width 0.08255)
			(type default)
		)
		(layer "In2.Cu")
	)
	(gr_line
		(start 29.628084 -326.663304)
		(end 29.778706 -326.448166)
		(stroke
			(width 0.08255)
			(type default)
		)
		(layer "In2.Cu")
	)
	(gr_line
		(start 29.639768 -236.046264)
		(end 29.72562 -235.558584)
		(stroke
			(width 0.08255)
			(type default)
		)
		(layer "In2.Cu")
	)
	(gr_line
		(start 29.639768 -236.046264)
		(end 29.790136 -236.261402)
		(stroke
			(width 0.08255)
			(type default)
		)
		(layer "In2.Cu")
	)
	(gr_line
		(start 29.642308 -172.158406)
		(end 29.66339 -172.12818)
		(stroke
			(width 0.08255)
			(type default)
		)
		(layer "In2.Cu")
	)
	(gr_line
		(start 29.647134 -444.409322)
		(end 29.784294 -443.63132)
		(stroke
			(width 0.08255)
			(type default)
		)
		(layer "In2.Cu")
	)
	(gr_line
		(start 29.66339 -172.12818)
		(end 29.66974 -172.092112)
		(stroke
			(width 0.08255)
			(type default)
		)
		(layer "In2.Cu")
	)
	(gr_line
		(start 29.684726 -47.013622)
		(end 29.684726 -47.013876)
		(stroke
			(width 0.08255)
			(type default)
		)
		(layer "In2.Cu")
	)
	(gr_line
		(start 29.684726 -47.013622)
		(end 29.690314 -46.982126)
		(stroke
			(width 0.08255)
			(type default)
		)
		(layer "In2.Cu")
	)
	(gr_line
		(start 29.69641 -350.285812)
		(end 29.717492 -350.255586)
		(stroke
			(width 0.08255)
			(type default)
		)
		(layer "In2.Cu")
	)
	(gr_line
		(start 29.70276 -434.581808)
		(end 30.350714 -434.12791)
		(stroke
			(width 0.08255)
			(type default)
		)
		(layer "In2.Cu")
	)
	(gr_line
		(start 29.7053 -128.520444)
		(end 29.726382 -128.55067)
		(stroke
			(width 0.08255)
			(type default)
		)
		(layer "In2.Cu")
	)
	(gr_line
		(start 29.71419 -327.150984)
		(end 29.929328 -327.301606)
		(stroke
			(width 0.08255)
			(type default)
		)
		(layer "In2.Cu")
	)
	(gr_line
		(start 29.717492 -350.255586)
		(end 29.723842 -350.219518)
		(stroke
			(width 0.08255)
			(type default)
		)
		(layer "In2.Cu")
	)
	(gr_line
		(start 29.72562 -235.558584)
		(end 29.940758 -235.407962)
		(stroke
			(width 0.08255)
			(type default)
		)
		(layer "In2.Cu")
	)
	(gr_line
		(start 29.726382 -128.55067)
		(end 29.732732 -128.586484)
		(stroke
			(width 0.08255)
			(type default)
		)
		(layer "In2.Cu")
	)
	(gr_line
		(start 29.763212 -228.570282)
		(end 30.408626 -228.118416)
		(stroke
			(width 0.08255)
			(type default)
		)
		(layer "In2.Cu")
	)
	(gr_line
		(start 29.773118 -133.096254)
		(end 29.85516 -133.56082)
		(stroke
			(width 0.08255)
			(type default)
		)
		(layer "In2.Cu")
	)
	(gr_line
		(start 29.794708 -331.496416)
		(end 29.928312 -332.25232)
		(stroke
			(width 0.08255)
			(type default)
		)
		(layer "In2.Cu")
	)
	(gr_line
		(start 29.809948 -428.978314)
		(end 30.054296 -429.021494)
		(stroke
			(width 0.08255)
			(type default)
		)
		(layer "In2.Cu")
	)
	(gr_line
		(start 29.835348 -424.133772)
		(end 29.890466 -423.89171)
		(stroke
			(width 0.08255)
			(type default)
		)
		(layer "In2.Cu")
	)
	(gr_line
		(start 29.865574 -328.008996)
		(end 29.951426 -328.496676)
		(stroke
			(width 0.08255)
			(type default)
		)
		(layer "In2.Cu")
	)
	(gr_line
		(start 29.865574 -328.008996)
		(end 30.015942 -327.794112)
		(stroke
			(width 0.08255)
			(type default)
		)
		(layer "In2.Cu")
	)
	(gr_line
		(start 29.872686 -249.411236)
		(end 29.890974 -249.398536)
		(stroke
			(width 0.08255)
			(type default)
		)
		(layer "In2.Cu")
	)
	(gr_line
		(start 29.877004 -234.700572)
		(end 29.96311 -234.212892)
		(stroke
			(width 0.08255)
			(type default)
		)
		(layer "In2.Cu")
	)
	(gr_line
		(start 29.877004 -234.700572)
		(end 30.027626 -234.91571)
		(stroke
			(width 0.08255)
			(type default)
		)
		(layer "In2.Cu")
	)
	(gr_line
		(start 29.88437 -443.063122)
		(end 30.021276 -442.28639)
		(stroke
			(width 0.08255)
			(type default)
		)
		(layer "In2.Cu")
	)
	(gr_line
		(start 29.890466 -423.89171)
		(end 30.30982 -423.628058)
		(stroke
			(width 0.08255)
			(type default)
		)
		(layer "In2.Cu")
	)
	(gr_line
		(start 29.890974 -249.398536)
		(end 29.903674 -249.380248)
		(stroke
			(width 0.08255)
			(type default)
		)
		(layer "In2.Cu")
	)
	(gr_line
		(start 29.909516 -276.009862)
		(end 29.930598 -275.979636)
		(stroke
			(width 0.08255)
			(type default)
		)
		(layer "In2.Cu")
	)
	(gr_line
		(start 29.915358 -15.55369)
		(end 29.933646 -15.56639)
		(stroke
			(width 0.08255)
			(type default)
		)
		(layer "In2.Cu")
	)
	(gr_line
		(start 29.917136 -433.767738)
		(end 30.175708 -433.813204)
		(stroke
			(width 0.08255)
			(type default)
		)
		(layer "In2.Cu")
	)
	(gr_line
		(start 29.930598 -275.979636)
		(end 29.936948 -275.943568)
		(stroke
			(width 0.08255)
			(type default)
		)
		(layer "In2.Cu")
	)
	(gr_line
		(start 29.933646 -15.56639)
		(end 29.946346 -15.584678)
		(stroke
			(width 0.08255)
			(type default)
		)
		(layer "In2.Cu")
	)
	(gr_line
		(start 29.951426 -328.496676)
		(end 30.166564 -328.647044)
		(stroke
			(width 0.08255)
			(type default)
		)
		(layer "In2.Cu")
	)
	(gr_line
		(start 29.96311 -234.212892)
		(end 30.177994 -234.062524)
		(stroke
			(width 0.08255)
			(type default)
		)
		(layer "In2.Cu")
	)
	(gr_line
		(start 29.97708 -227.756974)
		(end 30.235906 -227.80244)
		(stroke
			(width 0.08255)
			(type default)
		)
		(layer "In2.Cu")
	)
	(gr_line
		(start 29.985716 -255.762252)
		(end 29.992066 -255.726184)
		(stroke
			(width 0.08255)
			(type default)
		)
		(layer "In2.Cu")
	)
	(gr_line
		(start 29.992066 -255.726184)
		(end 30.013148 -255.695958)
		(stroke
			(width 0.08255)
			(type default)
		)
		(layer "In2.Cu")
	)
	(gr_line
		(start 30.010354 -325.78802)
		(end 30.031182 -325.817484)
		(stroke
			(width 0.08255)
			(type default)
		)
		(layer "In2.Cu")
	)
	(gr_line
		(start 30.028642 -332.820518)
		(end 30.1625 -333.577946)
		(stroke
			(width 0.08255)
			(type default)
		)
		(layer "In2.Cu")
	)
	(gr_line
		(start 30.030674 -178.759104)
		(end 30.0609 -178.738022)
		(stroke
			(width 0.08255)
			(type default)
		)
		(layer "In2.Cu")
	)
	(gr_line
		(start 30.031182 -325.817484)
		(end 30.037532 -325.853552)
		(stroke
			(width 0.08255)
			(type default)
		)
		(layer "In2.Cu")
	)
	(gr_line
		(start 30.057344 -130.468116)
		(end 30.0609 -130.447288)
		(stroke
			(width 0.08255)
			(type default)
		)
		(layer "In2.Cu")
	)
	(gr_line
		(start 30.057344 -130.467862)
		(end 30.057344 -130.468624)
		(stroke
			(width 0.08255)
			(type default)
		)
		(layer "In2.Cu")
	)
	(gr_line
		(start 30.057344 -130.426714)
		(end 30.0609 -130.447288)
		(stroke
			(width 0.08255)
			(type default)
		)
		(layer "In2.Cu")
	)
	(gr_line
		(start 30.058614 -424.41622)
		(end 30.709616 -424.00728)
		(stroke
			(width 0.08255)
			(type default)
		)
		(layer "In2.Cu")
	)
	(gr_line
		(start 30.0609 -178.738022)
		(end 30.096968 -178.731672)
		(stroke
			(width 0.08255)
			(type default)
		)
		(layer "In2.Cu")
	)
	(gr_line
		(start 30.06217 -351.56394)
		(end 30.080458 -351.55124)
		(stroke
			(width 0.08255)
			(type default)
		)
		(layer "In2.Cu")
	)
	(gr_line
		(start 30.080458 -351.55124)
		(end 30.093158 -351.532952)
		(stroke
			(width 0.08255)
			(type default)
		)
		(layer "In2.Cu")
	)
	(gr_line
		(start 30.10281 -329.354688)
		(end 30.188916 -329.842622)
		(stroke
			(width 0.08255)
			(type default)
		)
		(layer "In2.Cu")
	)
	(gr_line
		(start 30.10281 -329.354688)
		(end 30.253432 -329.139804)
		(stroke
			(width 0.08255)
			(type default)
		)
		(layer "In2.Cu")
	)
	(gr_line
		(start 30.108906 -150.902416)
		(end 30.115256 -150.866348)
		(stroke
			(width 0.08255)
			(type default)
		)
		(layer "In2.Cu")
	)
	(gr_line
		(start 30.11424 -233.35488)
		(end 30.200346 -232.8672)
		(stroke
			(width 0.08255)
			(type default)
		)
		(layer "In2.Cu")
	)
	(gr_line
		(start 30.11424 -233.35488)
		(end 30.264862 -233.569764)
		(stroke
			(width 0.08255)
			(type default)
		)
		(layer "In2.Cu")
	)
	(gr_line
		(start 30.115256 -150.866348)
		(end 30.136338 -150.836122)
		(stroke
			(width 0.08255)
			(type default)
		)
		(layer "In2.Cu")
	)
	(gr_line
		(start 30.13837 -326.42429)
		(end 30.275784 -327.203054)
		(stroke
			(width 0.08255)
			(type default)
		)
		(layer "In2.Cu")
	)
	(gr_line
		(start 30.148022 -347.814138)
		(end 30.151578 -347.79331)
		(stroke
			(width 0.08255)
			(type default)
		)
		(layer "In2.Cu")
	)
	(gr_line
		(start 30.148022 -347.813884)
		(end 30.148022 -347.814646)
		(stroke
			(width 0.08255)
			(type default)
		)
		(layer "In2.Cu")
	)
	(gr_line
		(start 30.148022 -347.772736)
		(end 30.151578 -347.79331)
		(stroke
			(width 0.08255)
			(type default)
		)
		(layer "In2.Cu")
	)
	(gr_line
		(start 30.149546 -236.286294)
		(end 30.28696 -235.507022)
		(stroke
			(width 0.08255)
			(type default)
		)
		(layer "In2.Cu")
	)
	(gr_line
		(start 30.188916 -329.842622)
		(end 30.4038 -329.99299)
		(stroke
			(width 0.08255)
			(type default)
		)
		(layer "In2.Cu")
	)
	(gr_line
		(start 30.200346 -232.8672)
		(end 30.41523 -232.716578)
		(stroke
			(width 0.08255)
			(type default)
		)
		(layer "In2.Cu")
	)
	(gr_line
		(start 30.226254 -223.471994)
		(end 30.271974 -223.213422)
		(stroke
			(width 0.08255)
			(type default)
		)
		(layer "In2.Cu")
	)
	(gr_line
		(start 30.261052 -38.200584)
		(end 30.282134 -38.23081)
		(stroke
			(width 0.08255)
			(type default)
		)
		(layer "In2.Cu")
	)
	(gr_line
		(start 30.27045 -145.83791)
		(end 30.291532 -145.807684)
		(stroke
			(width 0.08255)
			(type default)
		)
		(layer "In2.Cu")
	)
	(gr_line
		(start 30.271974 -223.213422)
		(end 30.677612 -222.92945)
		(stroke
			(width 0.08255)
			(type default)
		)
		(layer "In2.Cu")
	)
	(gr_line
		(start 30.275784 -119.058944)
		(end 30.294072 -119.071898)
		(stroke
			(width 0.08255)
			(type default)
		)
		(layer "In2.Cu")
	)
	(gr_line
		(start 30.282134 -38.23081)
		(end 30.288484 -38.266878)
		(stroke
			(width 0.08255)
			(type default)
		)
		(layer "In2.Cu")
	)
	(gr_line
		(start 30.291532 -145.807684)
		(end 30.297882 -145.771616)
		(stroke
			(width 0.08255)
			(type default)
		)
		(layer "In2.Cu")
	)
	(gr_line
		(start 30.294072 -119.071898)
		(end 30.306772 -119.090186)
		(stroke
			(width 0.08255)
			(type default)
		)
		(layer "In2.Cu")
	)
	(gr_line
		(start 30.30982 -423.628058)
		(end 30.551628 -423.68343)
		(stroke
			(width 0.08255)
			(type default)
		)
		(layer "In2.Cu")
	)
	(gr_line
		(start 30.351476 -69.478906)
		(end 30.372558 -69.44868)
		(stroke
			(width 0.08255)
			(type default)
		)
		(layer "In2.Cu")
	)
	(gr_line
		(start 30.364684 -25.241504)
		(end 30.382972 -25.254204)
		(stroke
			(width 0.08255)
			(type default)
		)
		(layer "In2.Cu")
	)
	(gr_line
		(start 30.365446 -26.17724)
		(end 30.411166 -25.918668)
		(stroke
			(width 0.08255)
			(type default)
		)
		(layer "In2.Cu")
	)
	(gr_line
		(start 30.365446 -26.17724)
		(end 30.649418 -26.582878)
		(stroke
			(width 0.08255)
			(type default)
		)
		(layer "In2.Cu")
	)
	(gr_line
		(start 30.372558 -69.44868)
		(end 30.378908 -69.412612)
		(stroke
			(width 0.08255)
			(type default)
		)
		(layer "In2.Cu")
	)
	(gr_line
		(start 30.375352 -327.76922)
		(end 30.512258 -328.545444)
		(stroke
			(width 0.08255)
			(type default)
		)
		(layer "In2.Cu")
	)
	(gr_line
		(start 30.382972 -25.254204)
		(end 30.395672 -25.272492)
		(stroke
			(width 0.08255)
			(type default)
		)
		(layer "In2.Cu")
	)
	(gr_line
		(start 30.387036 -234.938824)
		(end 30.523688 -234.16387)
		(stroke
			(width 0.08255)
			(type default)
		)
		(layer "In2.Cu")
	)
	(gr_line
		(start 30.409134 -17.206214)
		(end 30.456886 -16.93799)
		(stroke
			(width 0.08255)
			(type default)
		)
		(layer "In2.Cu")
	)
	(gr_line
		(start 30.409134 -17.206214)
		(end 30.72257 -17.654016)
		(stroke
			(width 0.08255)
			(type default)
		)
		(layer "In2.Cu")
	)
	(gr_line
		(start 30.463236 -223.74352)
		(end 31.11119 -223.289622)
		(stroke
			(width 0.08255)
			(type default)
		)
		(layer "In2.Cu")
	)
	(gr_line
		(start 30.463744 -428.734728)
		(end 30.506924 -428.49038)
		(stroke
			(width 0.08255)
			(type default)
		)
		(layer "In2.Cu")
	)
	(gr_line
		(start 30.49778 -232.26268)
		(end 30.50413 -232.226866)
		(stroke
			(width 0.08255)
			(type default)
		)
		(layer "In2.Cu")
	)
	(gr_line
		(start 30.50413 -232.226866)
		(end 30.525212 -232.19664)
		(stroke
			(width 0.08255)
			(type default)
		)
		(layer "In2.Cu")
	)
	(gr_line
		(start 30.506416 -245.633748)
		(end 30.52826 -245.60276)
		(stroke
			(width 0.08255)
			(type default)
		)
		(layer "In2.Cu")
	)
	(gr_line
		(start 30.506924 -428.49038)
		(end 30.912816 -428.206154)
		(stroke
			(width 0.08255)
			(type default)
		)
		(layer "In2.Cu")
	)
	(gr_line
		(start 30.50921 -340.816692)
		(end 30.512766 -340.83752)
		(stroke
			(width 0.08255)
			(type default)
		)
		(layer "In2.Cu")
	)
	(gr_line
		(start 30.50921 -340.816692)
		(end 30.512766 -340.796118)
		(stroke
			(width 0.08255)
			(type default)
		)
		(layer "In2.Cu")
	)
	(gr_line
		(start 30.512766 -340.837266)
		(end 30.512766 -340.838028)
		(stroke
			(width 0.08255)
			(type default)
		)
		(layer "In2.Cu")
	)
	(gr_line
		(start 30.52826 -245.60276)
		(end 30.535118 -245.56466)
		(stroke
			(width 0.08255)
			(type default)
		)
		(layer "In2.Cu")
	)
	(gr_line
		(start 30.575504 -350.844104)
		(end 30.596586 -350.813878)
		(stroke
			(width 0.08255)
			(type default)
		)
		(layer "In2.Cu")
	)
	(gr_line
		(start 30.585156 -433.526438)
		(end 30.635194 -433.243228)
		(stroke
			(width 0.08255)
			(type default)
		)
		(layer "In2.Cu")
	)
	(gr_line
		(start 30.596586 -350.813878)
		(end 30.602936 -350.778064)
		(stroke
			(width 0.08255)
			(type default)
		)
		(layer "In2.Cu")
	)
	(gr_line
		(start 30.612588 -329.115166)
		(end 30.749494 -329.89139)
		(stroke
			(width 0.08255)
			(type default)
		)
		(layer "In2.Cu")
	)
	(gr_line
		(start 30.624526 -233.592624)
		(end 30.760924 -232.81767)
		(stroke
			(width 0.08255)
			(type default)
		)
		(layer "In2.Cu")
	)
	(gr_line
		(start 30.635194 -433.243228)
		(end 31.011876 -432.979576)
		(stroke
			(width 0.08255)
			(type default)
		)
		(layer "In2.Cu")
	)
	(gr_line
		(start 30.6451 -227.515928)
		(end 30.69082 -227.257102)
		(stroke
			(width 0.08255)
			(type default)
		)
		(layer "In2.Cu")
	)
	(gr_line
		(start 30.649418 -26.582878)
		(end 30.90799 -26.628598)
		(stroke
			(width 0.08255)
			(type default)
		)
		(layer "In2.Cu")
	)
	(gr_line
		(start 30.667452 -336.47634)
		(end 30.671008 -336.455512)
		(stroke
			(width 0.08255)
			(type default)
		)
		(layer "In2.Cu")
	)
	(gr_line
		(start 30.667452 -336.476086)
		(end 30.667452 -336.476848)
		(stroke
			(width 0.08255)
			(type default)
		)
		(layer "In2.Cu")
	)
	(gr_line
		(start 30.667452 -336.434938)
		(end 30.671008 -336.455512)
		(stroke
			(width 0.08255)
			(type default)
		)
		(layer "In2.Cu")
	)
	(gr_line
		(start 30.677612 -222.92945)
		(end 30.936184 -222.974916)
		(stroke
			(width 0.08255)
			(type default)
		)
		(layer "In2.Cu")
	)
	(gr_line
		(start 30.69082 -227.257102)
		(end 31.096458 -226.97313)
		(stroke
			(width 0.08255)
			(type default)
		)
		(layer "In2.Cu")
	)
	(gr_line
		(start 30.693868 -439.130694)
		(end 30.737302 -439.375042)
		(stroke
			(width 0.08255)
			(type default)
		)
		(layer "In2.Cu")
	)
	(gr_line
		(start 30.693868 -439.130694)
		(end 30.977586 -438.724548)
		(stroke
			(width 0.08255)
			(type default)
		)
		(layer "In2.Cu")
	)
	(gr_line
		(start 30.699456 -429.007016)
		(end 31.331408 -428.564548)
		(stroke
			(width 0.08255)
			(type default)
		)
		(layer "In2.Cu")
	)
	(gr_line
		(start 30.72257 -17.654016)
		(end 30.991048 -17.701006)
		(stroke
			(width 0.08255)
			(type default)
		)
		(layer "In2.Cu")
	)
	(gr_line
		(start 30.725618 -124.240798)
		(end 30.743906 -124.253498)
		(stroke
			(width 0.08255)
			(type default)
		)
		(layer "In2.Cu")
	)
	(gr_line
		(start 30.72638 -125.176534)
		(end 30.7721 -124.917962)
		(stroke
			(width 0.08255)
			(type default)
		)
		(layer "In2.Cu")
	)
	(gr_line
		(start 30.72638 -125.176534)
		(end 31.010352 -125.582172)
		(stroke
			(width 0.08255)
			(type default)
		)
		(layer "In2.Cu")
	)
	(gr_line
		(start 30.726634 -25.744678)
		(end 31.180278 -26.392632)
		(stroke
			(width 0.08255)
			(type default)
		)
		(layer "In2.Cu")
	)
	(gr_line
		(start 30.743906 -124.253498)
		(end 30.756606 -124.271786)
		(stroke
			(width 0.08255)
			(type default)
		)
		(layer "In2.Cu")
	)
	(gr_line
		(start 30.754066 -40.949372)
		(end 30.757622 -40.928544)
		(stroke
			(width 0.08255)
			(type default)
		)
		(layer "In2.Cu")
	)
	(gr_line
		(start 30.754066 -40.949118)
		(end 30.754066 -40.94988)
		(stroke
			(width 0.08255)
			(type default)
		)
		(layer "In2.Cu")
	)
	(gr_line
		(start 30.754066 -40.90797)
		(end 30.757622 -40.928544)
		(stroke
			(width 0.08255)
			(type default)
		)
		(layer "In2.Cu")
	)
	(gr_line
		(start 30.7721 -16.763492)
		(end 31.263082 -17.464786)
		(stroke
			(width 0.08255)
			(type default)
		)
		(layer "In2.Cu")
	)
	(gr_line
		(start 30.821122 -433.798726)
		(end 31.470854 -433.343812)
		(stroke
			(width 0.08255)
			(type default)
		)
		(layer "In2.Cu")
	)
	(gr_line
		(start 30.82925 -286.444944)
		(end 30.859476 -286.423862)
		(stroke
			(width 0.08255)
			(type default)
		)
		(layer "In2.Cu")
	)
	(gr_line
		(start 30.845506 -266.276836)
		(end 30.851856 -266.240768)
		(stroke
			(width 0.08255)
			(type default)
		)
		(layer "In2.Cu")
	)
	(gr_line
		(start 30.851856 -266.240768)
		(end 30.872938 -266.210542)
		(stroke
			(width 0.08255)
			(type default)
		)
		(layer "In2.Cu")
	)
	(gr_line
		(start 30.852872 -172.463206)
		(end 30.873954 -172.43298)
		(stroke
			(width 0.08255)
			(type default)
		)
		(layer "In2.Cu")
	)
	(gr_line
		(start 30.859476 -286.423862)
		(end 30.895544 -286.417512)
		(stroke
			(width 0.08255)
			(type default)
		)
		(layer "In2.Cu")
	)
	(gr_line
		(start 30.867604 -352.283268)
		(end 30.885638 -352.270568)
		(stroke
			(width 0.08255)
			(type default)
		)
		(layer "In2.Cu")
	)
	(gr_line
		(start 30.873954 -172.43298)
		(end 30.880304 -172.396912)
		(stroke
			(width 0.08255)
			(type default)
		)
		(layer "In2.Cu")
	)
	(gr_line
		(start 30.882336 -227.786946)
		(end 31.53029 -227.333302)
		(stroke
			(width 0.08255)
			(type default)
		)
		(layer "In2.Cu")
	)
	(gr_line
		(start 30.885638 -352.270568)
		(end 30.8991 -352.251518)
		(stroke
			(width 0.08255)
			(type default)
		)
		(layer "In2.Cu")
	)
	(gr_line
		(start 30.88767 -256.162048)
		(end 30.89402 -256.126234)
		(stroke
			(width 0.08255)
			(type default)
		)
		(layer "In2.Cu")
	)
	(gr_line
		(start 30.89402 -256.126234)
		(end 30.915102 -256.096008)
		(stroke
			(width 0.08255)
			(type default)
		)
		(layer "In2.Cu")
	)
	(gr_line
		(start 30.912816 -428.206154)
		(end 31.15691 -428.249334)
		(stroke
			(width 0.08255)
			(type default)
		)
		(layer "In2.Cu")
	)
	(gr_line
		(start 30.950154 -215.583262)
		(end 30.979618 -215.562434)
		(stroke
			(width 0.08255)
			(type default)
		)
		(layer "In2.Cu")
	)
	(gr_line
		(start 30.975046 -423.417492)
		(end 31.030418 -423.17543)
		(stroke
			(width 0.08255)
			(type default)
		)
		(layer "In2.Cu")
	)
	(gr_line
		(start 30.977586 -438.724548)
		(end 31.221934 -438.681114)
		(stroke
			(width 0.08255)
			(type default)
		)
		(layer "In2.Cu")
	)
	(gr_line
		(start 30.979618 -215.562434)
		(end 31.015686 -215.556084)
		(stroke
			(width 0.08255)
			(type default)
		)
		(layer "In2.Cu")
	)
	(gr_line
		(start 31.010352 -125.582172)
		(end 31.268924 -125.627892)
		(stroke
			(width 0.08255)
			(type default)
		)
		(layer "In2.Cu")
	)
	(gr_line
		(start 31.011876 -432.979576)
		(end 31.295086 -433.02936)
		(stroke
			(width 0.08255)
			(type default)
		)
		(layer "In2.Cu")
	)
	(gr_line
		(start 31.030418 -423.17543)
		(end 31.449772 -422.911778)
		(stroke
			(width 0.08255)
			(type default)
		)
		(layer "In2.Cu")
	)
	(gr_line
		(start 31.05023 -151.242014)
		(end 31.05658 -151.2062)
		(stroke
			(width 0.08255)
			(type default)
		)
		(layer "In2.Cu")
	)
	(gr_line
		(start 31.053278 -439.548016)
		(end 31.494476 -438.916572)
		(stroke
			(width 0.08255)
			(type default)
		)
		(layer "In2.Cu")
	)
	(gr_line
		(start 31.05658 -151.2062)
		(end 31.077662 -151.175974)
		(stroke
			(width 0.08255)
			(type default)
		)
		(layer "In2.Cu")
	)
	(gr_line
		(start 31.087568 -124.743972)
		(end 31.54045 -125.391164)
		(stroke
			(width 0.08255)
			(type default)
		)
		(layer "In2.Cu")
	)
	(gr_line
		(start 31.096458 -226.97313)
		(end 31.355284 -227.018596)
		(stroke
			(width 0.08255)
			(type default)
		)
		(layer "In2.Cu")
	)
	(gr_line
		(start 31.103316 -347.941646)
		(end 31.106872 -347.920818)
		(stroke
			(width 0.08255)
			(type default)
		)
		(layer "In2.Cu")
	)
	(gr_line
		(start 31.103316 -347.941392)
		(end 31.103316 -347.942154)
		(stroke
			(width 0.08255)
			(type default)
		)
		(layer "In2.Cu")
	)
	(gr_line
		(start 31.103316 -347.900244)
		(end 31.106872 -347.920818)
		(stroke
			(width 0.08255)
			(type default)
		)
		(layer "In2.Cu")
	)
	(gr_line
		(start 31.1277 -247.632728)
		(end 31.148782 -247.602502)
		(stroke
			(width 0.08255)
			(type default)
		)
		(layer "In2.Cu")
	)
	(gr_line
		(start 31.148782 -247.602502)
		(end 31.155132 -247.566434)
		(stroke
			(width 0.08255)
			(type default)
		)
		(layer "In2.Cu")
	)
	(gr_line
		(start 31.14929 -27.296618)
		(end 31.19501 -27.0383)
		(stroke
			(width 0.08255)
			(type default)
		)
		(layer "In2.Cu")
	)
	(gr_line
		(start 31.14929 -27.296618)
		(end 31.433262 -27.702256)
		(stroke
			(width 0.08255)
			(type default)
		)
		(layer "In2.Cu")
	)
	(gr_line
		(start 31.149798 -140.941044)
		(end 31.153354 -140.920216)
		(stroke
			(width 0.08255)
			(type default)
		)
		(layer "In2.Cu")
	)
	(gr_line
		(start 31.149798 -140.94079)
		(end 31.149798 -140.941552)
		(stroke
			(width 0.08255)
			(type default)
		)
		(layer "In2.Cu")
	)
	(gr_line
		(start 31.149798 -140.899642)
		(end 31.153354 -140.920216)
		(stroke
			(width 0.08255)
			(type default)
		)
		(layer "In2.Cu")
	)
	(gr_line
		(start 31.197042 -423.700956)
		(end 31.84906 -423.291254)
		(stroke
			(width 0.08255)
			(type default)
		)
		(layer "In2.Cu")
	)
	(gr_line
		(start 31.218632 -146.15287)
		(end 31.239714 -146.122644)
		(stroke
			(width 0.08255)
			(type default)
		)
		(layer "In2.Cu")
	)
	(gr_line
		(start 31.239714 -146.122644)
		(end 31.246064 -146.086576)
		(stroke
			(width 0.08255)
			(type default)
		)
		(layer "In2.Cu")
	)
	(gr_line
		(start 31.259526 -18.420842)
		(end 31.307278 -18.152618)
		(stroke
			(width 0.08255)
			(type default)
		)
		(layer "In2.Cu")
	)
	(gr_line
		(start 31.259526 -18.420842)
		(end 31.572962 -18.868644)
		(stroke
			(width 0.08255)
			(type default)
		)
		(layer "In2.Cu")
	)
	(gr_line
		(start 31.345632 -222.68815)
		(end 31.391352 -222.429578)
		(stroke
			(width 0.08255)
			(type default)
		)
		(layer "In2.Cu")
	)
	(gr_line
		(start 31.391352 -222.429578)
		(end 31.79699 -222.145606)
		(stroke
			(width 0.08255)
			(type default)
		)
		(layer "In2.Cu")
	)
	(gr_line
		(start 31.433262 -27.702256)
		(end 31.691834 -27.747976)
		(stroke
			(width 0.08255)
			(type default)
		)
		(layer "In2.Cu")
	)
	(gr_line
		(start 31.449772 -422.911778)
		(end 31.69158 -422.96715)
		(stroke
			(width 0.08255)
			(type default)
		)
		(layer "In2.Cu")
	)
	(gr_line
		(start 31.459678 -121.684288)
		(end 31.505144 -121.425716)
		(stroke
			(width 0.08255)
			(type default)
		)
		(layer "In2.Cu")
	)
	(gr_line
		(start 31.459678 -121.684288)
		(end 31.74365 -122.09018)
		(stroke
			(width 0.08255)
			(type default)
		)
		(layer "In2.Cu")
	)
	(gr_line
		(start 31.464758 -438.027064)
		(end 31.508192 -438.271666)
		(stroke
			(width 0.08255)
			(type default)
		)
		(layer "In2.Cu")
	)
	(gr_line
		(start 31.464758 -438.027064)
		(end 31.748476 -437.620918)
		(stroke
			(width 0.08255)
			(type default)
		)
		(layer "In2.Cu")
	)
	(gr_line
		(start 31.483554 -351.41535)
		(end 31.504636 -351.385124)
		(stroke
			(width 0.08255)
			(type default)
		)
		(layer "In2.Cu")
	)
	(gr_line
		(start 31.492698 -238.07801)
		(end 31.499048 -238.041942)
		(stroke
			(width 0.08255)
			(type default)
		)
		(layer "In2.Cu")
	)
	(gr_line
		(start 31.499048 -238.041942)
		(end 31.52013 -238.011716)
		(stroke
			(width 0.08255)
			(type default)
		)
		(layer "In2.Cu")
	)
	(gr_line
		(start 31.504636 -351.385124)
		(end 31.50489 -351.385124)
		(stroke
			(width 0.08255)
			(type default)
		)
		(layer "In2.Cu")
	)
	(gr_line
		(start 31.50489 -351.385124)
		(end 31.511748 -351.34677)
		(stroke
			(width 0.08255)
			(type default)
		)
		(layer "In2.Cu")
	)
	(gr_line
		(start 31.510224 -126.295912)
		(end 31.555944 -126.037594)
		(stroke
			(width 0.08255)
			(type default)
		)
		(layer "In2.Cu")
	)
	(gr_line
		(start 31.510224 -126.295912)
		(end 31.794196 -126.70155)
		(stroke
			(width 0.08255)
			(type default)
		)
		(layer "In2.Cu")
	)
	(gr_line
		(start 31.510478 -26.864056)
		(end 31.963868 -27.511756)
		(stroke
			(width 0.08255)
			(type default)
		)
		(layer "In2.Cu")
	)
	(gr_line
		(start 31.547562 -39.000684)
		(end 31.633414 -38.513004)
		(stroke
			(width 0.08255)
			(type default)
		)
		(layer "In2.Cu")
	)
	(gr_line
		(start 31.547562 -39.000684)
		(end 31.69793 -39.215568)
		(stroke
			(width 0.08255)
			(type default)
		)
		(layer "In2.Cu")
	)
	(gr_line
		(start 31.572962 -18.868644)
		(end 31.84144 -18.915634)
		(stroke
			(width 0.08255)
			(type default)
		)
		(layer "In2.Cu")
	)
	(gr_line
		(start 31.581344 -222.960692)
		(end 32.231838 -222.505016)
		(stroke
			(width 0.08255)
			(type default)
		)
		(layer "In2.Cu")
	)
	(gr_line
		(start 31.621984 -17.977104)
		(end 32.113728 -18.679668)
		(stroke
			(width 0.08255)
			(type default)
		)
		(layer "In2.Cu")
	)
	(gr_line
		(start 31.62681 -60.288678)
		(end 31.63316 -60.25261)
		(stroke
			(width 0.08255)
			(type default)
		)
		(layer "In2.Cu")
	)
	(gr_line
		(start 31.63316 -60.25261)
		(end 31.654242 -60.222384)
		(stroke
			(width 0.08255)
			(type default)
		)
		(layer "In2.Cu")
	)
	(gr_line
		(start 31.633414 -38.513004)
		(end 31.848552 -38.362128)
		(stroke
			(width 0.08255)
			(type default)
		)
		(layer "In2.Cu")
	)
	(gr_line
		(start 31.74365 -122.09018)
		(end 32.002222 -122.135646)
		(stroke
			(width 0.08255)
			(type default)
		)
		(layer "In2.Cu")
	)
	(gr_line
		(start 31.748476 -437.620918)
		(end 31.993078 -437.577484)
		(stroke
			(width 0.08255)
			(type default)
		)
		(layer "In2.Cu")
	)
	(gr_line
		(start 31.769558 -335.71688)
		(end 31.773114 -335.696052)
		(stroke
			(width 0.08255)
			(type default)
		)
		(layer "In2.Cu")
	)
	(gr_line
		(start 31.769558 -335.716626)
		(end 31.769558 -335.717388)
		(stroke
			(width 0.08255)
			(type default)
		)
		(layer "In2.Cu")
	)
	(gr_line
		(start 31.769558 -335.675478)
		(end 31.773114 -335.696052)
		(stroke
			(width 0.08255)
			(type default)
		)
		(layer "In2.Cu")
	)
	(gr_line
		(start 31.784798 -37.654992)
		(end 31.87065 -37.167312)
		(stroke
			(width 0.08255)
			(type default)
		)
		(layer "In2.Cu")
	)
	(gr_line
		(start 31.784798 -37.654992)
		(end 31.935166 -37.869876)
		(stroke
			(width 0.08255)
			(type default)
		)
		(layer "In2.Cu")
	)
	(gr_line
		(start 31.794196 -126.70155)
		(end 32.052768 -126.74727)
		(stroke
			(width 0.08255)
			(type default)
		)
		(layer "In2.Cu")
	)
	(gr_line
		(start 31.79699 -222.145606)
		(end 32.055816 -222.191072)
		(stroke
			(width 0.08255)
			(type default)
		)
		(layer "In2.Cu")
	)
	(gr_line
		(start 31.81985 -256.463546)
		(end 31.8262 -256.427478)
		(stroke
			(width 0.08255)
			(type default)
		)
		(layer "In2.Cu")
	)
	(gr_line
		(start 31.820104 -121.251218)
		(end 32.27324 -121.898156)
		(stroke
			(width 0.08255)
			(type default)
		)
		(layer "In2.Cu")
	)
	(gr_line
		(start 31.822644 -438.446926)
		(end 32.266636 -437.811418)
		(stroke
			(width 0.08255)
			(type default)
		)
		(layer "In2.Cu")
	)
	(gr_line
		(start 31.8262 -256.427478)
		(end 31.847282 -256.397252)
		(stroke
			(width 0.08255)
			(type default)
		)
		(layer "In2.Cu")
	)
	(gr_line
		(start 31.87065 -37.167312)
		(end 32.085788 -37.016436)
		(stroke
			(width 0.08255)
			(type default)
		)
		(layer "In2.Cu")
	)
	(gr_line
		(start 31.871666 -125.864366)
		(end 32.323532 -126.509526)
		(stroke
			(width 0.08255)
			(type default)
		)
		(layer "In2.Cu")
	)
	(gr_line
		(start 31.939992 -151.659844)
		(end 31.946342 -151.623776)
		(stroke
			(width 0.08255)
			(type default)
		)
		(layer "In2.Cu")
	)
	(gr_line
		(start 31.946342 -151.623776)
		(end 31.967424 -151.59355)
		(stroke
			(width 0.08255)
			(type default)
		)
		(layer "In2.Cu")
	)
	(gr_line
		(start 32.022034 -36.3093)
		(end 32.107886 -35.82162)
		(stroke
			(width 0.08255)
			(type default)
		)
		(layer "In2.Cu")
	)
	(gr_line
		(start 32.022034 -36.3093)
		(end 32.172402 -36.524184)
		(stroke
			(width 0.08255)
			(type default)
		)
		(layer "In2.Cu")
	)
	(gr_line
		(start 32.026098 -247.945402)
		(end 32.04718 -247.915176)
		(stroke
			(width 0.08255)
			(type default)
		)
		(layer "In2.Cu")
	)
	(gr_line
		(start 32.04718 -247.915176)
		(end 32.05353 -247.879362)
		(stroke
			(width 0.08255)
			(type default)
		)
		(layer "In2.Cu")
	)
	(gr_line
		(start 32.057594 -39.239698)
		(end 32.1945 -38.462458)
		(stroke
			(width 0.08255)
			(type default)
		)
		(layer "In2.Cu")
	)
	(gr_line
		(start 32.107886 -35.82162)
		(end 32.323024 -35.670744)
		(stroke
			(width 0.08255)
			(type default)
		)
		(layer "In2.Cu")
	)
	(gr_line
		(start 32.109918 -19.63547)
		(end 32.15767 -19.366992)
		(stroke
			(width 0.08255)
			(type default)
		)
		(layer "In2.Cu")
	)
	(gr_line
		(start 32.109918 -19.63547)
		(end 32.423354 -20.083272)
		(stroke
			(width 0.08255)
			(type default)
		)
		(layer "In2.Cu")
	)
	(gr_line
		(start 32.11576 -347.92158)
		(end 32.119316 -347.900752)
		(stroke
			(width 0.08255)
			(type default)
		)
		(layer "In2.Cu")
	)
	(gr_line
		(start 32.11576 -347.921326)
		(end 32.11576 -347.922088)
		(stroke
			(width 0.08255)
			(type default)
		)
		(layer "In2.Cu")
	)
	(gr_line
		(start 32.11576 -347.880178)
		(end 32.119316 -347.900752)
		(stroke
			(width 0.08255)
			(type default)
		)
		(layer "In2.Cu")
	)
	(gr_line
		(start 32.1183 -264.432288)
		(end 32.131 -264.414)
		(stroke
			(width 0.08255)
			(type default)
		)
		(layer "In2.Cu")
	)
	(gr_line
		(start 32.12084 -163.31311)
		(end 32.12719 -163.277042)
		(stroke
			(width 0.08255)
			(type default)
		)
		(layer "In2.Cu")
	)
	(gr_line
		(start 32.12719 -163.277042)
		(end 32.148272 -163.246816)
		(stroke
			(width 0.08255)
			(type default)
		)
		(layer "In2.Cu")
	)
	(gr_line
		(start 32.131 -264.414)
		(end 32.149288 -264.4013)
		(stroke
			(width 0.08255)
			(type default)
		)
		(layer "In2.Cu")
	)
	(gr_line
		(start 32.134048 -384.2893)
		(end 32.154622 -384.292856)
		(stroke
			(width 0.08255)
			(type default)
		)
		(layer "In2.Cu")
	)
	(gr_line
		(start 32.153606 -146.432524)
		(end 32.175196 -146.401536)
		(stroke
			(width 0.08255)
			(type default)
		)
		(layer "In2.Cu")
	)
	(gr_line
		(start 32.154622 -384.292856)
		(end 32.175196 -384.2893)
		(stroke
			(width 0.08255)
			(type default)
		)
		(layer "In2.Cu")
	)
	(gr_line
		(start 32.175196 -146.401536)
		(end 32.1818 -146.364706)
		(stroke
			(width 0.08255)
			(type default)
		)
		(layer "In2.Cu")
	)
	(gr_line
		(start 32.188912 -21.249132)
		(end 32.20974 -21.263864)
		(stroke
			(width 0.08255)
			(type default)
		)
		(layer "In2.Cu")
	)
	(gr_line
		(start 32.20974 -21.263864)
		(end 32.223202 -21.282914)
		(stroke
			(width 0.08255)
			(type default)
		)
		(layer "In2.Cu")
	)
	(gr_line
		(start 32.235648 -436.923434)
		(end 32.279082 -437.168036)
		(stroke
			(width 0.08255)
			(type default)
		)
		(layer "In2.Cu")
	)
	(gr_line
		(start 32.235648 -436.923434)
		(end 32.519366 -436.517288)
		(stroke
			(width 0.08255)
			(type default)
		)
		(layer "In2.Cu")
	)
	(gr_line
		(start 32.243522 -122.803666)
		(end 32.289242 -122.545348)
		(stroke
			(width 0.08255)
			(type default)
		)
		(layer "In2.Cu")
	)
	(gr_line
		(start 32.243522 -122.803666)
		(end 32.527748 -123.209304)
		(stroke
			(width 0.08255)
			(type default)
		)
		(layer "In2.Cu")
	)
	(gr_line
		(start 32.25927 -34.963608)
		(end 32.345376 -34.475928)
		(stroke
			(width 0.08255)
			(type default)
		)
		(layer "In2.Cu")
	)
	(gr_line
		(start 32.25927 -34.963608)
		(end 32.409638 -35.178492)
		(stroke
			(width 0.08255)
			(type default)
		)
		(layer "In2.Cu")
	)
	(gr_line
		(start 32.294068 -127.41529)
		(end 32.339788 -127.156972)
		(stroke
			(width 0.08255)
			(type default)
		)
		(layer "In2.Cu")
	)
	(gr_line
		(start 32.294068 -127.41529)
		(end 32.57804 -127.820928)
		(stroke
			(width 0.08255)
			(type default)
		)
		(layer "In2.Cu")
	)
	(gr_line
		(start 32.29483 -37.89299)
		(end 32.431736 -37.116766)
		(stroke
			(width 0.08255)
			(type default)
		)
		(layer "In2.Cu")
	)
	(gr_line
		(start 32.345376 -34.475928)
		(end 32.56026 -34.325306)
		(stroke
			(width 0.08255)
			(type default)
		)
		(layer "In2.Cu")
	)
	(gr_line
		(start 32.403034 -238.439198)
		(end 32.409384 -238.40313)
		(stroke
			(width 0.08255)
			(type default)
		)
		(layer "In2.Cu")
	)
	(gr_line
		(start 32.409384 -238.40313)
		(end 32.430466 -238.372904)
		(stroke
			(width 0.08255)
			(type default)
		)
		(layer "In2.Cu")
	)
	(gr_line
		(start 32.423354 -20.083272)
		(end 32.691832 -20.130262)
		(stroke
			(width 0.08255)
			(type default)
		)
		(layer "In2.Cu")
	)
	(gr_line
		(start 32.472122 -19.191478)
		(end 32.964374 -19.89455)
		(stroke
			(width 0.08255)
			(type default)
		)
		(layer "In2.Cu")
	)
	(gr_line
		(start 32.519366 -436.517288)
		(end 32.764222 -436.473854)
		(stroke
			(width 0.08255)
			(type default)
		)
		(layer "In2.Cu")
	)
	(gr_line
		(start 32.527748 -123.209304)
		(end 32.786066 -123.255024)
		(stroke
			(width 0.08255)
			(type default)
		)
		(layer "In2.Cu")
	)
	(gr_line
		(start 32.532066 -36.547298)
		(end 32.668972 -35.771074)
		(stroke
			(width 0.08255)
			(type default)
		)
		(layer "In2.Cu")
	)
	(gr_line
		(start 32.565086 -276.543008)
		(end 32.595312 -276.521926)
		(stroke
			(width 0.08255)
			(type default)
		)
		(layer "In2.Cu")
	)
	(gr_line
		(start 32.57804 -127.820928)
		(end 32.836612 -127.866648)
		(stroke
			(width 0.08255)
			(type default)
		)
		(layer "In2.Cu")
	)
	(gr_line
		(start 32.593534 -437.343296)
		(end 33.037526 -436.707788)
		(stroke
			(width 0.08255)
			(type default)
		)
		(layer "In2.Cu")
	)
	(gr_line
		(start 32.595312 -276.521926)
		(end 32.631126 -276.515576)
		(stroke
			(width 0.08255)
			(type default)
		)
		(layer "In2.Cu")
	)
	(gr_line
		(start 32.605218 -122.37212)
		(end 33.057846 -123.018296)
		(stroke
			(width 0.08255)
			(type default)
		)
		(layer "In2.Cu")
	)
	(gr_line
		(start 32.639762 -23.387812)
		(end 32.725614 -23.875492)
		(stroke
			(width 0.08255)
			(type default)
		)
		(layer "In2.Cu")
	)
	(gr_line
		(start 32.639762 -23.387812)
		(end 32.79013 -23.172928)
		(stroke
			(width 0.08255)
			(type default)
		)
		(layer "In2.Cu")
	)
	(gr_line
		(start 32.656272 -126.985014)
		(end 33.107122 -127.62865)
		(stroke
			(width 0.08255)
			(type default)
		)
		(layer "In2.Cu")
	)
	(gr_line
		(start 32.667194 -28.516326)
		(end 32.688276 -28.546552)
		(stroke
			(width 0.08255)
			(type default)
		)
		(layer "In2.Cu")
	)
	(gr_line
		(start 32.688276 -28.546552)
		(end 32.694626 -28.582366)
		(stroke
			(width 0.08255)
			(type default)
		)
		(layer "In2.Cu")
	)
	(gr_line
		(start 32.725614 -23.875492)
		(end 32.940498 -24.026368)
		(stroke
			(width 0.08255)
			(type default)
		)
		(layer "In2.Cu")
	)
	(gr_line
		(start 32.769302 -35.201606)
		(end 32.905954 -34.426906)
		(stroke
			(width 0.08255)
			(type default)
		)
		(layer "In2.Cu")
	)
	(gr_line
		(start 32.777176 -70.499478)
		(end 32.807402 -70.478396)
		(stroke
			(width 0.08255)
			(type default)
		)
		(layer "In2.Cu")
	)
	(gr_line
		(start 32.807402 -70.478396)
		(end 32.84347 -70.472046)
		(stroke
			(width 0.08255)
			(type default)
		)
		(layer "In2.Cu")
	)
	(gr_line
		(start 32.853376 -151.988012)
		(end 32.859726 -151.951944)
		(stroke
			(width 0.08255)
			(type default)
		)
		(layer "In2.Cu")
	)
	(gr_line
		(start 32.859726 -151.951944)
		(end 32.880808 -151.921718)
		(stroke
			(width 0.08255)
			(type default)
		)
		(layer "In2.Cu")
	)
	(gr_line
		(start 32.876998 -24.733504)
		(end 32.96285 -25.221184)
		(stroke
			(width 0.08255)
			(type default)
		)
		(layer "In2.Cu")
	)
	(gr_line
		(start 32.876998 -24.733504)
		(end 33.027366 -24.51862)
		(stroke
			(width 0.08255)
			(type default)
		)
		(layer "In2.Cu")
	)
	(gr_line
		(start 32.96031 -20.850098)
		(end 33.008062 -20.58162)
		(stroke
			(width 0.08255)
			(type default)
		)
		(layer "In2.Cu")
	)
	(gr_line
		(start 32.96031 -20.850098)
		(end 33.273746 -21.2979)
		(stroke
			(width 0.08255)
			(type default)
		)
		(layer "In2.Cu")
	)
	(gr_line
		(start 32.96285 -25.221184)
		(end 33.177988 -25.37206)
		(stroke
			(width 0.08255)
			(type default)
		)
		(layer "In2.Cu")
	)
	(gr_line
		(start 33.000442 -22.392386)
		(end 33.021524 -22.422612)
		(stroke
			(width 0.08255)
			(type default)
		)
		(layer "In2.Cu")
	)
	(gr_line
		(start 33.000696 -248.222516)
		(end 33.021778 -248.19229)
		(stroke
			(width 0.08255)
			(type default)
		)
		(layer "In2.Cu")
	)
	(gr_line
		(start 33.006538 -435.819804)
		(end 33.049972 -436.06466)
		(stroke
			(width 0.08255)
			(type default)
		)
		(layer "In2.Cu")
	)
	(gr_line
		(start 33.006538 -435.819804)
		(end 33.290256 -435.413658)
		(stroke
			(width 0.08255)
			(type default)
		)
		(layer "In2.Cu")
	)
	(gr_line
		(start 33.021524 -22.422612)
		(end 33.027874 -22.45868)
		(stroke
			(width 0.08255)
			(type default)
		)
		(layer "In2.Cu")
	)
	(gr_line
		(start 33.021778 -248.19229)
		(end 33.028128 -248.156476)
		(stroke
			(width 0.08255)
			(type default)
		)
		(layer "In2.Cu")
	)
	(gr_line
		(start 33.027366 -123.923044)
		(end 33.073086 -123.664726)
		(stroke
			(width 0.08255)
			(type default)
		)
		(layer "In2.Cu")
	)
	(gr_line
		(start 33.027366 -123.923044)
		(end 33.311592 -124.328682)
		(stroke
			(width 0.08255)
			(type default)
		)
		(layer "In2.Cu")
	)
	(gr_line
		(start 33.05556 -58.22061)
		(end 33.06826 -58.202322)
		(stroke
			(width 0.08255)
			(type default)
		)
		(layer "In2.Cu")
	)
	(gr_line
		(start 33.06826 -58.202322)
		(end 33.086548 -58.189622)
		(stroke
			(width 0.08255)
			(type default)
		)
		(layer "In2.Cu")
	)
	(gr_line
		(start 33.105852 -203.35875)
		(end 33.25622 -203.573634)
		(stroke
			(width 0.08255)
			(type default)
		)
		(layer "In2.Cu")
	)
	(gr_line
		(start 33.114234 -26.079196)
		(end 33.200086 -26.566876)
		(stroke
			(width 0.08255)
			(type default)
		)
		(layer "In2.Cu")
	)
	(gr_line
		(start 33.114234 -26.079196)
		(end 33.264602 -25.864312)
		(stroke
			(width 0.08255)
			(type default)
		)
		(layer "In2.Cu")
	)
	(gr_line
		(start 33.149794 -23.149052)
		(end 33.287208 -23.927816)
		(stroke
			(width 0.08255)
			(type default)
		)
		(layer "In2.Cu")
	)
	(gr_line
		(start 33.200086 -26.566876)
		(end 33.415224 -26.717752)
		(stroke
			(width 0.08255)
			(type default)
		)
		(layer "In2.Cu")
	)
	(gr_line
		(start 33.207198 -203.012802)
		(end 33.98266 -203.149454)
		(stroke
			(width 0.08255)
			(type default)
		)
		(layer "In2.Cu")
	)
	(gr_line
		(start 33.23336 -431.672238)
		(end 33.27908 -431.413666)
		(stroke
			(width 0.08255)
			(type default)
		)
		(layer "In2.Cu")
	)
	(gr_line
		(start 33.25622 -203.573634)
		(end 33.7439 -203.659486)
		(stroke
			(width 0.08255)
			(type default)
		)
		(layer "In2.Cu")
	)
	(gr_line
		(start 33.269174 -238.938816)
		(end 33.275524 -238.903002)
		(stroke
			(width 0.08255)
			(type default)
		)
		(layer "In2.Cu")
	)
	(gr_line
		(start 33.273746 -21.2979)
		(end 33.542478 -21.34489)
		(stroke
			(width 0.08255)
			(type default)
		)
		(layer "In2.Cu")
	)
	(gr_line
		(start 33.275524 -238.903002)
		(end 33.296606 -238.872776)
		(stroke
			(width 0.08255)
			(type default)
		)
		(layer "In2.Cu")
	)
	(gr_line
		(start 33.27908 -431.413666)
		(end 33.684718 -431.12944)
		(stroke
			(width 0.08255)
			(type default)
		)
		(layer "In2.Cu")
	)
	(gr_line
		(start 33.290256 -435.413658)
		(end 33.535112 -435.370224)
		(stroke
			(width 0.08255)
			(type default)
		)
		(layer "In2.Cu")
	)
	(gr_line
		(start 33.311592 -124.328682)
		(end 33.56991 -124.374402)
		(stroke
			(width 0.08255)
			(type default)
		)
		(layer "In2.Cu")
	)
	(gr_line
		(start 33.3121 -32.123888)
		(end 33.315656 -32.10306)
		(stroke
			(width 0.08255)
			(type default)
		)
		(layer "In2.Cu")
	)
	(gr_line
		(start 33.3121 -32.123634)
		(end 33.3121 -32.124396)
		(stroke
			(width 0.08255)
			(type default)
		)
		(layer "In2.Cu")
	)
	(gr_line
		(start 33.3121 -32.082486)
		(end 33.315656 -32.10306)
		(stroke
			(width 0.08255)
			(type default)
		)
		(layer "In2.Cu")
	)
	(gr_line
		(start 33.312354 -263.586722)
		(end 33.34258 -263.56564)
		(stroke
			(width 0.08255)
			(type default)
		)
		(layer "In2.Cu")
	)
	(gr_line
		(start 33.322768 -20.406868)
		(end 33.81375 -21.108162)
		(stroke
			(width 0.08255)
			(type default)
		)
		(layer "In2.Cu")
	)
	(gr_line
		(start 33.33369 -173.401736)
		(end 33.363916 -173.380654)
		(stroke
			(width 0.08255)
			(type default)
		)
		(layer "In2.Cu")
	)
	(gr_line
		(start 33.34258 -263.56564)
		(end 33.378394 -263.55929)
		(stroke
			(width 0.08255)
			(type default)
		)
		(layer "In2.Cu")
	)
	(gr_line
		(start 33.35147 -27.424888)
		(end 33.437576 -27.912568)
		(stroke
			(width 0.08255)
			(type default)
		)
		(layer "In2.Cu")
	)
	(gr_line
		(start 33.35147 -27.424888)
		(end 33.502092 -27.210004)
		(stroke
			(width 0.08255)
			(type default)
		)
		(layer "In2.Cu")
	)
	(gr_line
		(start 33.363916 -173.380654)
		(end 33.39973 -173.374304)
		(stroke
			(width 0.08255)
			(type default)
		)
		(layer "In2.Cu")
	)
	(gr_line
		(start 33.364424 -436.239666)
		(end 33.808416 -435.604158)
		(stroke
			(width 0.08255)
			(type default)
		)
		(layer "In2.Cu")
	)
	(gr_line
		(start 33.386776 -24.493982)
		(end 33.523682 -25.27173)
		(stroke
			(width 0.08255)
			(type default)
		)
		(layer "In2.Cu")
	)
	(gr_line
		(start 33.389062 -123.491498)
		(end 33.841182 -124.137166)
		(stroke
			(width 0.08255)
			(type default)
		)
		(layer "In2.Cu")
	)
	(gr_line
		(start 33.413446 -281.168856)
		(end 33.443672 -281.147774)
		(stroke
			(width 0.08255)
			(type default)
		)
		(layer "In2.Cu")
	)
	(gr_line
		(start 33.437576 -27.912568)
		(end 33.65246 -28.06319)
		(stroke
			(width 0.08255)
			(type default)
		)
		(layer "In2.Cu")
	)
	(gr_line
		(start 33.443672 -281.147774)
		(end 33.47974 -281.141424)
		(stroke
			(width 0.08255)
			(type default)
		)
		(layer "In2.Cu")
	)
	(gr_line
		(start 33.470088 -431.944018)
		(end 34.119058 -431.489612)
		(stroke
			(width 0.08255)
			(type default)
		)
		(layer "In2.Cu")
	)
	(gr_line
		(start 33.491678 -128.178052)
		(end 33.512506 -128.207516)
		(stroke
			(width 0.08255)
			(type default)
		)
		(layer "In2.Cu")
	)
	(gr_line
		(start 33.512506 -128.207516)
		(end 33.518856 -128.243584)
		(stroke
			(width 0.08255)
			(type default)
		)
		(layer "In2.Cu")
	)
	(gr_line
		(start 33.624266 -25.84069)
		(end 33.761426 -26.618438)
		(stroke
			(width 0.08255)
			(type default)
		)
		(layer "In2.Cu")
	)
	(gr_line
		(start 33.684718 -431.12944)
		(end 33.94329 -431.17516)
		(stroke
			(width 0.08255)
			(type default)
		)
		(layer "In2.Cu")
	)
	(gr_line
		(start 33.73501 -426.444156)
		(end 33.78073 -426.185584)
		(stroke
			(width 0.08255)
			(type default)
		)
		(layer "In2.Cu")
	)
	(gr_line
		(start 33.7439 -203.659486)
		(end 33.959038 -203.509118)
		(stroke
			(width 0.08255)
			(type default)
		)
		(layer "In2.Cu")
	)
	(gr_line
		(start 33.761172 -160.94329)
		(end 33.773872 -160.925002)
		(stroke
			(width 0.08255)
			(type default)
		)
		(layer "In2.Cu")
	)
	(gr_line
		(start 33.773872 -160.925002)
		(end 33.79216 -160.912302)
		(stroke
			(width 0.08255)
			(type default)
		)
		(layer "In2.Cu")
	)
	(gr_line
		(start 33.78073 -426.185584)
		(end 34.186368 -425.901612)
		(stroke
			(width 0.08255)
			(type default)
		)
		(layer "In2.Cu")
	)
	(gr_line
		(start 33.843214 -22.912832)
		(end 33.938464 -23.451058)
		(stroke
			(width 0.08255)
			(type default)
		)
		(layer "In2.Cu")
	)
	(gr_line
		(start 33.843214 -22.912832)
		(end 34.012124 -22.672548)
		(stroke
			(width 0.08255)
			(type default)
		)
		(layer "In2.Cu")
	)
	(gr_line
		(start 33.861502 -27.186636)
		(end 33.998154 -27.96159)
		(stroke
			(width 0.08255)
			(type default)
		)
		(layer "In2.Cu")
	)
	(gr_line
		(start 33.938464 -23.451058)
		(end 34.179002 -23.618952)
		(stroke
			(width 0.08255)
			(type default)
		)
		(layer "In2.Cu")
	)
	(gr_line
		(start 33.951926 -130.741166)
		(end 33.955482 -130.720338)
		(stroke
			(width 0.08255)
			(type default)
		)
		(layer "In2.Cu")
	)
	(gr_line
		(start 33.951926 -130.740912)
		(end 33.951926 -130.741674)
		(stroke
			(width 0.08255)
			(type default)
		)
		(layer "In2.Cu")
	)
	(gr_line
		(start 33.951926 -130.699764)
		(end 33.955482 -130.720338)
		(stroke
			(width 0.08255)
			(type default)
		)
		(layer "In2.Cu")
	)
	(gr_line
		(start 33.972246 -426.715428)
		(end 34.618422 -426.263054)
		(stroke
			(width 0.08255)
			(type default)
		)
		(layer "In2.Cu")
	)
	(gr_line
		(start 34.066734 -383.594356)
		(end 34.087308 -383.5908)
		(stroke
			(width 0.08255)
			(type default)
		)
		(layer "In2.Cu")
	)
	(gr_line
		(start 34.087308 -383.5908)
		(end 34.107882 -383.594356)
		(stroke
			(width 0.08255)
			(type default)
		)
		(layer "In2.Cu")
	)
	(gr_line
		(start 34.10585 -24.40178)
		(end 34.2011 -24.940006)
		(stroke
			(width 0.08255)
			(type default)
		)
		(layer "In2.Cu")
	)
	(gr_line
		(start 34.10585 -24.40178)
		(end 34.27476 -24.161496)
		(stroke
			(width 0.08255)
			(type default)
		)
		(layer "In2.Cu")
	)
	(gr_line
		(start 34.155888 -145.71599)
		(end 34.177986 -145.684494)
		(stroke
			(width 0.08255)
			(type default)
		)
		(layer "In2.Cu")
	)
	(gr_line
		(start 34.156142 -248.748296)
		(end 34.177224 -248.71807)
		(stroke
			(width 0.08255)
			(type default)
		)
		(layer "In2.Cu")
	)
	(gr_line
		(start 34.156904 -30.910022)
		(end 34.157158 -30.908752)
		(stroke
			(width 0.08255)
			(type default)
		)
		(layer "In2.Cu")
	)
	(gr_line
		(start 34.157158 -30.908752)
		(end 34.15665 -30.909006)
		(stroke
			(width 0.08255)
			(type default)
		)
		(layer "In2.Cu")
	)
	(gr_line
		(start 34.172906 -124.610876)
		(end 34.193988 -124.641102)
		(stroke
			(width 0.08255)
			(type default)
		)
		(layer "In2.Cu")
	)
	(gr_line
		(start 34.172906 -57.429146)
		(end 34.203132 -57.408064)
		(stroke
			(width 0.08255)
			(type default)
		)
		(layer "In2.Cu")
	)
	(gr_line
		(start 34.175446 -21.624798)
		(end 34.196274 -21.654262)
		(stroke
			(width 0.08255)
			(type default)
		)
		(layer "In2.Cu")
	)
	(gr_line
		(start 34.177224 -248.71807)
		(end 34.183574 -248.682256)
		(stroke
			(width 0.08255)
			(type default)
		)
		(layer "In2.Cu")
	)
	(gr_line
		(start 34.177986 -145.684494)
		(end 34.184844 -145.64614)
		(stroke
			(width 0.08255)
			(type default)
		)
		(layer "In2.Cu")
	)
	(gr_line
		(start 34.186368 -425.901612)
		(end 34.444686 -425.947332)
		(stroke
			(width 0.08255)
			(type default)
		)
		(layer "In2.Cu")
	)
	(gr_line
		(start 34.193988 -124.641102)
		(end 34.200338 -124.67717)
		(stroke
			(width 0.08255)
			(type default)
		)
		(layer "In2.Cu")
	)
	(gr_line
		(start 34.196274 -21.654262)
		(end 34.202624 -21.69033)
		(stroke
			(width 0.08255)
			(type default)
		)
		(layer "In2.Cu")
	)
	(gr_line
		(start 34.2011 -24.940006)
		(end 34.441638 -25.1079)
		(stroke
			(width 0.08255)
			(type default)
		)
		(layer "In2.Cu")
	)
	(gr_line
		(start 34.203132 -57.408064)
		(end 34.2392 -57.401714)
		(stroke
			(width 0.08255)
			(type default)
		)
		(layer "In2.Cu")
	)
	(gr_line
		(start 34.262314 -239.111282)
		(end 34.268664 -239.075468)
		(stroke
			(width 0.08255)
			(type default)
		)
		(layer "In2.Cu")
	)
	(gr_line
		(start 34.268664 -239.075468)
		(end 34.289746 -239.045242)
		(stroke
			(width 0.08255)
			(type default)
		)
		(layer "In2.Cu")
	)
	(gr_line
		(start 34.352738 -430.888394)
		(end 34.398458 -430.629822)
		(stroke
			(width 0.08255)
			(type default)
		)
		(layer "In2.Cu")
	)
	(gr_line
		(start 34.371788 -22.648418)
		(end 34.525458 -23.520908)
		(stroke
			(width 0.08255)
			(type default)
		)
		(layer "In2.Cu")
	)
	(gr_line
		(start 34.398458 -430.629822)
		(end 34.804096 -430.34585)
		(stroke
			(width 0.08255)
			(type default)
		)
		(layer "In2.Cu")
	)
	(gr_line
		(start 34.451544 -203.595986)
		(end 34.602166 -203.81087)
		(stroke
			(width 0.08255)
			(type default)
		)
		(layer "In2.Cu")
	)
	(gr_line
		(start 34.503868 -30.830266)
		(end 34.509964 -30.865318)
		(stroke
			(width 0.08255)
			(type default)
		)
		(layer "In2.Cu")
	)
	(gr_line
		(start 34.503868 -30.830266)
		(end 34.509964 -30.864048)
		(stroke
			(width 0.08255)
			(type default)
		)
		(layer "In2.Cu")
	)
	(gr_line
		(start 34.504122 -30.830774)
		(end 34.509964 -30.86354)
		(stroke
			(width 0.08255)
			(type default)
		)
		(layer "In2.Cu")
	)
	(gr_line
		(start 34.51479 -30.929326)
		(end 34.518092 -30.910276)
		(stroke
			(width 0.08255)
			(type default)
		)
		(layer "In2.Cu")
	)
	(gr_line
		(start 34.515044 -30.892496)
		(end 34.518092 -30.910276)
		(stroke
			(width 0.08255)
			(type default)
		)
		(layer "In2.Cu")
	)
	(gr_line
		(start 34.55162 -203.250038)
		(end 35.326574 -203.38669)
		(stroke
			(width 0.08255)
			(type default)
		)
		(layer "In2.Cu")
	)
	(gr_line
		(start 34.585656 -160.35655)
		(end 34.615882 -160.335468)
		(stroke
			(width 0.08255)
			(type default)
		)
		(layer "In2.Cu")
	)
	(gr_line
		(start 34.589974 -431.159666)
		(end 35.237674 -430.706276)
		(stroke
			(width 0.08255)
			(type default)
		)
		(layer "In2.Cu")
	)
	(gr_line
		(start 34.602166 -203.81087)
		(end 35.089846 -203.896976)
		(stroke
			(width 0.08255)
			(type default)
		)
		(layer "In2.Cu")
	)
	(gr_line
		(start 34.615882 -160.335468)
		(end 34.651696 -160.329118)
		(stroke
			(width 0.08255)
			(type default)
		)
		(layer "In2.Cu")
	)
	(gr_line
		(start 34.63417 -24.136604)
		(end 34.788094 -25.009602)
		(stroke
			(width 0.08255)
			(type default)
		)
		(layer "In2.Cu")
	)
	(gr_line
		(start 34.728912 -225.09353)
		(end 34.7472 -225.08083)
		(stroke
			(width 0.08255)
			(type default)
		)
		(layer "In2.Cu")
	)
	(gr_line
		(start 34.7472 -225.08083)
		(end 34.7599 -225.062542)
		(stroke
			(width 0.08255)
			(type default)
		)
		(layer "In2.Cu")
	)
	(gr_line
		(start 34.804096 -430.34585)
		(end 35.062668 -430.391316)
		(stroke
			(width 0.08255)
			(type default)
		)
		(layer "In2.Cu")
	)
	(gr_line
		(start 34.854388 -425.660312)
		(end 34.900108 -425.40174)
		(stroke
			(width 0.08255)
			(type default)
		)
		(layer "In2.Cu")
	)
	(gr_line
		(start 34.900108 -425.40174)
		(end 35.305746 -425.117768)
		(stroke
			(width 0.08255)
			(type default)
		)
		(layer "In2.Cu")
	)
	(gr_line
		(start 34.965386 -422.018714)
		(end 35.099244 -421.809672)
		(stroke
			(width 0.08255)
			(type default)
		)
		(layer "In2.Cu")
	)
	(gr_line
		(start 34.988246 -223.788478)
		(end 35.033712 -224.047304)
		(stroke
			(width 0.08255)
			(type default)
		)
		(layer "In2.Cu")
	)
	(gr_line
		(start 34.988246 -223.788478)
		(end 35.272218 -223.38284)
		(stroke
			(width 0.08255)
			(type default)
		)
		(layer "In2.Cu")
	)
	(gr_line
		(start 35.014154 -249.174254)
		(end 35.035236 -249.144028)
		(stroke
			(width 0.08255)
			(type default)
		)
		(layer "In2.Cu")
	)
	(gr_line
		(start 35.035236 -249.144028)
		(end 35.041586 -249.108214)
		(stroke
			(width 0.08255)
			(type default)
		)
		(layer "In2.Cu")
	)
	(gr_line
		(start 35.041332 -146.13509)
		(end 35.063176 -146.104102)
		(stroke
			(width 0.08255)
			(type default)
		)
		(layer "In2.Cu")
	)
	(gr_line
		(start 35.063176 -146.104102)
		(end 35.070034 -146.065748)
		(stroke
			(width 0.08255)
			(type default)
		)
		(layer "In2.Cu")
	)
	(gr_line
		(start 35.078924 -422.360344)
		(end 35.832288 -422.195244)
		(stroke
			(width 0.08255)
			(type default)
		)
		(layer "In2.Cu")
	)
	(gr_line
		(start 35.089846 -203.896976)
		(end 35.304476 -203.746354)
		(stroke
			(width 0.08255)
			(type default)
		)
		(layer "In2.Cu")
	)
	(gr_line
		(start 35.090354 -425.9326)
		(end 35.738562 -425.478702)
		(stroke
			(width 0.08255)
			(type default)
		)
		(layer "In2.Cu")
	)
	(gr_line
		(start 35.099244 -421.809672)
		(end 35.583114 -421.7035)
		(stroke
			(width 0.08255)
			(type default)
		)
		(layer "In2.Cu")
	)
	(gr_line
		(start 35.099498 -129.817114)
		(end 35.103054 -129.796286)
		(stroke
			(width 0.08255)
			(type default)
		)
		(layer "In2.Cu")
	)
	(gr_line
		(start 35.099498 -129.81686)
		(end 35.099498 -129.817622)
		(stroke
			(width 0.08255)
			(type default)
		)
		(layer "In2.Cu")
	)
	(gr_line
		(start 35.099498 -129.775712)
		(end 35.103054 -129.796286)
		(stroke
			(width 0.08255)
			(type default)
		)
		(layer "In2.Cu")
	)
	(gr_line
		(start 35.272218 -223.38284)
		(end 35.53079 -223.33712)
		(stroke
			(width 0.08255)
			(type default)
		)
		(layer "In2.Cu")
	)
	(gr_line
		(start 35.305746 -425.117768)
		(end 35.564064 -425.163488)
		(stroke
			(width 0.08255)
			(type default)
		)
		(layer "In2.Cu")
	)
	(gr_line
		(start 35.348164 -224.222818)
		(end 35.803332 -223.572832)
		(stroke
			(width 0.08255)
			(type default)
		)
		(layer "In2.Cu")
	)
	(gr_line
		(start 35.438842 -239.518444)
		(end 35.445192 -239.48263)
		(stroke
			(width 0.08255)
			(type default)
		)
		(layer "In2.Cu")
	)
	(gr_line
		(start 35.445192 -239.48263)
		(end 35.466274 -239.452404)
		(stroke
			(width 0.08255)
			(type default)
		)
		(layer "In2.Cu")
	)
	(gr_line
		(start 35.472116 -430.10455)
		(end 35.517836 -429.845978)
		(stroke
			(width 0.08255)
			(type default)
		)
		(layer "In2.Cu")
	)
	(gr_line
		(start 35.517836 -429.845978)
		(end 35.923474 -429.562006)
		(stroke
			(width 0.08255)
			(type default)
		)
		(layer "In2.Cu")
	)
	(gr_line
		(start 35.583114 -421.7035)
		(end 35.792156 -421.837612)
		(stroke
			(width 0.08255)
			(type default)
		)
		(layer "In2.Cu")
	)
	(gr_line
		(start 35.681158 -30.118304)
		(end 35.684968 -30.09646)
		(stroke
			(width 0.08255)
			(type default)
		)
		(layer "In2.Cu")
	)
	(gr_line
		(start 35.681412 -30.075886)
		(end 35.684968 -30.09646)
		(stroke
			(width 0.08255)
			(type default)
		)
		(layer "In2.Cu")
	)
	(gr_line
		(start 35.709352 -430.375822)
		(end 36.356798 -429.922432)
		(stroke
			(width 0.08255)
			(type default)
		)
		(layer "In2.Cu")
	)
	(gr_line
		(start 35.77209 -222.6691)
		(end 35.817556 -222.927926)
		(stroke
			(width 0.08255)
			(type default)
		)
		(layer "In2.Cu")
	)
	(gr_line
		(start 35.77209 -222.6691)
		(end 36.056062 -222.263462)
		(stroke
			(width 0.08255)
			(type default)
		)
		(layer "In2.Cu")
	)
	(gr_line
		(start 35.797236 -203.833222)
		(end 35.947858 -204.048106)
		(stroke
			(width 0.08255)
			(type default)
		)
		(layer "In2.Cu")
	)
	(gr_line
		(start 35.898074 -146.59864)
		(end 35.919156 -146.568414)
		(stroke
			(width 0.08255)
			(type default)
		)
		(layer "In2.Cu")
	)
	(gr_line
		(start 35.898836 -203.487528)
		(end 36.674552 -203.62418)
		(stroke
			(width 0.08255)
			(type default)
		)
		(layer "In2.Cu")
	)
	(gr_line
		(start 35.906202 -249.588274)
		(end 35.927792 -249.55754)
		(stroke
			(width 0.08255)
			(type default)
		)
		(layer "In2.Cu")
	)
	(gr_line
		(start 35.919156 -146.568414)
		(end 35.925252 -146.533108)
		(stroke
			(width 0.08255)
			(type default)
		)
		(layer "In2.Cu")
	)
	(gr_line
		(start 35.923474 -429.562006)
		(end 36.1823 -429.607472)
		(stroke
			(width 0.08255)
			(type default)
		)
		(layer "In2.Cu")
	)
	(gr_line
		(start 35.927792 -249.55754)
		(end 35.934396 -249.52071)
		(stroke
			(width 0.08255)
			(type default)
		)
		(layer "In2.Cu")
	)
	(gr_line
		(start 35.947858 -204.048106)
		(end 36.435538 -204.134212)
		(stroke
			(width 0.08255)
			(type default)
		)
		(layer "In2.Cu")
	)
	(gr_line
		(start 36.056062 -222.263462)
		(end 36.314634 -222.217742)
		(stroke
			(width 0.08255)
			(type default)
		)
		(layer "In2.Cu")
	)
	(gr_line
		(start 36.132262 -223.102932)
		(end 36.586668 -222.453962)
		(stroke
			(width 0.08255)
			(type default)
		)
		(layer "In2.Cu")
	)
	(gr_line
		(start 36.220654 -219.274898)
		(end 36.266374 -219.016072)
		(stroke
			(width 0.08255)
			(type default)
		)
		(layer "In2.Cu")
	)
	(gr_line
		(start 36.266374 -219.016072)
		(end 36.672012 -218.7321)
		(stroke
			(width 0.08255)
			(type default)
		)
		(layer "In2.Cu")
	)
	(gr_line
		(start 36.280344 -421.730424)
		(end 36.414202 -421.521636)
		(stroke
			(width 0.08255)
			(type default)
		)
		(layer "In2.Cu")
	)
	(gr_line
		(start 36.300918 -239.920018)
		(end 36.307268 -239.884204)
		(stroke
			(width 0.08255)
			(type default)
		)
		(layer "In2.Cu")
	)
	(gr_line
		(start 36.307268 -239.884204)
		(end 36.32835 -239.853978)
		(stroke
			(width 0.08255)
			(type default)
		)
		(layer "In2.Cu")
	)
	(gr_line
		(start 36.394898 -422.072054)
		(end 37.145722 -421.907462)
		(stroke
			(width 0.08255)
			(type default)
		)
		(layer "In2.Cu")
	)
	(gr_line
		(start 36.414202 -421.521636)
		(end 36.898072 -421.415464)
		(stroke
			(width 0.08255)
			(type default)
		)
		(layer "In2.Cu")
	)
	(gr_line
		(start 36.421568 -492.043466)
		(end 36.72713 -492.349028)
		(stroke
			(width 0.08255)
			(type default)
		)
		(layer "In2.Cu")
	)
	(gr_line
		(start 36.421568 -491.53699)
		(end 36.72713 -491.231428)
		(stroke
			(width 0.08255)
			(type default)
		)
		(layer "In2.Cu")
	)
	(gr_line
		(start 36.421568 -487.243374)
		(end 36.72713 -487.548936)
		(stroke
			(width 0.08255)
			(type default)
		)
		(layer "In2.Cu")
	)
	(gr_line
		(start 36.421568 -486.736898)
		(end 36.72713 -486.431336)
		(stroke
			(width 0.08255)
			(type default)
		)
		(layer "In2.Cu")
	)
	(gr_line
		(start 36.421568 -482.443282)
		(end 36.72713 -482.748844)
		(stroke
			(width 0.08255)
			(type default)
		)
		(layer "In2.Cu")
	)
	(gr_line
		(start 36.421568 -481.936806)
		(end 36.72713 -481.631244)
		(stroke
			(width 0.08255)
			(type default)
		)
		(layer "In2.Cu")
	)
	(gr_line
		(start 36.421568 -469.64346)
		(end 36.72713 -469.949022)
		(stroke
			(width 0.08255)
			(type default)
		)
		(layer "In2.Cu")
	)
	(gr_line
		(start 36.421568 -469.136984)
		(end 36.72713 -468.831422)
		(stroke
			(width 0.08255)
			(type default)
		)
		(layer "In2.Cu")
	)
	(gr_line
		(start 36.421568 -389.043418)
		(end 36.72713 -389.34898)
		(stroke
			(width 0.08255)
			(type default)
		)
		(layer "In2.Cu")
	)
	(gr_line
		(start 36.421568 -388.536942)
		(end 36.72713 -388.23138)
		(stroke
			(width 0.08255)
			(type default)
		)
		(layer "In2.Cu")
	)
	(gr_line
		(start 36.421568 -384.243326)
		(end 36.72713 -384.548888)
		(stroke
			(width 0.08255)
			(type default)
		)
		(layer "In2.Cu")
	)
	(gr_line
		(start 36.421568 -383.73685)
		(end 36.72713 -383.431288)
		(stroke
			(width 0.08255)
			(type default)
		)
		(layer "In2.Cu")
	)
	(gr_line
		(start 36.421568 -379.443234)
		(end 36.72713 -379.748796)
		(stroke
			(width 0.08255)
			(type default)
		)
		(layer "In2.Cu")
	)
	(gr_line
		(start 36.421568 -378.936758)
		(end 36.72713 -378.631196)
		(stroke
			(width 0.08255)
			(type default)
		)
		(layer "In2.Cu")
	)
	(gr_line
		(start 36.421568 -366.643412)
		(end 36.72713 -366.948974)
		(stroke
			(width 0.08255)
			(type default)
		)
		(layer "In2.Cu")
	)
	(gr_line
		(start 36.421568 -366.136936)
		(end 36.72713 -365.831374)
		(stroke
			(width 0.08255)
			(type default)
		)
		(layer "In2.Cu")
	)
	(gr_line
		(start 36.421568 -286.04337)
		(end 36.72713 -286.348932)
		(stroke
			(width 0.08255)
			(type default)
		)
		(layer "In2.Cu")
	)
	(gr_line
		(start 36.421568 -285.536894)
		(end 36.72713 -285.231332)
		(stroke
			(width 0.08255)
			(type default)
		)
		(layer "In2.Cu")
	)
	(gr_line
		(start 36.421568 -281.243278)
		(end 36.72713 -281.54884)
		(stroke
			(width 0.08255)
			(type default)
		)
		(layer "In2.Cu")
	)
	(gr_line
		(start 36.421568 -280.736802)
		(end 36.72713 -280.43124)
		(stroke
			(width 0.08255)
			(type default)
		)
		(layer "In2.Cu")
	)
	(gr_line
		(start 36.421568 -276.443186)
		(end 36.72713 -276.748748)
		(stroke
			(width 0.08255)
			(type default)
		)
		(layer "In2.Cu")
	)
	(gr_line
		(start 36.421568 -275.93671)
		(end 36.72713 -275.631148)
		(stroke
			(width 0.08255)
			(type default)
		)
		(layer "In2.Cu")
	)
	(gr_line
		(start 36.421568 -263.643364)
		(end 36.72713 -263.948926)
		(stroke
			(width 0.08255)
			(type default)
		)
		(layer "In2.Cu")
	)
	(gr_line
		(start 36.421568 -263.136888)
		(end 36.72713 -262.831326)
		(stroke
			(width 0.08255)
			(type default)
		)
		(layer "In2.Cu")
	)
	(gr_line
		(start 36.421568 -183.043322)
		(end 36.72713 -183.348884)
		(stroke
			(width 0.08255)
			(type default)
		)
		(layer "In2.Cu")
	)
	(gr_line
		(start 36.421568 -182.536846)
		(end 36.72713 -182.231284)
		(stroke
			(width 0.08255)
			(type default)
		)
		(layer "In2.Cu")
	)
	(gr_line
		(start 36.421568 -178.24323)
		(end 36.72713 -178.548792)
		(stroke
			(width 0.08255)
			(type default)
		)
		(layer "In2.Cu")
	)
	(gr_line
		(start 36.421568 -177.736754)
		(end 36.72713 -177.431192)
		(stroke
			(width 0.08255)
			(type default)
		)
		(layer "In2.Cu")
	)
	(gr_line
		(start 36.421568 -173.443138)
		(end 36.72713 -173.7487)
		(stroke
			(width 0.08255)
			(type default)
		)
		(layer "In2.Cu")
	)
	(gr_line
		(start 36.421568 -172.936662)
		(end 36.72713 -172.6311)
		(stroke
			(width 0.08255)
			(type default)
		)
		(layer "In2.Cu")
	)
	(gr_line
		(start 36.421568 -160.643316)
		(end 36.72713 -160.948878)
		(stroke
			(width 0.08255)
			(type default)
		)
		(layer "In2.Cu")
	)
	(gr_line
		(start 36.421568 -160.13684)
		(end 36.72713 -159.831278)
		(stroke
			(width 0.08255)
			(type default)
		)
		(layer "In2.Cu")
	)
	(gr_line
		(start 36.421568 -80.043274)
		(end 36.72713 -80.348836)
		(stroke
			(width 0.08255)
			(type default)
		)
		(layer "In2.Cu")
	)
	(gr_line
		(start 36.421568 -79.536798)
		(end 36.72713 -79.231236)
		(stroke
			(width 0.08255)
			(type default)
		)
		(layer "In2.Cu")
	)
	(gr_line
		(start 36.421568 -75.243182)
		(end 36.72713 -75.548744)
		(stroke
			(width 0.08255)
			(type default)
		)
		(layer "In2.Cu")
	)
	(gr_line
		(start 36.421568 -74.736706)
		(end 36.72713 -74.431144)
		(stroke
			(width 0.08255)
			(type default)
		)
		(layer "In2.Cu")
	)
	(gr_line
		(start 36.421568 -70.44309)
		(end 36.72713 -70.748652)
		(stroke
			(width 0.08255)
			(type default)
		)
		(layer "In2.Cu")
	)
	(gr_line
		(start 36.421568 -69.936614)
		(end 36.72713 -69.631052)
		(stroke
			(width 0.08255)
			(type default)
		)
		(layer "In2.Cu")
	)
	(gr_line
		(start 36.421568 -57.643268)
		(end 36.72713 -57.94883)
		(stroke
			(width 0.08255)
			(type default)
		)
		(layer "In2.Cu")
	)
	(gr_line
		(start 36.421568 -57.136792)
		(end 36.72713 -56.83123)
		(stroke
			(width 0.08255)
			(type default)
		)
		(layer "In2.Cu")
	)
	(gr_line
		(start 36.435538 -204.134212)
		(end 36.650422 -203.983844)
		(stroke
			(width 0.08255)
			(type default)
		)
		(layer "In2.Cu")
	)
	(gr_line
		(start 36.45662 -219.546932)
		(end 37.104828 -219.093034)
		(stroke
			(width 0.08255)
			(type default)
		)
		(layer "In2.Cu")
	)
	(gr_line
		(start 36.555934 -221.549722)
		(end 36.6014 -221.808548)
		(stroke
			(width 0.08255)
			(type default)
		)
		(layer "In2.Cu")
	)
	(gr_line
		(start 36.555934 -221.549722)
		(end 36.839906 -221.144084)
		(stroke
			(width 0.08255)
			(type default)
		)
		(layer "In2.Cu")
	)
	(gr_line
		(start 36.672012 -218.7321)
		(end 36.930584 -218.77782)
		(stroke
			(width 0.08255)
			(type default)
		)
		(layer "In2.Cu")
	)
	(gr_line
		(start 36.8173 -249.920252)
		(end 36.838382 -249.890026)
		(stroke
			(width 0.08255)
			(type default)
		)
		(layer "In2.Cu")
	)
	(gr_line
		(start 36.838382 -249.890026)
		(end 36.844732 -249.854212)
		(stroke
			(width 0.08255)
			(type default)
		)
		(layer "In2.Cu")
	)
	(gr_line
		(start 36.839906 -221.144084)
		(end 37.098478 -221.098364)
		(stroke
			(width 0.08255)
			(type default)
		)
		(layer "In2.Cu")
	)
	(gr_line
		(start 36.862512 -146.854926)
		(end 36.883594 -146.8247)
		(stroke
			(width 0.08255)
			(type default)
		)
		(layer "In2.Cu")
	)
	(gr_line
		(start 36.883594 -146.8247)
		(end 36.889944 -146.788886)
		(stroke
			(width 0.08255)
			(type default)
		)
		(layer "In2.Cu")
	)
	(gr_line
		(start 36.89096 -428.594266)
		(end 36.93668 -428.852838)
		(stroke
			(width 0.08255)
			(type default)
		)
		(layer "In2.Cu")
	)
	(gr_line
		(start 36.89096 -428.594266)
		(end 37.175186 -428.188374)
		(stroke
			(width 0.08255)
			(type default)
		)
		(layer "In2.Cu")
	)
	(gr_line
		(start 36.898072 -421.415464)
		(end 37.107114 -421.549322)
		(stroke
			(width 0.08255)
			(type default)
		)
		(layer "In2.Cu")
	)
	(gr_line
		(start 36.916106 -221.983554)
		(end 37.370512 -221.334584)
		(stroke
			(width 0.08255)
			(type default)
		)
		(layer "In2.Cu")
	)
	(gr_line
		(start 37.175186 -428.188374)
		(end 37.433504 -428.142908)
		(stroke
			(width 0.08255)
			(type default)
		)
		(layer "In2.Cu")
	)
	(gr_line
		(start 37.212778 -240.21415)
		(end 37.219128 -240.178082)
		(stroke
			(width 0.08255)
			(type default)
		)
		(layer "In2.Cu")
	)
	(gr_line
		(start 37.219128 -240.178082)
		(end 37.24021 -240.147856)
		(stroke
			(width 0.08255)
			(type default)
		)
		(layer "In2.Cu")
	)
	(gr_line
		(start 37.251894 -429.027082)
		(end 37.705284 -428.379636)
		(stroke
			(width 0.08255)
			(type default)
		)
		(layer "In2.Cu")
	)
	(gr_line
		(start 37.595302 -421.442388)
		(end 37.72916 -421.2336)
		(stroke
			(width 0.08255)
			(type default)
		)
		(layer "In2.Cu")
	)
	(gr_line
		(start 37.70884 -421.784272)
		(end 38.461188 -421.619426)
		(stroke
			(width 0.08255)
			(type default)
		)
		(layer "In2.Cu")
	)
	(gr_line
		(start 37.72916 -421.2336)
		(end 38.21303 -421.127428)
		(stroke
			(width 0.08255)
			(type default)
		)
		(layer "In2.Cu")
	)
	(gr_line
		(start 37.884608 -241.912902)
		(end 37.890958 -241.877088)
		(stroke
			(width 0.08255)
			(type default)
		)
		(layer "In2.Cu")
	)
	(gr_line
		(start 37.890958 -241.877088)
		(end 37.91204 -241.846862)
		(stroke
			(width 0.08255)
			(type default)
		)
		(layer "In2.Cu")
	)
	(gr_line
		(start 37.939726 -423.500042)
		(end 37.985446 -423.24147)
		(stroke
			(width 0.08255)
			(type default)
		)
		(layer "In2.Cu")
	)
	(gr_line
		(start 37.985446 -423.24147)
		(end 38.391084 -422.957498)
		(stroke
			(width 0.08255)
			(type default)
		)
		(layer "In2.Cu")
	)
	(gr_line
		(start 38.001702 -203.858368)
		(end 38.03777 -203.864718)
		(stroke
			(width 0.08255)
			(type default)
		)
		(layer "In2.Cu")
	)
	(gr_line
		(start 38.03777 -203.864718)
		(end 38.067996 -203.8858)
		(stroke
			(width 0.08255)
			(type default)
		)
		(layer "In2.Cu")
	)
	(gr_line
		(start 38.177724 -423.770552)
		(end 38.823138 -423.318432)
		(stroke
			(width 0.08255)
			(type default)
		)
		(layer "In2.Cu")
	)
	(gr_line
		(start 38.21303 -421.127428)
		(end 38.421818 -421.261286)
		(stroke
			(width 0.08255)
			(type default)
		)
		(layer "In2.Cu")
	)
	(gr_line
		(start 38.391084 -422.957498)
		(end 38.649656 -423.002964)
		(stroke
			(width 0.08255)
			(type default)
		)
		(layer "In2.Cu")
	)
	(gr_line
		(start 38.394894 -218.189556)
		(end 38.413182 -218.176856)
		(stroke
			(width 0.08255)
			(type default)
		)
		(layer "In2.Cu")
	)
	(gr_line
		(start 38.413182 -218.176856)
		(end 38.425882 -218.158568)
		(stroke
			(width 0.08255)
			(type default)
		)
		(layer "In2.Cu")
	)
	(gr_line
		(start 38.569138 -203.023724)
		(end 38.605206 -203.030074)
		(stroke
			(width 0.08255)
			(type default)
		)
		(layer "In2.Cu")
	)
	(gr_line
		(start 38.605206 -203.030074)
		(end 38.635432 -203.051156)
		(stroke
			(width 0.08255)
			(type default)
		)
		(layer "In2.Cu")
	)
	(gr_line
		(start 38.694614 -214.562944)
		(end 38.730682 -214.556594)
		(stroke
			(width 0.08255)
			(type default)
		)
		(layer "In2.Cu")
	)
	(gr_line
		(start 38.730682 -214.556594)
		(end 38.760908 -214.535512)
		(stroke
			(width 0.08255)
			(type default)
		)
		(layer "In2.Cu")
	)
	(gr_line
		(start 38.84422 -307.118766)
		(end 38.864794 -307.122322)
		(stroke
			(width 0.08255)
			(type default)
		)
		(layer "In2.Cu")
	)
	(gr_line
		(start 38.864794 -307.122322)
		(end 38.885368 -307.118766)
		(stroke
			(width 0.08255)
			(type default)
		)
		(layer "In2.Cu")
	)
	(gr_line
		(start 39.014146 -306.157376)
		(end 39.03472 -306.160932)
		(stroke
			(width 0.08255)
			(type default)
		)
		(layer "In2.Cu")
	)
	(gr_line
		(start 39.03472 -306.160932)
		(end 39.055294 -306.157376)
		(stroke
			(width 0.08255)
			(type default)
		)
		(layer "In2.Cu")
	)
	(gr_line
		(start 39.03599 -304.290984)
		(end 39.056564 -304.29454)
		(stroke
			(width 0.08255)
			(type default)
		)
		(layer "In2.Cu")
	)
	(gr_line
		(start 39.041324 -202.122278)
		(end 39.077138 -202.128628)
		(stroke
			(width 0.08255)
			(type default)
		)
		(layer "In2.Cu")
	)
	(gr_line
		(start 39.05631 -305.228752)
		(end 39.076884 -305.232308)
		(stroke
			(width 0.08255)
			(type default)
		)
		(layer "In2.Cu")
	)
	(gr_line
		(start 39.056564 -304.29454)
		(end 39.077138 -304.290984)
		(stroke
			(width 0.08255)
			(type default)
		)
		(layer "In2.Cu")
	)
	(gr_line
		(start 39.059104 -422.716198)
		(end 39.104824 -422.457626)
		(stroke
			(width 0.08255)
			(type default)
		)
		(layer "In2.Cu")
	)
	(gr_line
		(start 39.076884 -305.232308)
		(end 39.097458 -305.228752)
		(stroke
			(width 0.08255)
			(type default)
		)
		(layer "In2.Cu")
	)
	(gr_line
		(start 39.077138 -202.128628)
		(end 39.107364 -202.14971)
		(stroke
			(width 0.08255)
			(type default)
		)
		(layer "In2.Cu")
	)
	(gr_line
		(start 39.104824 -422.457626)
		(end 39.510462 -422.173654)
		(stroke
			(width 0.08255)
			(type default)
		)
		(layer "In2.Cu")
	)
	(gr_line
		(start 39.239698 -114.929666)
		(end 39.246048 -114.893598)
		(stroke
			(width 0.08255)
			(type default)
		)
		(layer "In2.Cu")
	)
	(gr_line
		(start 39.246048 -114.893598)
		(end 39.26713 -114.863372)
		(stroke
			(width 0.08255)
			(type default)
		)
		(layer "In2.Cu")
	)
	(gr_line
		(start 39.296594 -422.986962)
		(end 39.940738 -422.535858)
		(stroke
			(width 0.08255)
			(type default)
		)
		(layer "In2.Cu")
	)
	(gr_line
		(start 39.450264 -441.369704)
		(end 39.481252 -441.348114)
		(stroke
			(width 0.08255)
			(type default)
		)
		(layer "In2.Cu")
	)
	(gr_line
		(start 39.476934 -201.271632)
		(end 39.513002 -201.277982)
		(stroke
			(width 0.08255)
			(type default)
		)
		(layer "In2.Cu")
	)
	(gr_line
		(start 39.481252 -441.348114)
		(end 39.51859 -441.34151)
		(stroke
			(width 0.08255)
			(type default)
		)
		(layer "In2.Cu")
	)
	(gr_line
		(start 39.510462 -422.173654)
		(end 39.76878 -422.219374)
		(stroke
			(width 0.08255)
			(type default)
		)
		(layer "In2.Cu")
	)
	(gr_line
		(start 39.513002 -201.277982)
		(end 39.543228 -201.299064)
		(stroke
			(width 0.08255)
			(type default)
		)
		(layer "In2.Cu")
	)
	(gr_line
		(start 39.563294 -101.611938)
		(end 39.599362 -101.618288)
		(stroke
			(width 0.08255)
			(type default)
		)
		(layer "In2.Cu")
	)
	(gr_line
		(start 39.599362 -101.618288)
		(end 39.629588 -101.63937)
		(stroke
			(width 0.08255)
			(type default)
		)
		(layer "In2.Cu")
	)
	(gr_line
		(start 39.617142 -442.434472)
		(end 39.647368 -442.41339)
		(stroke
			(width 0.08255)
			(type default)
		)
		(layer "In2.Cu")
	)
	(gr_line
		(start 39.647368 -442.41339)
		(end 39.683182 -442.40704)
		(stroke
			(width 0.08255)
			(type default)
		)
		(layer "In2.Cu")
	)
	(gr_line
		(start 39.855394 -100.711254)
		(end 39.891208 -100.717604)
		(stroke
			(width 0.08255)
			(type default)
		)
		(layer "In2.Cu")
	)
	(gr_line
		(start 39.891208 -100.717604)
		(end 39.921434 -100.738686)
		(stroke
			(width 0.08255)
			(type default)
		)
		(layer "In2.Cu")
	)
	(gr_line
		(start 40.030654 -443.361318)
		(end 40.061642 -443.339728)
		(stroke
			(width 0.08255)
			(type default)
		)
		(layer "In2.Cu")
	)
	(gr_line
		(start 40.061642 -443.339728)
		(end 40.09898 -443.333124)
		(stroke
			(width 0.08255)
			(type default)
		)
		(layer "In2.Cu")
	)
	(gr_line
		(start 40.129714 -115.327684)
		(end 40.136064 -115.291616)
		(stroke
			(width 0.08255)
			(type default)
		)
		(layer "In2.Cu")
	)
	(gr_line
		(start 40.136064 -115.291616)
		(end 40.157146 -115.26139)
		(stroke
			(width 0.08255)
			(type default)
		)
		(layer "In2.Cu")
	)
	(gr_line
		(start 40.258238 -99.786948)
		(end 40.294306 -99.793298)
		(stroke
			(width 0.08255)
			(type default)
		)
		(layer "In2.Cu")
	)
	(gr_line
		(start 40.294306 -99.793298)
		(end 40.324532 -99.81438)
		(stroke
			(width 0.08255)
			(type default)
		)
		(layer "In2.Cu")
	)
	(gr_line
		(start 40.320214 -444.298832)
		(end 40.35044 -444.27775)
		(stroke
			(width 0.08255)
			(type default)
		)
		(layer "In2.Cu")
	)
	(gr_line
		(start 40.35044 -444.27775)
		(end 40.350948 -444.277496)
		(stroke
			(width 0.08255)
			(type default)
		)
		(layer "In2.Cu")
	)
	(gr_line
		(start 40.350948 -444.277496)
		(end 40.388032 -444.270892)
		(stroke
			(width 0.08255)
			(type default)
		)
		(layer "In2.Cu")
	)
	(gr_line
		(start 40.57396 -98.813874)
		(end 40.609774 -98.820224)
		(stroke
			(width 0.08255)
			(type default)
		)
		(layer "In2.Cu")
	)
	(gr_line
		(start 40.609774 -98.820224)
		(end 40.64 -98.841306)
		(stroke
			(width 0.08255)
			(type default)
		)
		(layer "In2.Cu")
	)
	(gr_line
		(start 40.766492 -213.131654)
		(end 40.78478 -213.118954)
		(stroke
			(width 0.08255)
			(type default)
		)
		(layer "In2.Cu")
	)
	(gr_line
		(start 40.78478 -213.118954)
		(end 40.79748 -213.100666)
		(stroke
			(width 0.08255)
			(type default)
		)
		(layer "In2.Cu")
	)
	(gr_line
		(start 40.877236 -205.852776)
		(end 40.895524 -205.865476)
		(stroke
			(width 0.08255)
			(type default)
		)
		(layer "In2.Cu")
	)
	(gr_line
		(start 40.895524 -205.865476)
		(end 40.908224 -205.883764)
		(stroke
			(width 0.08255)
			(type default)
		)
		(layer "In2.Cu")
	)
	(gr_line
		(start 41.053512 -115.586002)
		(end 41.059608 -115.550696)
		(stroke
			(width 0.08255)
			(type default)
		)
		(layer "In2.Cu")
	)
	(gr_line
		(start 41.059608 -115.550696)
		(end 41.08069 -115.52047)
		(stroke
			(width 0.08255)
			(type default)
		)
		(layer "In2.Cu")
	)
	(gr_line
		(start 41.09212 -417.879276)
		(end 41.177972 -417.391342)
		(stroke
			(width 0.08255)
			(type default)
		)
		(layer "In2.Cu")
	)
	(gr_line
		(start 41.09212 -417.879276)
		(end 41.23436 -418.08273)
		(stroke
			(width 0.08255)
			(type default)
		)
		(layer "In2.Cu")
	)
	(gr_line
		(start 41.177972 -417.391342)
		(end 41.381426 -417.249102)
		(stroke
			(width 0.08255)
			(type default)
		)
		(layer "In2.Cu")
	)
	(gr_line
		(start 41.3258 -416.553396)
		(end 41.411906 -416.065716)
		(stroke
			(width 0.08255)
			(type default)
		)
		(layer "In2.Cu")
	)
	(gr_line
		(start 41.3258 -416.553396)
		(end 41.468294 -416.75685)
		(stroke
			(width 0.08255)
			(type default)
		)
		(layer "In2.Cu")
	)
	(gr_line
		(start 41.411906 -416.065716)
		(end 41.615106 -415.923222)
		(stroke
			(width 0.08255)
			(type default)
		)
		(layer "In2.Cu")
	)
	(gr_line
		(start 41.576752 -205.110588)
		(end 41.59504 -205.123288)
		(stroke
			(width 0.08255)
			(type default)
		)
		(layer "In2.Cu")
	)
	(gr_line
		(start 41.593516 -418.109146)
		(end 41.727882 -417.3474)
		(stroke
			(width 0.08255)
			(type default)
		)
		(layer "In2.Cu")
	)
	(gr_line
		(start 41.59504 -205.123288)
		(end 41.60774 -205.141576)
		(stroke
			(width 0.08255)
			(type default)
		)
		(layer "In2.Cu")
	)
	(gr_line
		(start 41.663874 -440.96305)
		(end 41.684448 -440.959494)
		(stroke
			(width 0.08255)
			(type default)
		)
		(layer "In2.Cu")
	)
	(gr_line
		(start 41.684448 -440.959494)
		(end 41.705022 -440.96305)
		(stroke
			(width 0.08255)
			(type default)
		)
		(layer "In2.Cu")
	)
	(gr_line
		(start 41.75506 -111.930942)
		(end 41.776142 -111.900716)
		(stroke
			(width 0.08255)
			(type default)
		)
		(layer "In2.Cu")
	)
	(gr_line
		(start 41.776142 -111.900716)
		(end 41.782492 -111.864902)
		(stroke
			(width 0.08255)
			(type default)
		)
		(layer "In2.Cu")
	)
	(gr_line
		(start 41.790366 -211.68233)
		(end 41.811448 -211.652104)
		(stroke
			(width 0.08255)
			(type default)
		)
		(layer "In2.Cu")
	)
	(gr_line
		(start 41.811448 -211.652104)
		(end 41.817798 -211.61629)
		(stroke
			(width 0.08255)
			(type default)
		)
		(layer "In2.Cu")
	)
	(gr_line
		(start 41.82618 -443.028578)
		(end 41.846754 -443.025022)
		(stroke
			(width 0.08255)
			(type default)
		)
		(layer "In2.Cu")
	)
	(gr_line
		(start 41.82745 -416.781488)
		(end 41.961308 -416.023298)
		(stroke
			(width 0.08255)
			(type default)
		)
		(layer "In2.Cu")
	)
	(gr_line
		(start 41.84015 -444.014606)
		(end 41.862756 -444.010542)
		(stroke
			(width 0.08255)
			(type default)
		)
		(layer "In2.Cu")
	)
	(gr_line
		(start 41.842944 -442.02604)
		(end 41.863518 -442.022484)
		(stroke
			(width 0.08255)
			(type default)
		)
		(layer "In2.Cu")
	)
	(gr_line
		(start 41.846754 -443.025022)
		(end 41.867328 -443.028578)
		(stroke
			(width 0.08255)
			(type default)
		)
		(layer "In2.Cu")
	)
	(gr_line
		(start 41.850818 -103.194612)
		(end 41.869106 -103.207312)
		(stroke
			(width 0.08255)
			(type default)
		)
		(layer "In2.Cu")
	)
	(gr_line
		(start 41.862756 -444.010542)
		(end 41.884854 -444.014606)
		(stroke
			(width 0.08255)
			(type default)
		)
		(layer "In2.Cu")
	)
	(gr_line
		(start 41.863518 -442.022484)
		(end 41.884092 -442.02604)
		(stroke
			(width 0.08255)
			(type default)
		)
		(layer "In2.Cu")
	)
	(gr_line
		(start 41.869106 -103.207312)
		(end 41.881806 -103.2256)
		(stroke
			(width 0.08255)
			(type default)
		)
		(layer "In2.Cu")
	)
	(gr_line
		(start 41.939972 -207.357472)
		(end 41.961054 -207.387698)
		(stroke
			(width 0.08255)
			(type default)
		)
		(layer "In2.Cu")
	)
	(gr_line
		(start 41.961054 -207.387698)
		(end 41.967404 -207.423766)
		(stroke
			(width 0.08255)
			(type default)
		)
		(layer "In2.Cu")
	)
	(gr_line
		(start 41.982898 -115.873276)
		(end 41.989248 -115.837462)
		(stroke
			(width 0.08255)
			(type default)
		)
		(layer "In2.Cu")
	)
	(gr_line
		(start 41.989248 -115.837462)
		(end 42.01033 -115.807236)
		(stroke
			(width 0.08255)
			(type default)
		)
		(layer "In2.Cu")
	)
	(gr_line
		(start 42.077132 -204.229208)
		(end 42.09542 -204.241908)
		(stroke
			(width 0.08255)
			(type default)
		)
		(layer "In2.Cu")
	)
	(gr_line
		(start 42.09542 -204.241908)
		(end 42.10812 -204.260196)
		(stroke
			(width 0.08255)
			(type default)
		)
		(layer "In2.Cu")
	)
	(gr_line
		(start 42.258742 -209.11693)
		(end 42.262298 -209.096102)
		(stroke
			(width 0.08255)
			(type default)
		)
		(layer "In2.Cu")
	)
	(gr_line
		(start 42.258742 -209.116676)
		(end 42.258742 -209.117438)
		(stroke
			(width 0.08255)
			(type default)
		)
		(layer "In2.Cu")
	)
	(gr_line
		(start 42.258742 -209.075528)
		(end 42.262298 -209.096102)
		(stroke
			(width 0.08255)
			(type default)
		)
		(layer "In2.Cu")
	)
	(gr_line
		(start 42.375582 -103.93045)
		(end 42.396664 -103.960676)
		(stroke
			(width 0.08255)
			(type default)
		)
		(layer "In2.Cu")
	)
	(gr_line
		(start 42.396664 -103.960676)
		(end 42.403014 -103.996744)
		(stroke
			(width 0.08255)
			(type default)
		)
		(layer "In2.Cu")
	)
	(gr_line
		(start 42.52595 -102.562406)
		(end 42.544238 -102.575106)
		(stroke
			(width 0.08255)
			(type default)
		)
		(layer "In2.Cu")
	)
	(gr_line
		(start 42.544238 -102.575106)
		(end 42.556938 -102.593394)
		(stroke
			(width 0.08255)
			(type default)
		)
		(layer "In2.Cu")
	)
	(gr_line
		(start 42.669714 -112.2934)
		(end 42.690796 -112.263174)
		(stroke
			(width 0.08255)
			(type default)
		)
		(layer "In2.Cu")
	)
	(gr_line
		(start 42.690796 -112.263174)
		(end 42.697146 -112.22736)
		(stroke
			(width 0.08255)
			(type default)
		)
		(layer "In2.Cu")
	)
	(gr_line
		(start 42.723562 -212.02015)
		(end 42.744644 -211.989924)
		(stroke
			(width 0.08255)
			(type default)
		)
		(layer "In2.Cu")
	)
	(gr_line
		(start 42.744644 -211.989924)
		(end 42.750994 -211.953856)
		(stroke
			(width 0.08255)
			(type default)
		)
		(layer "In2.Cu")
	)
	(gr_line
		(start 42.782236 -206.818992)
		(end 42.803318 -206.849218)
		(stroke
			(width 0.08255)
			(type default)
		)
		(layer "In2.Cu")
	)
	(gr_line
		(start 42.782998 -106.192828)
		(end 42.786554 -106.172254)
		(stroke
			(width 0.08255)
			(type default)
		)
		(layer "In2.Cu")
	)
	(gr_line
		(start 42.782998 -106.151426)
		(end 42.786554 -106.172254)
		(stroke
			(width 0.08255)
			(type default)
		)
		(layer "In2.Cu")
	)
	(gr_line
		(start 42.782998 -106.150918)
		(end 42.782998 -106.15168)
		(stroke
			(width 0.08255)
			(type default)
		)
		(layer "In2.Cu")
	)
	(gr_line
		(start 42.803318 -206.849218)
		(end 42.809668 -206.885286)
		(stroke
			(width 0.08255)
			(type default)
		)
		(layer "In2.Cu")
	)
	(gr_line
		(start 42.881804 -203.63688)
		(end 42.900092 -203.64958)
		(stroke
			(width 0.08255)
			(type default)
		)
		(layer "In2.Cu")
	)
	(gr_line
		(start 42.900092 -203.64958)
		(end 42.912792 -203.667868)
		(stroke
			(width 0.08255)
			(type default)
		)
		(layer "In2.Cu")
	)
	(gr_line
		(start 43.061128 -101.730302)
		(end 43.079416 -101.743002)
		(stroke
			(width 0.08255)
			(type default)
		)
		(layer "In2.Cu")
	)
	(gr_line
		(start 43.079416 -101.743002)
		(end 43.092116 -101.76129)
		(stroke
			(width 0.08255)
			(type default)
		)
		(layer "In2.Cu")
	)
	(gr_line
		(start 43.223688 -209.274156)
		(end 43.227244 -209.253582)
		(stroke
			(width 0.08255)
			(type default)
		)
		(layer "In2.Cu")
	)
	(gr_line
		(start 43.223688 -209.232754)
		(end 43.227244 -209.253582)
		(stroke
			(width 0.08255)
			(type default)
		)
		(layer "In2.Cu")
	)
	(gr_line
		(start 43.223688 -209.232246)
		(end 43.223688 -209.233008)
		(stroke
			(width 0.08255)
			(type default)
		)
		(layer "In2.Cu")
	)
	(gr_line
		(start 43.307254 -103.66502)
		(end 43.328336 -103.695246)
		(stroke
			(width 0.08255)
			(type default)
		)
		(layer "In2.Cu")
	)
	(gr_line
		(start 43.328336 -103.695246)
		(end 43.334686 -103.73106)
		(stroke
			(width 0.08255)
			(type default)
		)
		(layer "In2.Cu")
	)
	(gr_line
		(start 43.645582 -112.47755)
		(end 43.666664 -112.447324)
		(stroke
			(width 0.08255)
			(type default)
		)
		(layer "In2.Cu")
	)
	(gr_line
		(start 43.666664 -112.447324)
		(end 43.673014 -112.41151)
		(stroke
			(width 0.08255)
			(type default)
		)
		(layer "In2.Cu")
	)
	(gr_line
		(start 43.717972 -212.269324)
		(end 43.739054 -212.239098)
		(stroke
			(width 0.08255)
			(type default)
		)
		(layer "In2.Cu")
	)
	(gr_line
		(start 43.739054 -212.239098)
		(end 43.745404 -212.20303)
		(stroke
			(width 0.08255)
			(type default)
		)
		(layer "In2.Cu")
	)
	(gr_line
		(start 43.76166 -106.192828)
		(end 43.765216 -106.172)
		(stroke
			(width 0.08255)
			(type default)
		)
		(layer "In2.Cu")
	)
	(gr_line
		(start 43.76166 -106.192574)
		(end 43.76166 -106.193336)
		(stroke
			(width 0.08255)
			(type default)
		)
		(layer "In2.Cu")
	)
	(gr_line
		(start 43.76166 -106.151426)
		(end 43.765216 -106.172)
		(stroke
			(width 0.08255)
			(type default)
		)
		(layer "In2.Cu")
	)
	(gr_line
		(start 43.788584 -101.046026)
		(end 43.806872 -101.058726)
		(stroke
			(width 0.08255)
			(type default)
		)
		(layer "In2.Cu")
	)
	(gr_line
		(start 43.793918 -206.667354)
		(end 43.815 -206.69758)
		(stroke
			(width 0.08255)
			(type default)
		)
		(layer "In2.Cu")
	)
	(gr_line
		(start 43.806872 -101.058726)
		(end 43.819572 -101.077014)
		(stroke
			(width 0.08255)
			(type default)
		)
		(layer "In2.Cu")
	)
	(gr_line
		(start 43.815 -206.69758)
		(end 43.82135 -206.733648)
		(stroke
			(width 0.08255)
			(type default)
		)
		(layer "In2.Cu")
	)
	(gr_line
		(start 44.209208 -103.356918)
		(end 44.23029 -103.387144)
		(stroke
			(width 0.08255)
			(type default)
		)
		(layer "In2.Cu")
	)
	(gr_line
		(start 44.23029 -103.387144)
		(end 44.23664 -103.423212)
		(stroke
			(width 0.08255)
			(type default)
		)
		(layer "In2.Cu")
	)
	(gr_line
		(start 44.26204 -209.274156)
		(end 44.265596 -209.253582)
		(stroke
			(width 0.08255)
			(type default)
		)
		(layer "In2.Cu")
	)
	(gr_line
		(start 44.26204 -209.232754)
		(end 44.265596 -209.253582)
		(stroke
			(width 0.08255)
			(type default)
		)
		(layer "In2.Cu")
	)
	(gr_line
		(start 44.26204 -209.232246)
		(end 44.26204 -209.233008)
		(stroke
			(width 0.08255)
			(type default)
		)
		(layer "In2.Cu")
	)
	(gr_line
		(start 44.614084 -212.695028)
		(end 44.635166 -212.664802)
		(stroke
			(width 0.08255)
			(type default)
		)
		(layer "In2.Cu")
	)
	(gr_line
		(start 44.635166 -212.664802)
		(end 44.641516 -212.628734)
		(stroke
			(width 0.08255)
			(type default)
		)
		(layer "In2.Cu")
	)
	(gr_line
		(start 44.643294 -112.667288)
		(end 44.664376 -112.637062)
		(stroke
			(width 0.08255)
			(type default)
		)
		(layer "In2.Cu")
	)
	(gr_line
		(start 44.661328 -206.164688)
		(end 44.68241 -206.194914)
		(stroke
			(width 0.08255)
			(type default)
		)
		(layer "In2.Cu")
	)
	(gr_line
		(start 44.664376 -112.637062)
		(end 44.670726 -112.601248)
		(stroke
			(width 0.08255)
			(type default)
		)
		(layer "In2.Cu")
	)
	(gr_line
		(start 44.68241 -206.194914)
		(end 44.68876 -206.230728)
		(stroke
			(width 0.08255)
			(type default)
		)
		(layer "In2.Cu")
	)
	(gr_line
		(start 44.743878 -106.341164)
		(end 44.747434 -106.320336)
		(stroke
			(width 0.08255)
			(type default)
		)
		(layer "In2.Cu")
	)
	(gr_line
		(start 44.743878 -106.34091)
		(end 44.743878 -106.341672)
		(stroke
			(width 0.08255)
			(type default)
		)
		(layer "In2.Cu")
	)
	(gr_line
		(start 44.743878 -106.299762)
		(end 44.747434 -106.320336)
		(stroke
			(width 0.08255)
			(type default)
		)
		(layer "In2.Cu")
	)
	(gr_line
		(start 45.110908 -102.921562)
		(end 45.13199 -102.951788)
		(stroke
			(width 0.08255)
			(type default)
		)
		(layer "In2.Cu")
	)
	(gr_line
		(start 45.13199 -102.951788)
		(end 45.13834 -102.987602)
		(stroke
			(width 0.08255)
			(type default)
		)
		(layer "In2.Cu")
	)
	(gr_line
		(start 45.183552 -303.214024)
		(end 45.21962 -303.207674)
		(stroke
			(width 0.08255)
			(type default)
		)
		(layer "In2.Cu")
	)
	(gr_line
		(start 45.21962 -303.207674)
		(end 45.249846 -303.186592)
		(stroke
			(width 0.08255)
			(type default)
		)
		(layer "In2.Cu")
	)
	(gr_line
		(start 45.225716 -209.316574)
		(end 45.229272 -209.296)
		(stroke
			(width 0.08255)
			(type default)
		)
		(layer "In2.Cu")
	)
	(gr_line
		(start 45.225716 -209.275172)
		(end 45.229272 -209.296)
		(stroke
			(width 0.08255)
			(type default)
		)
		(layer "In2.Cu")
	)
	(gr_line
		(start 45.225716 -209.274664)
		(end 45.225716 -209.275426)
		(stroke
			(width 0.08255)
			(type default)
		)
		(layer "In2.Cu")
	)
	(gr_line
		(start 45.543724 -304.092102)
		(end 45.579792 -304.085752)
		(stroke
			(width 0.08255)
			(type default)
		)
		(layer "In2.Cu")
	)
	(gr_line
		(start 45.579792 -304.085752)
		(end 45.610018 -304.06467)
		(stroke
			(width 0.08255)
			(type default)
		)
		(layer "In2.Cu")
	)
	(gr_line
		(start 45.748702 -106.489246)
		(end 45.752258 -106.468418)
		(stroke
			(width 0.08255)
			(type default)
		)
		(layer "In2.Cu")
	)
	(gr_line
		(start 45.748702 -106.488992)
		(end 45.748702 -106.489754)
		(stroke
			(width 0.08255)
			(type default)
		)
		(layer "In2.Cu")
	)
	(gr_line
		(start 45.748702 -106.447844)
		(end 45.752258 -106.468418)
		(stroke
			(width 0.08255)
			(type default)
		)
		(layer "In2.Cu")
	)
	(gr_line
		(start 45.89907 -304.950368)
		(end 45.935138 -304.944018)
		(stroke
			(width 0.08255)
			(type default)
		)
		(layer "In2.Cu")
	)
	(gr_line
		(start 45.935138 -304.944018)
		(end 45.965364 -304.922936)
		(stroke
			(width 0.08255)
			(type default)
		)
		(layer "In2.Cu")
	)
	(gr_line
		(start 46.347888 -305.802792)
		(end 46.383956 -305.796442)
		(stroke
			(width 0.08255)
			(type default)
		)
		(layer "In2.Cu")
	)
	(gr_line
		(start 46.383956 -305.796442)
		(end 46.414182 -305.77536)
		(stroke
			(width 0.08255)
			(type default)
		)
		(layer "In2.Cu")
	)
	(gr_line
		(start 54.52872 -212.228176)
		(end 54.54142 -212.209888)
		(stroke
			(width 0.08255)
			(type default)
		)
		(layer "In2.Cu")
	)
	(gr_line
		(start 54.54142 -212.209888)
		(end 54.559708 -212.197188)
		(stroke
			(width 0.08255)
			(type default)
		)
		(layer "In2.Cu")
	)
	(gr_line
		(start 55.21071 -212.887052)
		(end 55.22341 -212.868764)
		(stroke
			(width 0.08255)
			(type default)
		)
		(layer "In2.Cu")
	)
	(gr_line
		(start 55.22341 -212.868764)
		(end 55.241698 -212.856064)
		(stroke
			(width 0.08255)
			(type default)
		)
		(layer "In2.Cu")
	)
	(gr_line
		(start 55.863744 -213.556596)
		(end 55.876444 -213.538308)
		(stroke
			(width 0.08255)
			(type default)
		)
		(layer "In2.Cu")
	)
	(gr_line
		(start 55.876444 -213.538308)
		(end 55.894732 -213.525608)
		(stroke
			(width 0.08255)
			(type default)
		)
		(layer "In2.Cu")
	)
	(gr_line
		(start 57.319164 -214.12581)
		(end 57.331864 -214.107522)
		(stroke
			(width 0.08255)
			(type default)
		)
		(layer "In2.Cu")
	)
	(gr_line
		(start 57.331864 -214.107522)
		(end 57.350152 -214.094822)
		(stroke
			(width 0.08255)
			(type default)
		)
		(layer "In2.Cu")
	)
	(gr_line
		(start 66.811144 -287.655762)
		(end 66.84137 -287.63468)
		(stroke
			(width 0.08255)
			(type default)
		)
		(layer "In2.Cu")
	)
	(gr_line
		(start 66.84137 -287.63468)
		(end 66.877438 -287.62833)
		(stroke
			(width 0.08255)
			(type default)
		)
		(layer "In2.Cu")
	)
	(gr_line
		(start 67.10934 -288.577274)
		(end 67.139566 -288.556192)
		(stroke
			(width 0.08255)
			(type default)
		)
		(layer "In2.Cu")
	)
	(gr_line
		(start 67.139566 -288.556192)
		(end 67.175634 -288.549842)
		(stroke
			(width 0.08255)
			(type default)
		)
		(layer "In2.Cu")
	)
	(gr_line
		(start 67.406266 -289.475926)
		(end 67.436492 -289.454844)
		(stroke
			(width 0.08255)
			(type default)
		)
		(layer "In2.Cu")
	)
	(gr_line
		(start 67.436492 -289.454844)
		(end 67.47256 -289.448494)
		(stroke
			(width 0.08255)
			(type default)
		)
		(layer "In2.Cu")
	)
	(gr_line
		(start 67.741546 -290.407852)
		(end 67.771772 -290.38677)
		(stroke
			(width 0.08255)
			(type default)
		)
		(layer "In2.Cu")
	)
	(gr_line
		(start 67.771772 -290.38677)
		(end 67.80784 -290.38042)
		(stroke
			(width 0.08255)
			(type default)
		)
		(layer "In2.Cu")
	)
	(gr_line
		(start 81.500726 -193.333624)
		(end 81.530952 -193.312542)
		(stroke
			(width 0.08255)
			(type default)
		)
		(layer "In2.Cu")
	)
	(gr_line
		(start 81.530952 -193.312542)
		(end 81.56702 -193.306192)
		(stroke
			(width 0.08255)
			(type default)
		)
		(layer "In2.Cu")
	)
	(gr_line
		(start 81.8642 -194.213988)
		(end 81.894426 -194.192906)
		(stroke
			(width 0.08255)
			(type default)
		)
		(layer "In2.Cu")
	)
	(gr_line
		(start 81.894426 -194.192906)
		(end 81.930494 -194.186556)
		(stroke
			(width 0.08255)
			(type default)
		)
		(layer "In2.Cu")
	)
	(gr_line
		(start 82.168492 -195.12788)
		(end 82.198718 -195.106798)
		(stroke
			(width 0.08255)
			(type default)
		)
		(layer "In2.Cu")
	)
	(gr_line
		(start 82.198718 -195.106798)
		(end 82.234786 -195.100448)
		(stroke
			(width 0.08255)
			(type default)
		)
		(layer "In2.Cu")
	)
	(gr_line
		(start 83.410298 -195.8467)
		(end 83.440524 -195.825618)
		(stroke
			(width 0.08255)
			(type default)
		)
		(layer "In2.Cu")
	)
	(gr_line
		(start 83.440524 -195.825618)
		(end 83.476592 -195.819268)
		(stroke
			(width 0.08255)
			(type default)
		)
		(layer "In2.Cu")
	)
	(gr_line
		(start 87.354664 -158.293816)
		(end 87.367364 -158.275528)
		(stroke
			(width 0.08255)
			(type default)
		)
		(layer "In2.Cu")
	)
	(gr_line
		(start 87.367364 -158.275528)
		(end 87.385652 -158.262828)
		(stroke
			(width 0.08255)
			(type default)
		)
		(layer "In2.Cu")
	)
	(gr_line
		(start 87.894668 -159.161734)
		(end 87.907368 -159.143446)
		(stroke
			(width 0.08255)
			(type default)
		)
		(layer "In2.Cu")
	)
	(gr_line
		(start 87.907368 -159.143446)
		(end 87.925656 -159.130746)
		(stroke
			(width 0.08255)
			(type default)
		)
		(layer "In2.Cu")
	)
	(gr_line
		(start 88.641174 -159.83331)
		(end 88.653874 -159.815022)
		(stroke
			(width 0.08255)
			(type default)
		)
		(layer "In2.Cu")
	)
	(gr_line
		(start 88.653874 -159.815022)
		(end 88.672162 -159.802322)
		(stroke
			(width 0.08255)
			(type default)
		)
		(layer "In2.Cu")
	)
	(gr_line
		(start 89.17051 -160.670748)
		(end 89.18321 -160.65246)
		(stroke
			(width 0.08255)
			(type default)
		)
		(layer "In2.Cu")
	)
	(gr_line
		(start 89.18321 -160.65246)
		(end 89.201498 -160.63976)
		(stroke
			(width 0.08255)
			(type default)
		)
		(layer "In2.Cu")
	)
	(gr_line
		(start 157.637988 -274.547584)
		(end 157.658562 -274.544028)
		(stroke
			(width 0.08255)
			(type default)
		)
		(layer "In2.Cu")
	)
	(gr_line
		(start 157.658562 -274.544028)
		(end 157.679136 -274.547584)
		(stroke
			(width 0.08255)
			(type default)
		)
		(layer "In2.Cu")
	)
	(gr_line
		(start 168.378124 -271.656556)
		(end 168.398698 -271.653)
		(stroke
			(width 0.08255)
			(type default)
		)
		(layer "In2.Cu")
	)
	(gr_line
		(start 168.398698 -271.653)
		(end 168.419272 -271.656556)
		(stroke
			(width 0.08255)
			(type default)
		)
		(layer "In2.Cu")
	)
	(gr_line
		(start 179.373784 -268.771116)
		(end 179.394358 -268.76756)
		(stroke
			(width 0.08255)
			(type default)
		)
		(layer "In2.Cu")
	)
	(gr_line
		(start 179.394358 -268.76756)
		(end 179.414932 -268.771116)
		(stroke
			(width 0.08255)
			(type default)
		)
		(layer "In2.Cu")
	)
	(gr_line
		(start 188.759338 -469.924892)
		(end 188.796168 -469.931496)
		(stroke
			(width 0.08255)
			(type default)
		)
		(layer "In2.Cu")
	)
	(gr_line
		(start 188.796168 -469.931496)
		(end 188.826394 -469.952832)
		(stroke
			(width 0.08255)
			(type default)
		)
		(layer "In2.Cu")
	)
	(gr_line
		(start 189.287912 -177.169572)
		(end 189.308486 -177.166016)
		(stroke
			(width 0.08255)
			(type default)
		)
		(layer "In2.Cu")
	)
	(gr_line
		(start 189.308486 -177.166016)
		(end 189.32906 -177.169572)
		(stroke
			(width 0.08255)
			(type default)
		)
		(layer "In2.Cu")
	)
	(gr_line
		(start 192.783714 -175.6156)
		(end 192.804288 -175.612044)
		(stroke
			(width 0.08255)
			(type default)
		)
		(layer "In2.Cu")
	)
	(gr_line
		(start 192.804288 -175.612044)
		(end 192.824862 -175.6156)
		(stroke
			(width 0.08255)
			(type default)
		)
		(layer "In2.Cu")
	)
	(gr_line
		(start 195.346066 -470.098882)
		(end 195.38188 -470.105232)
		(stroke
			(width 0.08255)
			(type default)
		)
		(layer "In2.Cu")
	)
	(gr_line
		(start 195.38188 -470.105232)
		(end 195.412106 -470.126314)
		(stroke
			(width 0.08255)
			(type default)
		)
		(layer "In2.Cu")
	)
	(gr_line
		(start 199.676258 -83.28152)
		(end 199.706484 -83.260438)
		(stroke
			(width 0.08255)
			(type default)
		)
		(layer "In2.Cu")
	)
	(gr_line
		(start 199.706484 -83.260438)
		(end 199.742552 -83.254088)
		(stroke
			(width 0.08255)
			(type default)
		)
		(layer "In2.Cu")
	)
	(gr_line
		(start 202.061826 -470.272618)
		(end 202.097894 -470.278968)
		(stroke
			(width 0.08255)
			(type default)
		)
		(layer "In2.Cu")
	)
	(gr_line
		(start 202.097894 -470.278968)
		(end 202.12812 -470.30005)
		(stroke
			(width 0.08255)
			(type default)
		)
		(layer "In2.Cu")
	)
	(gr_line
		(start 203.843382 -172.105828)
		(end 203.87945 -172.099478)
		(stroke
			(width 0.08255)
			(type default)
		)
		(layer "In2.Cu")
	)
	(gr_line
		(start 203.87945 -172.099478)
		(end 203.909676 -172.078396)
		(stroke
			(width 0.08255)
			(type default)
		)
		(layer "In2.Cu")
	)
	(gr_line
		(start 206.563214 -77.253084)
		(end 206.59344 -77.232002)
		(stroke
			(width 0.08255)
			(type default)
		)
		(layer "In2.Cu")
	)
	(gr_line
		(start 206.59344 -77.232002)
		(end 206.629508 -77.225652)
		(stroke
			(width 0.08255)
			(type default)
		)
		(layer "In2.Cu")
	)
	(gr_line
		(start 206.88554 -75.018392)
		(end 206.903828 -75.005692)
		(stroke
			(width 0.08255)
			(type default)
		)
		(layer "In2.Cu")
	)
	(gr_line
		(start 206.903828 -75.005692)
		(end 206.916528 -74.987404)
		(stroke
			(width 0.08255)
			(type default)
		)
		(layer "In2.Cu")
	)
	(gr_line
		(start 210.979004 -471.23477)
		(end 210.999832 -471.238326)
		(stroke
			(width 0.08255)
			(type default)
		)
		(layer "In2.Cu")
	)
	(gr_line
		(start 210.999832 -471.238326)
		(end 211.020406 -471.23477)
		(stroke
			(width 0.08255)
			(type default)
		)
		(layer "In2.Cu")
	)
	(gr_line
		(start 211.199222 -171.393612)
		(end 211.219796 -171.390056)
		(stroke
			(width 0.08255)
			(type default)
		)
		(layer "In2.Cu")
	)
	(gr_line
		(start 211.219796 -171.390056)
		(end 211.240624 -171.393612)
		(stroke
			(width 0.08255)
			(type default)
		)
		(layer "In2.Cu")
	)
	(gr_line
		(start 211.759038 -377.493276)
		(end 211.779612 -377.48972)
		(stroke
			(width 0.08255)
			(type default)
		)
		(layer "In2.Cu")
	)
	(gr_line
		(start 211.779612 -377.48972)
		(end 211.80044 -377.493276)
		(stroke
			(width 0.08255)
			(type default)
		)
		(layer "In2.Cu")
	)
	(gr_line
		(start 212.842602 -261.896606)
		(end 212.863176 -261.89305)
		(stroke
			(width 0.08255)
			(type default)
		)
		(layer "In2.Cu")
	)
	(gr_line
		(start 212.863176 -261.89305)
		(end 212.88375 -261.896606)
		(stroke
			(width 0.08255)
			(type default)
		)
		(layer "In2.Cu")
	)
	(gr_line
		(start 213.404704 -71.270368)
		(end 213.43493 -71.249286)
		(stroke
			(width 0.08255)
			(type default)
		)
		(layer "In2.Cu")
	)
	(gr_line
		(start 213.43493 -71.249286)
		(end 213.470998 -71.242936)
		(stroke
			(width 0.08255)
			(type default)
		)
		(layer "In2.Cu")
	)
	(gr_line
		(start 213.457536 -179.615338)
		(end 213.484968 -179.620164)
		(stroke
			(width 0.08255)
			(type default)
		)
		(layer "In2.Cu")
	)
	(gr_line
		(start 213.484968 -179.620164)
		(end 213.512146 -179.614322)
		(stroke
			(width 0.08255)
			(type default)
		)
		(layer "In2.Cu")
	)
	(gr_line
		(start 218.061286 -58.450734)
		(end 218.073986 -58.432446)
		(stroke
			(width 0.08255)
			(type default)
		)
		(layer "In2.Cu")
	)
	(gr_line
		(start 218.073986 -58.432446)
		(end 218.092274 -58.419746)
		(stroke
			(width 0.08255)
			(type default)
		)
		(layer "In2.Cu")
	)
	(gr_line
		(start 218.12504 -481.935282)
		(end 218.155266 -481.956364)
		(stroke
			(width 0.08255)
			(type default)
		)
		(layer "In2.Cu")
	)
	(gr_line
		(start 218.155266 -481.956364)
		(end 218.191334 -481.962714)
		(stroke
			(width 0.08255)
			(type default)
		)
		(layer "In2.Cu")
	)
	(gr_line
		(start 218.665552 -486.839514)
		(end 218.695778 -486.860596)
		(stroke
			(width 0.08255)
			(type default)
		)
		(layer "In2.Cu")
	)
	(gr_line
		(start 218.695778 -486.860596)
		(end 218.731846 -486.866946)
		(stroke
			(width 0.08255)
			(type default)
		)
		(layer "In2.Cu")
	)
	(gr_line
		(start 219.40647 -491.783116)
		(end 219.437458 -491.80496)
		(stroke
			(width 0.08255)
			(type default)
		)
		(layer "In2.Cu")
	)
	(gr_line
		(start 219.437458 -491.80496)
		(end 219.474796 -491.81131)
		(stroke
			(width 0.08255)
			(type default)
		)
		(layer "In2.Cu")
	)
	(gr_line
		(start 219.61983 -57.350406)
		(end 219.650056 -57.329324)
		(stroke
			(width 0.08255)
			(type default)
		)
		(layer "In2.Cu")
	)
	(gr_line
		(start 219.650056 -57.329324)
		(end 219.68587 -57.322974)
		(stroke
			(width 0.08255)
			(type default)
		)
		(layer "In2.Cu")
	)
	(gr_line
		(start 220.175328 -366.252506)
		(end 220.232732 -366.212374)
		(stroke
			(width 0.08255)
			(type default)
		)
		(layer "In2.Cu")
	)
	(gr_line
		(start 220.179646 -160.25241)
		(end 220.23705 -160.212278)
		(stroke
			(width 0.08255)
			(type default)
		)
		(layer "In2.Cu")
	)
	(gr_line
		(start 221.421452 -492.043466)
		(end 221.727014 -492.349028)
		(stroke
			(width 0.08255)
			(type default)
		)
		(layer "In2.Cu")
	)
	(gr_line
		(start 221.421452 -491.53699)
		(end 221.727014 -491.231428)
		(stroke
			(width 0.08255)
			(type default)
		)
		(layer "In2.Cu")
	)
	(gr_line
		(start 221.421452 -487.243374)
		(end 221.727014 -487.548936)
		(stroke
			(width 0.08255)
			(type default)
		)
		(layer "In2.Cu")
	)
	(gr_line
		(start 221.421452 -486.736898)
		(end 221.727014 -486.431336)
		(stroke
			(width 0.08255)
			(type default)
		)
		(layer "In2.Cu")
	)
	(gr_line
		(start 221.421452 -482.443282)
		(end 221.727014 -482.748844)
		(stroke
			(width 0.08255)
			(type default)
		)
		(layer "In2.Cu")
	)
	(gr_line
		(start 221.421452 -481.936806)
		(end 221.727014 -481.631244)
		(stroke
			(width 0.08255)
			(type default)
		)
		(layer "In2.Cu")
	)
	(gr_line
		(start 221.421452 -469.64346)
		(end 221.727014 -469.949022)
		(stroke
			(width 0.08255)
			(type default)
		)
		(layer "In2.Cu")
	)
	(gr_line
		(start 221.421452 -469.136984)
		(end 221.727014 -468.831422)
		(stroke
			(width 0.08255)
			(type default)
		)
		(layer "In2.Cu")
	)
	(gr_line
		(start 221.421452 -389.043418)
		(end 221.727014 -389.34898)
		(stroke
			(width 0.08255)
			(type default)
		)
		(layer "In2.Cu")
	)
	(gr_line
		(start 221.421452 -388.536942)
		(end 221.727014 -388.23138)
		(stroke
			(width 0.08255)
			(type default)
		)
		(layer "In2.Cu")
	)
	(gr_line
		(start 221.421452 -384.243326)
		(end 221.727014 -384.548888)
		(stroke
			(width 0.08255)
			(type default)
		)
		(layer "In2.Cu")
	)
	(gr_line
		(start 221.421452 -383.73685)
		(end 221.727014 -383.431288)
		(stroke
			(width 0.08255)
			(type default)
		)
		(layer "In2.Cu")
	)
	(gr_line
		(start 221.421452 -379.443234)
		(end 221.727014 -379.748796)
		(stroke
			(width 0.08255)
			(type default)
		)
		(layer "In2.Cu")
	)
	(gr_line
		(start 221.421452 -378.936758)
		(end 221.727014 -378.631196)
		(stroke
			(width 0.08255)
			(type default)
		)
		(layer "In2.Cu")
	)
	(gr_line
		(start 221.421452 -366.643412)
		(end 221.727014 -366.948974)
		(stroke
			(width 0.08255)
			(type default)
		)
		(layer "In2.Cu")
	)
	(gr_line
		(start 221.421452 -366.136936)
		(end 221.727014 -365.831374)
		(stroke
			(width 0.08255)
			(type default)
		)
		(layer "In2.Cu")
	)
	(gr_line
		(start 221.421452 -286.04337)
		(end 221.727014 -286.348932)
		(stroke
			(width 0.08255)
			(type default)
		)
		(layer "In2.Cu")
	)
	(gr_line
		(start 221.421452 -285.536894)
		(end 221.727014 -285.231332)
		(stroke
			(width 0.08255)
			(type default)
		)
		(layer "In2.Cu")
	)
	(gr_line
		(start 221.421452 -281.243278)
		(end 221.727014 -281.54884)
		(stroke
			(width 0.08255)
			(type default)
		)
		(layer "In2.Cu")
	)
	(gr_line
		(start 221.421452 -280.736802)
		(end 221.727014 -280.43124)
		(stroke
			(width 0.08255)
			(type default)
		)
		(layer "In2.Cu")
	)
	(gr_line
		(start 221.421452 -276.443186)
		(end 221.727014 -276.748748)
		(stroke
			(width 0.08255)
			(type default)
		)
		(layer "In2.Cu")
	)
	(gr_line
		(start 221.421452 -275.93671)
		(end 221.727014 -275.631148)
		(stroke
			(width 0.08255)
			(type default)
		)
		(layer "In2.Cu")
	)
	(gr_line
		(start 221.421452 -263.643364)
		(end 221.727014 -263.948926)
		(stroke
			(width 0.08255)
			(type default)
		)
		(layer "In2.Cu")
	)
	(gr_line
		(start 221.421452 -263.136888)
		(end 221.727014 -262.831326)
		(stroke
			(width 0.08255)
			(type default)
		)
		(layer "In2.Cu")
	)
	(gr_line
		(start 221.421452 -183.043322)
		(end 221.727014 -183.348884)
		(stroke
			(width 0.08255)
			(type default)
		)
		(layer "In2.Cu")
	)
	(gr_line
		(start 221.421452 -182.536846)
		(end 221.727014 -182.231284)
		(stroke
			(width 0.08255)
			(type default)
		)
		(layer "In2.Cu")
	)
	(gr_line
		(start 221.421452 -178.24323)
		(end 221.727014 -178.548792)
		(stroke
			(width 0.08255)
			(type default)
		)
		(layer "In2.Cu")
	)
	(gr_line
		(start 221.421452 -177.736754)
		(end 221.727014 -177.431192)
		(stroke
			(width 0.08255)
			(type default)
		)
		(layer "In2.Cu")
	)
	(gr_line
		(start 221.421452 -173.443138)
		(end 221.727014 -173.7487)
		(stroke
			(width 0.08255)
			(type default)
		)
		(layer "In2.Cu")
	)
	(gr_line
		(start 221.421452 -172.936662)
		(end 221.727014 -172.6311)
		(stroke
			(width 0.08255)
			(type default)
		)
		(layer "In2.Cu")
	)
	(gr_line
		(start 221.421452 -160.643316)
		(end 221.727014 -160.948878)
		(stroke
			(width 0.08255)
			(type default)
		)
		(layer "In2.Cu")
	)
	(gr_line
		(start 221.421452 -160.13684)
		(end 221.727014 -159.831278)
		(stroke
			(width 0.08255)
			(type default)
		)
		(layer "In2.Cu")
	)
	(gr_line
		(start 221.421452 -80.043274)
		(end 221.727014 -80.348836)
		(stroke
			(width 0.08255)
			(type default)
		)
		(layer "In2.Cu")
	)
	(gr_line
		(start 221.421452 -79.536798)
		(end 221.727014 -79.231236)
		(stroke
			(width 0.08255)
			(type default)
		)
		(layer "In2.Cu")
	)
	(gr_line
		(start 221.421452 -75.243182)
		(end 221.727014 -75.548744)
		(stroke
			(width 0.08255)
			(type default)
		)
		(layer "In2.Cu")
	)
	(gr_line
		(start 221.421452 -74.736706)
		(end 221.727014 -74.431144)
		(stroke
			(width 0.08255)
			(type default)
		)
		(layer "In2.Cu")
	)
	(gr_line
		(start 221.421452 -70.44309)
		(end 221.727014 -70.748652)
		(stroke
			(width 0.08255)
			(type default)
		)
		(layer "In2.Cu")
	)
	(gr_line
		(start 221.421452 -69.936614)
		(end 221.727014 -69.631052)
		(stroke
			(width 0.08255)
			(type default)
		)
		(layer "In2.Cu")
	)
	(gr_line
		(start 221.421452 -57.643268)
		(end 221.727014 -57.94883)
		(stroke
			(width 0.08255)
			(type default)
		)
		(layer "In2.Cu")
	)
	(gr_line
		(start 221.421452 -57.136792)
		(end 221.727014 -56.83123)
		(stroke
			(width 0.08255)
			(type default)
		)
		(layer "In2.Cu")
	)
	(gr_line
		(start 0 -505.000006)
		(end 0 -421.942006)
		(stroke
			(width 1.524)
			(type default)
		)
		(layer "In3.Cu")
	)
	(gr_arc
		(start 0 -505.000006)
		(mid 0.292895 -505.707108)
		(end 0.999998 -506.000004)
		(stroke
			(width 1.524)
			(type default)
		)
		(layer "In3.Cu")
	)
	(gr_line
		(start 0 -421.942006)
		(end 0.500126 -421.44188)
		(stroke
			(width 1.524)
			(type default)
		)
		(layer "In3.Cu")
	)
	(gr_line
		(start 0 -418.742114)
		(end 0 -315.941964)
		(stroke
			(width 1.524)
			(type default)
		)
		(layer "In3.Cu")
	)
	(gr_line
		(start 0 -315.941964)
		(end 0.500126 -315.442092)
		(stroke
			(width 1.524)
			(type default)
		)
		(layer "In3.Cu")
	)
	(gr_line
		(start 0 -312.742072)
		(end 0 -189.941962)
		(stroke
			(width 1.524)
			(type default)
		)
		(layer "In3.Cu")
	)
	(gr_line
		(start 0 -189.941962)
		(end 0.500126 -189.44209)
		(stroke
			(width 1.524)
			(type default)
		)
		(layer "In3.Cu")
	)
	(gr_line
		(start 0 -186.74207)
		(end 0 -0.999998)
		(stroke
			(width 1.524)
			(type default)
		)
		(layer "In3.Cu")
	)
	(gr_line
		(start 0.500126 -421.44188)
		(end 4.400042 -421.44188)
		(stroke
			(width 1.524)
			(type default)
		)
		(layer "In3.Cu")
	)
	(gr_line
		(start 0.500126 -419.241986)
		(end 0 -418.742114)
		(stroke
			(width 1.524)
			(type default)
		)
		(layer "In3.Cu")
	)
	(gr_line
		(start 0.500126 -315.442092)
		(end 4.400042 -315.442092)
		(stroke
			(width 1.524)
			(type default)
		)
		(layer "In3.Cu")
	)
	(gr_line
		(start 0.500126 -313.241944)
		(end 0 -312.742072)
		(stroke
			(width 1.524)
			(type default)
		)
		(layer "In3.Cu")
	)
	(gr_line
		(start 0.500126 -189.44209)
		(end 4.400042 -189.44209)
		(stroke
			(width 1.524)
			(type default)
		)
		(layer "In3.Cu")
	)
	(gr_line
		(start 0.500126 -187.241942)
		(end 0 -186.74207)
		(stroke
			(width 1.524)
			(type default)
		)
		(layer "In3.Cu")
	)
	(gr_arc
		(start 0.999998 0)
		(mid 0.292893 -0.292893)
		(end 0 -0.999998)
		(stroke
			(width 1.524)
			(type default)
		)
		(layer "In3.Cu")
	)
	(gr_line
		(start 0.999998 0)
		(end 30.80004 0)
		(stroke
			(width 1.524)
			(type default)
		)
		(layer "In3.Cu")
	)
	(gr_arc
		(start 4.400042 -421.44188)
		(mid 5.499862 -420.34206)
		(end 4.400042 -419.241986)
		(stroke
			(width 1.524)
			(type default)
		)
		(layer "In3.Cu")
	)
	(gr_line
		(start 4.400042 -419.241986)
		(end 0.500126 -419.241986)
		(stroke
			(width 1.524)
			(type default)
		)
		(layer "In3.Cu")
	)
	(gr_arc
		(start 4.400042 -315.442092)
		(mid 5.500116 -314.342018)
		(end 4.400042 -313.241944)
		(stroke
			(width 1.524)
			(type default)
		)
		(layer "In3.Cu")
	)
	(gr_line
		(start 4.400042 -313.241944)
		(end 0.500126 -313.241944)
		(stroke
			(width 1.524)
			(type default)
		)
		(layer "In3.Cu")
	)
	(gr_arc
		(start 4.400042 -189.44209)
		(mid 5.500116 -188.342016)
		(end 4.400042 -187.241942)
		(stroke
			(width 1.524)
			(type default)
		)
		(layer "In3.Cu")
	)
	(gr_line
		(start 4.400042 -187.241942)
		(end 0.500126 -187.241942)
		(stroke
			(width 1.524)
			(type default)
		)
		(layer "In3.Cu")
	)
	(gr_arc
		(start 4.56946 -445.54775)
		(mid 5.079873 -446.058544)
		(end 5.59054 -445.548004)
		(stroke
			(width 0.2)
			(type default)
		)
		(layer "In3.Cu")
	)
	(gr_line
		(start 4.56946 -444.735204)
		(end 4.56946 -445.54775)
		(stroke
			(width 0.2)
			(type default)
		)
		(layer "In3.Cu")
	)
	(gr_arc
		(start 4.56946 -442.347858)
		(mid 5.079873 -442.858652)
		(end 5.59054 -442.348112)
		(stroke
			(width 0.2)
			(type default)
		)
		(layer "In3.Cu")
	)
	(gr_line
		(start 4.56946 -441.535312)
		(end 4.56946 -442.347858)
		(stroke
			(width 0.2)
			(type default)
		)
		(layer "In3.Cu")
	)
	(gr_arc
		(start 4.56946 -439.147712)
		(mid 5.079873 -439.658506)
		(end 5.59054 -439.147966)
		(stroke
			(width 0.2)
			(type default)
		)
		(layer "In3.Cu")
	)
	(gr_line
		(start 4.56946 -438.335166)
		(end 4.56946 -439.147712)
		(stroke
			(width 0.2)
			(type default)
		)
		(layer "In3.Cu")
	)
	(gr_arc
		(start 4.56946 -435.94782)
		(mid 5.079873 -436.458614)
		(end 5.59054 -435.948074)
		(stroke
			(width 0.2)
			(type default)
		)
		(layer "In3.Cu")
	)
	(gr_line
		(start 4.56946 -435.135274)
		(end 4.56946 -435.94782)
		(stroke
			(width 0.2)
			(type default)
		)
		(layer "In3.Cu")
	)
	(gr_arc
		(start 4.56946 -430.347882)
		(mid 5.08 -430.858422)
		(end 5.59054 -430.347882)
		(stroke
			(width 0.2)
			(type default)
		)
		(layer "In3.Cu")
	)
	(gr_line
		(start 4.56946 -429.535082)
		(end 4.56946 -430.347882)
		(stroke
			(width 0.2)
			(type default)
		)
		(layer "In3.Cu")
	)
	(gr_arc
		(start 4.56946 -427.14799)
		(mid 5.08 -427.65853)
		(end 5.59054 -427.14799)
		(stroke
			(width 0.2)
			(type default)
		)
		(layer "In3.Cu")
	)
	(gr_line
		(start 4.56946 -426.33519)
		(end 4.56946 -427.14799)
		(stroke
			(width 0.2)
			(type default)
		)
		(layer "In3.Cu")
	)
	(gr_arc
		(start 4.56946 -423.948098)
		(mid 5.08 -424.458638)
		(end 5.59054 -423.948098)
		(stroke
			(width 0.2)
			(type default)
		)
		(layer "In3.Cu")
	)
	(gr_line
		(start 4.56946 -423.135298)
		(end 4.56946 -423.948098)
		(stroke
			(width 0.2)
			(type default)
		)
		(layer "In3.Cu")
	)
	(gr_arc
		(start 4.56946 -417.54806)
		(mid 5.08 -418.0586)
		(end 5.59054 -417.54806)
		(stroke
			(width 0.2)
			(type default)
		)
		(layer "In3.Cu")
	)
	(gr_line
		(start 4.56946 -416.73526)
		(end 4.56946 -417.54806)
		(stroke
			(width 0.2)
			(type default)
		)
		(layer "In3.Cu")
	)
	(gr_arc
		(start 4.56946 -414.34766)
		(mid 5.079873 -414.858454)
		(end 5.59054 -414.347914)
		(stroke
			(width 0.2)
			(type default)
		)
		(layer "In3.Cu")
	)
	(gr_line
		(start 4.56946 -413.535114)
		(end 4.56946 -414.34766)
		(stroke
			(width 0.2)
			(type default)
		)
		(layer "In3.Cu")
	)
	(gr_arc
		(start 4.56946 -411.147768)
		(mid 5.079873 -411.658562)
		(end 5.59054 -411.148022)
		(stroke
			(width 0.2)
			(type default)
		)
		(layer "In3.Cu")
	)
	(gr_line
		(start 4.56946 -410.335222)
		(end 4.56946 -411.147768)
		(stroke
			(width 0.2)
			(type default)
		)
		(layer "In3.Cu")
	)
	(gr_arc
		(start 4.56946 -407.947622)
		(mid 5.079873 -408.458416)
		(end 5.59054 -407.947876)
		(stroke
			(width 0.2)
			(type default)
		)
		(layer "In3.Cu")
	)
	(gr_line
		(start 4.56946 -407.135076)
		(end 4.56946 -407.947622)
		(stroke
			(width 0.2)
			(type default)
		)
		(layer "In3.Cu")
	)
	(gr_arc
		(start 4.56946 -404.74773)
		(mid 5.079873 -405.258524)
		(end 5.59054 -404.747984)
		(stroke
			(width 0.2)
			(type default)
		)
		(layer "In3.Cu")
	)
	(gr_line
		(start 4.56946 -403.935184)
		(end 4.56946 -404.74773)
		(stroke
			(width 0.2)
			(type default)
		)
		(layer "In3.Cu")
	)
	(gr_arc
		(start 4.56946 -399.148046)
		(mid 5.08 -399.658586)
		(end 5.59054 -399.148046)
		(stroke
			(width 0.2)
			(type default)
		)
		(layer "In3.Cu")
	)
	(gr_line
		(start 4.56946 -398.335246)
		(end 4.56946 -399.148046)
		(stroke
			(width 0.2)
			(type default)
		)
		(layer "In3.Cu")
	)
	(gr_arc
		(start 4.56946 -395.9479)
		(mid 5.08 -396.45844)
		(end 5.59054 -395.9479)
		(stroke
			(width 0.2)
			(type default)
		)
		(layer "In3.Cu")
	)
	(gr_line
		(start 4.56946 -395.1351)
		(end 4.56946 -395.9479)
		(stroke
			(width 0.2)
			(type default)
		)
		(layer "In3.Cu")
	)
	(gr_arc
		(start 4.56946 -392.748008)
		(mid 5.08 -393.258548)
		(end 5.59054 -392.748008)
		(stroke
			(width 0.2)
			(type default)
		)
		(layer "In3.Cu")
	)
	(gr_line
		(start 4.56946 -391.935208)
		(end 4.56946 -392.748008)
		(stroke
			(width 0.2)
			(type default)
		)
		(layer "In3.Cu")
	)
	(gr_arc
		(start 4.56946 -389.548116)
		(mid 5.08 -390.058656)
		(end 5.59054 -389.548116)
		(stroke
			(width 0.2)
			(type default)
		)
		(layer "In3.Cu")
	)
	(gr_line
		(start 4.56946 -388.735316)
		(end 4.56946 -389.548116)
		(stroke
			(width 0.2)
			(type default)
		)
		(layer "In3.Cu")
	)
	(gr_arc
		(start 4.56946 -358.74833)
		(mid 5.08 -359.25887)
		(end 5.59054 -358.74833)
		(stroke
			(width 0.2)
			(type default)
		)
		(layer "In3.Cu")
	)
	(gr_line
		(start 4.56946 -357.93553)
		(end 4.56946 -358.74833)
		(stroke
			(width 0.2)
			(type default)
		)
		(layer "In3.Cu")
	)
	(gr_arc
		(start 4.56946 -355.548184)
		(mid 5.08 -356.058724)
		(end 5.59054 -355.548184)
		(stroke
			(width 0.2)
			(type default)
		)
		(layer "In3.Cu")
	)
	(gr_line
		(start 4.56946 -354.735384)
		(end 4.56946 -355.548184)
		(stroke
			(width 0.2)
			(type default)
		)
		(layer "In3.Cu")
	)
	(gr_arc
		(start 4.56946 -352.348292)
		(mid 5.08 -352.858832)
		(end 5.59054 -352.348292)
		(stroke
			(width 0.2)
			(type default)
		)
		(layer "In3.Cu")
	)
	(gr_line
		(start 4.56946 -351.535492)
		(end 4.56946 -352.348292)
		(stroke
			(width 0.2)
			(type default)
		)
		(layer "In3.Cu")
	)
	(gr_arc
		(start 4.56946 -349.148146)
		(mid 5.08 -349.658686)
		(end 5.59054 -349.148146)
		(stroke
			(width 0.2)
			(type default)
		)
		(layer "In3.Cu")
	)
	(gr_line
		(start 4.56946 -348.335346)
		(end 4.56946 -349.148146)
		(stroke
			(width 0.2)
			(type default)
		)
		(layer "In3.Cu")
	)
	(gr_arc
		(start 4.56946 -345.948254)
		(mid 5.08 -346.458794)
		(end 5.59054 -345.948254)
		(stroke
			(width 0.2)
			(type default)
		)
		(layer "In3.Cu")
	)
	(gr_line
		(start 4.56946 -345.135454)
		(end 4.56946 -345.948254)
		(stroke
			(width 0.2)
			(type default)
		)
		(layer "In3.Cu")
	)
	(gr_arc
		(start 4.56946 -342.748108)
		(mid 5.08 -343.258648)
		(end 5.59054 -342.748108)
		(stroke
			(width 0.2)
			(type default)
		)
		(layer "In3.Cu")
	)
	(gr_line
		(start 4.56946 -341.935308)
		(end 4.56946 -342.748108)
		(stroke
			(width 0.2)
			(type default)
		)
		(layer "In3.Cu")
	)
	(gr_arc
		(start 4.56946 -339.548216)
		(mid 5.08 -340.058756)
		(end 5.59054 -339.548216)
		(stroke
			(width 0.2)
			(type default)
		)
		(layer "In3.Cu")
	)
	(gr_line
		(start 4.56946 -338.735416)
		(end 4.56946 -339.548216)
		(stroke
			(width 0.2)
			(type default)
		)
		(layer "In3.Cu")
	)
	(gr_arc
		(start 4.56946 -336.348324)
		(mid 5.08 -336.858864)
		(end 5.59054 -336.348324)
		(stroke
			(width 0.2)
			(type default)
		)
		(layer "In3.Cu")
	)
	(gr_line
		(start 4.56946 -335.535524)
		(end 4.56946 -336.348324)
		(stroke
			(width 0.2)
			(type default)
		)
		(layer "In3.Cu")
	)
	(gr_arc
		(start 4.56946 -330.748132)
		(mid 5.08 -331.258672)
		(end 5.59054 -330.748132)
		(stroke
			(width 0.2)
			(type default)
		)
		(layer "In3.Cu")
	)
	(gr_line
		(start 4.56946 -329.935332)
		(end 4.56946 -330.748132)
		(stroke
			(width 0.2)
			(type default)
		)
		(layer "In3.Cu")
	)
	(gr_arc
		(start 4.56946 -327.54824)
		(mid 5.08 -328.05878)
		(end 5.59054 -327.54824)
		(stroke
			(width 0.2)
			(type default)
		)
		(layer "In3.Cu")
	)
	(gr_line
		(start 4.56946 -326.73544)
		(end 4.56946 -327.54824)
		(stroke
			(width 0.2)
			(type default)
		)
		(layer "In3.Cu")
	)
	(gr_arc
		(start 4.56946 -324.348094)
		(mid 5.08 -324.858634)
		(end 5.59054 -324.348094)
		(stroke
			(width 0.2)
			(type default)
		)
		(layer "In3.Cu")
	)
	(gr_line
		(start 4.56946 -323.535294)
		(end 4.56946 -324.348094)
		(stroke
			(width 0.2)
			(type default)
		)
		(layer "In3.Cu")
	)
	(gr_arc
		(start 4.56946 -321.148202)
		(mid 5.08 -321.658742)
		(end 5.59054 -321.148202)
		(stroke
			(width 0.2)
			(type default)
		)
		(layer "In3.Cu")
	)
	(gr_line
		(start 4.56946 -320.335402)
		(end 4.56946 -321.148202)
		(stroke
			(width 0.2)
			(type default)
		)
		(layer "In3.Cu")
	)
	(gr_arc
		(start 4.56946 -317.94831)
		(mid 5.08 -318.45885)
		(end 5.59054 -317.94831)
		(stroke
			(width 0.2)
			(type default)
		)
		(layer "In3.Cu")
	)
	(gr_line
		(start 4.56946 -317.13551)
		(end 4.56946 -317.94831)
		(stroke
			(width 0.2)
			(type default)
		)
		(layer "In3.Cu")
	)
	(gr_arc
		(start 4.56946 -309.948326)
		(mid 5.08 -310.458866)
		(end 5.59054 -309.948326)
		(stroke
			(width 0.2)
			(type default)
		)
		(layer "In3.Cu")
	)
	(gr_line
		(start 4.56946 -309.135526)
		(end 4.56946 -309.948326)
		(stroke
			(width 0.2)
			(type default)
		)
		(layer "In3.Cu")
	)
	(gr_arc
		(start 4.56946 -306.74818)
		(mid 5.08 -307.25872)
		(end 5.59054 -306.74818)
		(stroke
			(width 0.2)
			(type default)
		)
		(layer "In3.Cu")
	)
	(gr_line
		(start 4.56946 -305.93538)
		(end 4.56946 -306.74818)
		(stroke
			(width 0.2)
			(type default)
		)
		(layer "In3.Cu")
	)
	(gr_arc
		(start 4.56946 -303.548288)
		(mid 5.08 -304.058828)
		(end 5.59054 -303.548288)
		(stroke
			(width 0.2)
			(type default)
		)
		(layer "In3.Cu")
	)
	(gr_line
		(start 4.56946 -302.735488)
		(end 4.56946 -303.548288)
		(stroke
			(width 0.2)
			(type default)
		)
		(layer "In3.Cu")
	)
	(gr_arc
		(start 4.56946 -300.348142)
		(mid 5.08 -300.858682)
		(end 5.59054 -300.348142)
		(stroke
			(width 0.2)
			(type default)
		)
		(layer "In3.Cu")
	)
	(gr_line
		(start 4.56946 -299.535342)
		(end 4.56946 -300.348142)
		(stroke
			(width 0.2)
			(type default)
		)
		(layer "In3.Cu")
	)
	(gr_arc
		(start 4.56946 -297.14825)
		(mid 5.08 -297.65879)
		(end 5.59054 -297.14825)
		(stroke
			(width 0.2)
			(type default)
		)
		(layer "In3.Cu")
	)
	(gr_line
		(start 4.56946 -296.33545)
		(end 4.56946 -297.14825)
		(stroke
			(width 0.2)
			(type default)
		)
		(layer "In3.Cu")
	)
	(gr_arc
		(start 4.56946 -293.948104)
		(mid 5.08 -294.458644)
		(end 5.59054 -293.948104)
		(stroke
			(width 0.2)
			(type default)
		)
		(layer "In3.Cu")
	)
	(gr_line
		(start 4.56946 -293.135304)
		(end 4.56946 -293.948104)
		(stroke
			(width 0.2)
			(type default)
		)
		(layer "In3.Cu")
	)
	(gr_arc
		(start 4.56946 -290.748212)
		(mid 5.08 -291.258752)
		(end 5.59054 -290.748212)
		(stroke
			(width 0.2)
			(type default)
		)
		(layer "In3.Cu")
	)
	(gr_line
		(start 4.56946 -289.935412)
		(end 4.56946 -290.748212)
		(stroke
			(width 0.2)
			(type default)
		)
		(layer "In3.Cu")
	)
	(gr_arc
		(start 4.56946 -284.348174)
		(mid 5.08 -284.858714)
		(end 5.59054 -284.348174)
		(stroke
			(width 0.2)
			(type default)
		)
		(layer "In3.Cu")
	)
	(gr_line
		(start 4.56946 -283.535374)
		(end 4.56946 -284.348174)
		(stroke
			(width 0.2)
			(type default)
		)
		(layer "In3.Cu")
	)
	(gr_arc
		(start 4.56946 -281.148282)
		(mid 5.08 -281.658822)
		(end 5.59054 -281.148282)
		(stroke
			(width 0.2)
			(type default)
		)
		(layer "In3.Cu")
	)
	(gr_line
		(start 4.56946 -280.335482)
		(end 4.56946 -281.148282)
		(stroke
			(width 0.2)
			(type default)
		)
		(layer "In3.Cu")
	)
	(gr_arc
		(start 4.56946 -232.748328)
		(mid 5.08 -233.258868)
		(end 5.59054 -232.748328)
		(stroke
			(width 0.2)
			(type default)
		)
		(layer "In3.Cu")
	)
	(gr_line
		(start 4.56946 -231.935528)
		(end 4.56946 -232.748328)
		(stroke
			(width 0.2)
			(type default)
		)
		(layer "In3.Cu")
	)
	(gr_arc
		(start 4.56946 -229.548182)
		(mid 5.08 -230.058722)
		(end 5.59054 -229.548182)
		(stroke
			(width 0.2)
			(type default)
		)
		(layer "In3.Cu")
	)
	(gr_line
		(start 4.56946 -228.735382)
		(end 4.56946 -229.548182)
		(stroke
			(width 0.2)
			(type default)
		)
		(layer "In3.Cu")
	)
	(gr_arc
		(start 4.56946 -223.148144)
		(mid 5.08 -223.658684)
		(end 5.59054 -223.148144)
		(stroke
			(width 0.2)
			(type default)
		)
		(layer "In3.Cu")
	)
	(gr_line
		(start 4.56946 -222.335344)
		(end 4.56946 -223.148144)
		(stroke
			(width 0.2)
			(type default)
		)
		(layer "In3.Cu")
	)
	(gr_arc
		(start 4.56946 -219.948252)
		(mid 5.08 -220.458792)
		(end 5.59054 -219.948252)
		(stroke
			(width 0.2)
			(type default)
		)
		(layer "In3.Cu")
	)
	(gr_line
		(start 4.56946 -219.135452)
		(end 4.56946 -219.948252)
		(stroke
			(width 0.2)
			(type default)
		)
		(layer "In3.Cu")
	)
	(gr_arc
		(start 4.56946 -216.748106)
		(mid 5.08 -217.258646)
		(end 5.59054 -216.748106)
		(stroke
			(width 0.2)
			(type default)
		)
		(layer "In3.Cu")
	)
	(gr_line
		(start 4.56946 -215.935306)
		(end 4.56946 -216.748106)
		(stroke
			(width 0.2)
			(type default)
		)
		(layer "In3.Cu")
	)
	(gr_arc
		(start 4.56946 -213.548214)
		(mid 5.08 -214.058754)
		(end 5.59054 -213.548214)
		(stroke
			(width 0.2)
			(type default)
		)
		(layer "In3.Cu")
	)
	(gr_line
		(start 4.56946 -212.735414)
		(end 4.56946 -213.548214)
		(stroke
			(width 0.2)
			(type default)
		)
		(layer "In3.Cu")
	)
	(gr_arc
		(start 4.56946 -210.348322)
		(mid 5.08 -210.858862)
		(end 5.59054 -210.348322)
		(stroke
			(width 0.2)
			(type default)
		)
		(layer "In3.Cu")
	)
	(gr_line
		(start 4.56946 -209.535522)
		(end 4.56946 -210.348322)
		(stroke
			(width 0.2)
			(type default)
		)
		(layer "In3.Cu")
	)
	(gr_arc
		(start 4.56946 -207.148176)
		(mid 5.08 -207.658716)
		(end 5.59054 -207.148176)
		(stroke
			(width 0.2)
			(type default)
		)
		(layer "In3.Cu")
	)
	(gr_line
		(start 4.56946 -206.335376)
		(end 4.56946 -207.148176)
		(stroke
			(width 0.2)
			(type default)
		)
		(layer "In3.Cu")
	)
	(gr_arc
		(start 4.56946 -203.948284)
		(mid 5.08 -204.458824)
		(end 5.59054 -203.948284)
		(stroke
			(width 0.2)
			(type default)
		)
		(layer "In3.Cu")
	)
	(gr_line
		(start 4.56946 -203.135484)
		(end 4.56946 -203.948284)
		(stroke
			(width 0.2)
			(type default)
		)
		(layer "In3.Cu")
	)
	(gr_arc
		(start 4.56946 -200.748138)
		(mid 5.08 -201.258678)
		(end 5.59054 -200.748138)
		(stroke
			(width 0.2)
			(type default)
		)
		(layer "In3.Cu")
	)
	(gr_line
		(start 4.56946 -199.935338)
		(end 4.56946 -200.748138)
		(stroke
			(width 0.2)
			(type default)
		)
		(layer "In3.Cu")
	)
	(gr_arc
		(start 4.56946 -195.1482)
		(mid 5.08 -195.65874)
		(end 5.59054 -195.1482)
		(stroke
			(width 0.2)
			(type default)
		)
		(layer "In3.Cu")
	)
	(gr_line
		(start 4.56946 -194.3354)
		(end 4.56946 -195.1482)
		(stroke
			(width 0.2)
			(type default)
		)
		(layer "In3.Cu")
	)
	(gr_arc
		(start 4.56946 -191.948308)
		(mid 5.08 -192.458848)
		(end 5.59054 -191.948308)
		(stroke
			(width 0.2)
			(type default)
		)
		(layer "In3.Cu")
	)
	(gr_line
		(start 4.56946 -191.135508)
		(end 4.56946 -191.948308)
		(stroke
			(width 0.2)
			(type default)
		)
		(layer "In3.Cu")
	)
	(gr_arc
		(start 4.56946 -183.948324)
		(mid 5.08 -184.458864)
		(end 5.59054 -183.948324)
		(stroke
			(width 0.2)
			(type default)
		)
		(layer "In3.Cu")
	)
	(gr_line
		(start 4.56946 -183.135524)
		(end 4.56946 -183.948324)
		(stroke
			(width 0.2)
			(type default)
		)
		(layer "In3.Cu")
	)
	(gr_arc
		(start 4.56946 -180.748178)
		(mid 5.08 -181.258718)
		(end 5.59054 -180.748178)
		(stroke
			(width 0.2)
			(type default)
		)
		(layer "In3.Cu")
	)
	(gr_line
		(start 4.56946 -179.935378)
		(end 4.56946 -180.748178)
		(stroke
			(width 0.2)
			(type default)
		)
		(layer "In3.Cu")
	)
	(gr_arc
		(start 4.56946 -177.548286)
		(mid 5.08 -178.058826)
		(end 5.59054 -177.548286)
		(stroke
			(width 0.2)
			(type default)
		)
		(layer "In3.Cu")
	)
	(gr_line
		(start 4.56946 -176.735486)
		(end 4.56946 -177.548286)
		(stroke
			(width 0.2)
			(type default)
		)
		(layer "In3.Cu")
	)
	(gr_arc
		(start 4.56946 -174.34814)
		(mid 5.08 -174.85868)
		(end 5.59054 -174.34814)
		(stroke
			(width 0.2)
			(type default)
		)
		(layer "In3.Cu")
	)
	(gr_line
		(start 4.56946 -173.53534)
		(end 4.56946 -174.34814)
		(stroke
			(width 0.2)
			(type default)
		)
		(layer "In3.Cu")
	)
	(gr_arc
		(start 4.56946 -171.148248)
		(mid 5.08 -171.658788)
		(end 5.59054 -171.148248)
		(stroke
			(width 0.2)
			(type default)
		)
		(layer "In3.Cu")
	)
	(gr_line
		(start 4.56946 -170.335448)
		(end 4.56946 -171.148248)
		(stroke
			(width 0.2)
			(type default)
		)
		(layer "In3.Cu")
	)
	(gr_arc
		(start 4.56946 -167.948102)
		(mid 5.08 -168.458642)
		(end 5.59054 -167.948102)
		(stroke
			(width 0.2)
			(type default)
		)
		(layer "In3.Cu")
	)
	(gr_line
		(start 4.56946 -167.135302)
		(end 4.56946 -167.948102)
		(stroke
			(width 0.2)
			(type default)
		)
		(layer "In3.Cu")
	)
	(gr_arc
		(start 4.56946 -164.74821)
		(mid 5.08 -165.25875)
		(end 5.59054 -164.74821)
		(stroke
			(width 0.2)
			(type default)
		)
		(layer "In3.Cu")
	)
	(gr_line
		(start 4.56946 -163.93541)
		(end 4.56946 -164.74821)
		(stroke
			(width 0.2)
			(type default)
		)
		(layer "In3.Cu")
	)
	(gr_arc
		(start 4.56946 -161.548318)
		(mid 5.08 -162.058858)
		(end 5.59054 -161.548318)
		(stroke
			(width 0.2)
			(type default)
		)
		(layer "In3.Cu")
	)
	(gr_line
		(start 4.56946 -160.735518)
		(end 4.56946 -161.548318)
		(stroke
			(width 0.2)
			(type default)
		)
		(layer "In3.Cu")
	)
	(gr_arc
		(start 4.56946 -158.348172)
		(mid 5.08 -158.858712)
		(end 5.59054 -158.348172)
		(stroke
			(width 0.2)
			(type default)
		)
		(layer "In3.Cu")
	)
	(gr_line
		(start 4.56946 -157.535372)
		(end 4.56946 -158.348172)
		(stroke
			(width 0.2)
			(type default)
		)
		(layer "In3.Cu")
	)
	(gr_arc
		(start 4.56946 -155.14828)
		(mid 5.08 -155.65882)
		(end 5.59054 -155.14828)
		(stroke
			(width 0.2)
			(type default)
		)
		(layer "In3.Cu")
	)
	(gr_line
		(start 4.56946 -154.33548)
		(end 4.56946 -155.14828)
		(stroke
			(width 0.2)
			(type default)
		)
		(layer "In3.Cu")
	)
	(gr_line
		(start 5.59054 -445.548004)
		(end 5.59054 -444.735204)
		(stroke
			(width 0.2)
			(type default)
		)
		(layer "In3.Cu")
	)
	(gr_arc
		(start 5.59054 -444.735204)
		(mid 5.08 -444.224664)
		(end 4.56946 -444.735204)
		(stroke
			(width 0.2)
			(type default)
		)
		(layer "In3.Cu")
	)
	(gr_line
		(start 5.59054 -442.348112)
		(end 5.59054 -441.535312)
		(stroke
			(width 0.2)
			(type default)
		)
		(layer "In3.Cu")
	)
	(gr_arc
		(start 5.59054 -441.535312)
		(mid 5.08 -441.024772)
		(end 4.56946 -441.535312)
		(stroke
			(width 0.2)
			(type default)
		)
		(layer "In3.Cu")
	)
	(gr_line
		(start 5.59054 -439.147966)
		(end 5.59054 -438.335166)
		(stroke
			(width 0.2)
			(type default)
		)
		(layer "In3.Cu")
	)
	(gr_arc
		(start 5.59054 -438.335166)
		(mid 5.08 -437.824626)
		(end 4.56946 -438.335166)
		(stroke
			(width 0.2)
			(type default)
		)
		(layer "In3.Cu")
	)
	(gr_line
		(start 5.59054 -435.948074)
		(end 5.59054 -435.135274)
		(stroke
			(width 0.2)
			(type default)
		)
		(layer "In3.Cu")
	)
	(gr_arc
		(start 5.59054 -435.135274)
		(mid 5.08 -434.624734)
		(end 4.56946 -435.135274)
		(stroke
			(width 0.2)
			(type default)
		)
		(layer "In3.Cu")
	)
	(gr_line
		(start 5.59054 -430.347882)
		(end 5.59054 -429.535336)
		(stroke
			(width 0.2)
			(type default)
		)
		(layer "In3.Cu")
	)
	(gr_arc
		(start 5.59054 -429.535336)
		(mid 5.080127 -429.024542)
		(end 4.56946 -429.535082)
		(stroke
			(width 0.2)
			(type default)
		)
		(layer "In3.Cu")
	)
	(gr_line
		(start 5.59054 -427.14799)
		(end 5.59054 -426.335444)
		(stroke
			(width 0.2)
			(type default)
		)
		(layer "In3.Cu")
	)
	(gr_arc
		(start 5.59054 -426.335444)
		(mid 5.080127 -425.82465)
		(end 4.56946 -426.33519)
		(stroke
			(width 0.2)
			(type default)
		)
		(layer "In3.Cu")
	)
	(gr_line
		(start 5.59054 -423.948098)
		(end 5.59054 -423.135552)
		(stroke
			(width 0.2)
			(type default)
		)
		(layer "In3.Cu")
	)
	(gr_arc
		(start 5.59054 -423.135552)
		(mid 5.080127 -422.624758)
		(end 4.56946 -423.135298)
		(stroke
			(width 0.2)
			(type default)
		)
		(layer "In3.Cu")
	)
	(gr_line
		(start 5.59054 -417.54806)
		(end 5.59054 -416.735514)
		(stroke
			(width 0.2)
			(type default)
		)
		(layer "In3.Cu")
	)
	(gr_arc
		(start 5.59054 -416.735514)
		(mid 5.080127 -416.22472)
		(end 4.56946 -416.73526)
		(stroke
			(width 0.2)
			(type default)
		)
		(layer "In3.Cu")
	)
	(gr_line
		(start 5.59054 -414.347914)
		(end 5.59054 -413.535114)
		(stroke
			(width 0.2)
			(type default)
		)
		(layer "In3.Cu")
	)
	(gr_arc
		(start 5.59054 -413.535114)
		(mid 5.08 -413.024574)
		(end 4.56946 -413.535114)
		(stroke
			(width 0.2)
			(type default)
		)
		(layer "In3.Cu")
	)
	(gr_line
		(start 5.59054 -411.148022)
		(end 5.59054 -410.335222)
		(stroke
			(width 0.2)
			(type default)
		)
		(layer "In3.Cu")
	)
	(gr_arc
		(start 5.59054 -410.335222)
		(mid 5.08 -409.824682)
		(end 4.56946 -410.335222)
		(stroke
			(width 0.2)
			(type default)
		)
		(layer "In3.Cu")
	)
	(gr_line
		(start 5.59054 -407.947876)
		(end 5.59054 -407.135076)
		(stroke
			(width 0.2)
			(type default)
		)
		(layer "In3.Cu")
	)
	(gr_arc
		(start 5.59054 -407.135076)
		(mid 5.08 -406.624536)
		(end 4.56946 -407.135076)
		(stroke
			(width 0.2)
			(type default)
		)
		(layer "In3.Cu")
	)
	(gr_line
		(start 5.59054 -404.747984)
		(end 5.59054 -403.935184)
		(stroke
			(width 0.2)
			(type default)
		)
		(layer "In3.Cu")
	)
	(gr_arc
		(start 5.59054 -403.935184)
		(mid 5.08 -403.424644)
		(end 4.56946 -403.935184)
		(stroke
			(width 0.2)
			(type default)
		)
		(layer "In3.Cu")
	)
	(gr_line
		(start 5.59054 -399.148046)
		(end 5.59054 -398.3355)
		(stroke
			(width 0.2)
			(type default)
		)
		(layer "In3.Cu")
	)
	(gr_arc
		(start 5.59054 -398.3355)
		(mid 5.080127 -397.824706)
		(end 4.56946 -398.335246)
		(stroke
			(width 0.2)
			(type default)
		)
		(layer "In3.Cu")
	)
	(gr_line
		(start 5.59054 -395.9479)
		(end 5.59054 -395.135354)
		(stroke
			(width 0.2)
			(type default)
		)
		(layer "In3.Cu")
	)
	(gr_arc
		(start 5.59054 -395.135354)
		(mid 5.080127 -394.62456)
		(end 4.56946 -395.1351)
		(stroke
			(width 0.2)
			(type default)
		)
		(layer "In3.Cu")
	)
	(gr_line
		(start 5.59054 -392.748008)
		(end 5.59054 -391.935462)
		(stroke
			(width 0.2)
			(type default)
		)
		(layer "In3.Cu")
	)
	(gr_arc
		(start 5.59054 -391.935462)
		(mid 5.080127 -391.424668)
		(end 4.56946 -391.935208)
		(stroke
			(width 0.2)
			(type default)
		)
		(layer "In3.Cu")
	)
	(gr_line
		(start 5.59054 -389.548116)
		(end 5.59054 -388.73557)
		(stroke
			(width 0.2)
			(type default)
		)
		(layer "In3.Cu")
	)
	(gr_arc
		(start 5.59054 -388.73557)
		(mid 5.080127 -388.224776)
		(end 4.56946 -388.735316)
		(stroke
			(width 0.2)
			(type default)
		)
		(layer "In3.Cu")
	)
	(gr_line
		(start 5.59054 -358.74833)
		(end 5.59054 -357.935784)
		(stroke
			(width 0.2)
			(type default)
		)
		(layer "In3.Cu")
	)
	(gr_arc
		(start 5.59054 -357.935784)
		(mid 5.080127 -357.42499)
		(end 4.56946 -357.93553)
		(stroke
			(width 0.2)
			(type default)
		)
		(layer "In3.Cu")
	)
	(gr_line
		(start 5.59054 -355.548184)
		(end 5.59054 -354.735638)
		(stroke
			(width 0.2)
			(type default)
		)
		(layer "In3.Cu")
	)
	(gr_arc
		(start 5.59054 -354.735638)
		(mid 5.080127 -354.224844)
		(end 4.56946 -354.735384)
		(stroke
			(width 0.2)
			(type default)
		)
		(layer "In3.Cu")
	)
	(gr_line
		(start 5.59054 -352.348292)
		(end 5.59054 -351.535746)
		(stroke
			(width 0.2)
			(type default)
		)
		(layer "In3.Cu")
	)
	(gr_arc
		(start 5.59054 -351.535746)
		(mid 5.080127 -351.024952)
		(end 4.56946 -351.535492)
		(stroke
			(width 0.2)
			(type default)
		)
		(layer "In3.Cu")
	)
	(gr_line
		(start 5.59054 -349.148146)
		(end 5.59054 -348.3356)
		(stroke
			(width 0.2)
			(type default)
		)
		(layer "In3.Cu")
	)
	(gr_arc
		(start 5.59054 -348.3356)
		(mid 5.080127 -347.824806)
		(end 4.56946 -348.335346)
		(stroke
			(width 0.2)
			(type default)
		)
		(layer "In3.Cu")
	)
	(gr_line
		(start 5.59054 -345.948254)
		(end 5.59054 -345.135708)
		(stroke
			(width 0.2)
			(type default)
		)
		(layer "In3.Cu")
	)
	(gr_arc
		(start 5.59054 -345.135708)
		(mid 5.080127 -344.624914)
		(end 4.56946 -345.135454)
		(stroke
			(width 0.2)
			(type default)
		)
		(layer "In3.Cu")
	)
	(gr_line
		(start 5.59054 -342.748108)
		(end 5.59054 -341.935562)
		(stroke
			(width 0.2)
			(type default)
		)
		(layer "In3.Cu")
	)
	(gr_arc
		(start 5.59054 -341.935562)
		(mid 5.080127 -341.424768)
		(end 4.56946 -341.935308)
		(stroke
			(width 0.2)
			(type default)
		)
		(layer "In3.Cu")
	)
	(gr_line
		(start 5.59054 -339.548216)
		(end 5.59054 -338.73567)
		(stroke
			(width 0.2)
			(type default)
		)
		(layer "In3.Cu")
	)
	(gr_arc
		(start 5.59054 -338.73567)
		(mid 5.080127 -338.224876)
		(end 4.56946 -338.735416)
		(stroke
			(width 0.2)
			(type default)
		)
		(layer "In3.Cu")
	)
	(gr_line
		(start 5.59054 -336.348324)
		(end 5.59054 -335.535778)
		(stroke
			(width 0.2)
			(type default)
		)
		(layer "In3.Cu")
	)
	(gr_arc
		(start 5.59054 -335.535778)
		(mid 5.080127 -335.024984)
		(end 4.56946 -335.535524)
		(stroke
			(width 0.2)
			(type default)
		)
		(layer "In3.Cu")
	)
	(gr_line
		(start 5.59054 -330.748132)
		(end 5.59054 -329.935586)
		(stroke
			(width 0.2)
			(type default)
		)
		(layer "In3.Cu")
	)
	(gr_arc
		(start 5.59054 -329.935586)
		(mid 5.080127 -329.424792)
		(end 4.56946 -329.935332)
		(stroke
			(width 0.2)
			(type default)
		)
		(layer "In3.Cu")
	)
	(gr_line
		(start 5.59054 -327.54824)
		(end 5.59054 -326.735694)
		(stroke
			(width 0.2)
			(type default)
		)
		(layer "In3.Cu")
	)
	(gr_arc
		(start 5.59054 -326.735694)
		(mid 5.080127 -326.2249)
		(end 4.56946 -326.73544)
		(stroke
			(width 0.2)
			(type default)
		)
		(layer "In3.Cu")
	)
	(gr_line
		(start 5.59054 -324.348094)
		(end 5.59054 -323.535548)
		(stroke
			(width 0.2)
			(type default)
		)
		(layer "In3.Cu")
	)
	(gr_arc
		(start 5.59054 -323.535548)
		(mid 5.080127 -323.024754)
		(end 4.56946 -323.535294)
		(stroke
			(width 0.2)
			(type default)
		)
		(layer "In3.Cu")
	)
	(gr_line
		(start 5.59054 -321.148202)
		(end 5.59054 -320.335656)
		(stroke
			(width 0.2)
			(type default)
		)
		(layer "In3.Cu")
	)
	(gr_arc
		(start 5.59054 -320.335656)
		(mid 5.080127 -319.824862)
		(end 4.56946 -320.335402)
		(stroke
			(width 0.2)
			(type default)
		)
		(layer "In3.Cu")
	)
	(gr_line
		(start 5.59054 -317.94831)
		(end 5.59054 -317.135764)
		(stroke
			(width 0.2)
			(type default)
		)
		(layer "In3.Cu")
	)
	(gr_arc
		(start 5.59054 -317.135764)
		(mid 5.080127 -316.62497)
		(end 4.56946 -317.13551)
		(stroke
			(width 0.2)
			(type default)
		)
		(layer "In3.Cu")
	)
	(gr_line
		(start 5.59054 -309.948326)
		(end 5.59054 -309.13578)
		(stroke
			(width 0.2)
			(type default)
		)
		(layer "In3.Cu")
	)
	(gr_arc
		(start 5.59054 -309.13578)
		(mid 5.080127 -308.624986)
		(end 4.56946 -309.135526)
		(stroke
			(width 0.2)
			(type default)
		)
		(layer "In3.Cu")
	)
	(gr_line
		(start 5.59054 -306.74818)
		(end 5.59054 -305.935634)
		(stroke
			(width 0.2)
			(type default)
		)
		(layer "In3.Cu")
	)
	(gr_arc
		(start 5.59054 -305.935634)
		(mid 5.080127 -305.42484)
		(end 4.56946 -305.93538)
		(stroke
			(width 0.2)
			(type default)
		)
		(layer "In3.Cu")
	)
	(gr_line
		(start 5.59054 -303.548288)
		(end 5.59054 -302.735742)
		(stroke
			(width 0.2)
			(type default)
		)
		(layer "In3.Cu")
	)
	(gr_arc
		(start 5.59054 -302.735742)
		(mid 5.080127 -302.224948)
		(end 4.56946 -302.735488)
		(stroke
			(width 0.2)
			(type default)
		)
		(layer "In3.Cu")
	)
	(gr_line
		(start 5.59054 -300.348142)
		(end 5.59054 -299.535596)
		(stroke
			(width 0.2)
			(type default)
		)
		(layer "In3.Cu")
	)
	(gr_arc
		(start 5.59054 -299.535596)
		(mid 5.080127 -299.024802)
		(end 4.56946 -299.535342)
		(stroke
			(width 0.2)
			(type default)
		)
		(layer "In3.Cu")
	)
	(gr_line
		(start 5.59054 -297.14825)
		(end 5.59054 -296.335704)
		(stroke
			(width 0.2)
			(type default)
		)
		(layer "In3.Cu")
	)
	(gr_arc
		(start 5.59054 -296.335704)
		(mid 5.080127 -295.82491)
		(end 4.56946 -296.33545)
		(stroke
			(width 0.2)
			(type default)
		)
		(layer "In3.Cu")
	)
	(gr_line
		(start 5.59054 -293.948104)
		(end 5.59054 -293.135558)
		(stroke
			(width 0.2)
			(type default)
		)
		(layer "In3.Cu")
	)
	(gr_arc
		(start 5.59054 -293.135558)
		(mid 5.080127 -292.624764)
		(end 4.56946 -293.135304)
		(stroke
			(width 0.2)
			(type default)
		)
		(layer "In3.Cu")
	)
	(gr_line
		(start 5.59054 -290.748212)
		(end 5.59054 -289.935666)
		(stroke
			(width 0.2)
			(type default)
		)
		(layer "In3.Cu")
	)
	(gr_arc
		(start 5.59054 -289.935666)
		(mid 5.080127 -289.424872)
		(end 4.56946 -289.935412)
		(stroke
			(width 0.2)
			(type default)
		)
		(layer "In3.Cu")
	)
	(gr_line
		(start 5.59054 -284.348174)
		(end 5.59054 -283.535628)
		(stroke
			(width 0.2)
			(type default)
		)
		(layer "In3.Cu")
	)
	(gr_arc
		(start 5.59054 -283.535628)
		(mid 5.080127 -283.024834)
		(end 4.56946 -283.535374)
		(stroke
			(width 0.2)
			(type default)
		)
		(layer "In3.Cu")
	)
	(gr_line
		(start 5.59054 -281.148282)
		(end 5.59054 -280.335736)
		(stroke
			(width 0.2)
			(type default)
		)
		(layer "In3.Cu")
	)
	(gr_arc
		(start 5.59054 -280.335736)
		(mid 5.080127 -279.824942)
		(end 4.56946 -280.335482)
		(stroke
			(width 0.2)
			(type default)
		)
		(layer "In3.Cu")
	)
	(gr_line
		(start 5.59054 -232.748328)
		(end 5.59054 -231.935782)
		(stroke
			(width 0.2)
			(type default)
		)
		(layer "In3.Cu")
	)
	(gr_arc
		(start 5.59054 -231.935782)
		(mid 5.080127 -231.424988)
		(end 4.56946 -231.935528)
		(stroke
			(width 0.2)
			(type default)
		)
		(layer "In3.Cu")
	)
	(gr_line
		(start 5.59054 -229.548182)
		(end 5.59054 -228.735636)
		(stroke
			(width 0.2)
			(type default)
		)
		(layer "In3.Cu")
	)
	(gr_arc
		(start 5.59054 -228.735636)
		(mid 5.080127 -228.224842)
		(end 4.56946 -228.735382)
		(stroke
			(width 0.2)
			(type default)
		)
		(layer "In3.Cu")
	)
	(gr_line
		(start 5.59054 -223.148144)
		(end 5.59054 -222.335598)
		(stroke
			(width 0.2)
			(type default)
		)
		(layer "In3.Cu")
	)
	(gr_arc
		(start 5.59054 -222.335598)
		(mid 5.080127 -221.824804)
		(end 4.56946 -222.335344)
		(stroke
			(width 0.2)
			(type default)
		)
		(layer "In3.Cu")
	)
	(gr_line
		(start 5.59054 -219.948252)
		(end 5.59054 -219.135706)
		(stroke
			(width 0.2)
			(type default)
		)
		(layer "In3.Cu")
	)
	(gr_arc
		(start 5.59054 -219.135706)
		(mid 5.080127 -218.624912)
		(end 4.56946 -219.135452)
		(stroke
			(width 0.2)
			(type default)
		)
		(layer "In3.Cu")
	)
	(gr_line
		(start 5.59054 -216.748106)
		(end 5.59054 -215.93556)
		(stroke
			(width 0.2)
			(type default)
		)
		(layer "In3.Cu")
	)
	(gr_arc
		(start 5.59054 -215.93556)
		(mid 5.080127 -215.424766)
		(end 4.56946 -215.935306)
		(stroke
			(width 0.2)
			(type default)
		)
		(layer "In3.Cu")
	)
	(gr_line
		(start 5.59054 -213.548214)
		(end 5.59054 -212.735668)
		(stroke
			(width 0.2)
			(type default)
		)
		(layer "In3.Cu")
	)
	(gr_arc
		(start 5.59054 -212.735668)
		(mid 5.080127 -212.224874)
		(end 4.56946 -212.735414)
		(stroke
			(width 0.2)
			(type default)
		)
		(layer "In3.Cu")
	)
	(gr_line
		(start 5.59054 -210.348322)
		(end 5.59054 -209.535776)
		(stroke
			(width 0.2)
			(type default)
		)
		(layer "In3.Cu")
	)
	(gr_arc
		(start 5.59054 -209.535776)
		(mid 5.080127 -209.024982)
		(end 4.56946 -209.535522)
		(stroke
			(width 0.2)
			(type default)
		)
		(layer "In3.Cu")
	)
	(gr_line
		(start 5.59054 -207.148176)
		(end 5.59054 -206.33563)
		(stroke
			(width 0.2)
			(type default)
		)
		(layer "In3.Cu")
	)
	(gr_arc
		(start 5.59054 -206.33563)
		(mid 5.080127 -205.824836)
		(end 4.56946 -206.335376)
		(stroke
			(width 0.2)
			(type default)
		)
		(layer "In3.Cu")
	)
	(gr_line
		(start 5.59054 -203.948284)
		(end 5.59054 -203.135738)
		(stroke
			(width 0.2)
			(type default)
		)
		(layer "In3.Cu")
	)
	(gr_arc
		(start 5.59054 -203.135738)
		(mid 5.080127 -202.624944)
		(end 4.56946 -203.135484)
		(stroke
			(width 0.2)
			(type default)
		)
		(layer "In3.Cu")
	)
	(gr_line
		(start 5.59054 -200.748138)
		(end 5.59054 -199.935592)
		(stroke
			(width 0.2)
			(type default)
		)
		(layer "In3.Cu")
	)
	(gr_arc
		(start 5.59054 -199.935592)
		(mid 5.080127 -199.424798)
		(end 4.56946 -199.935338)
		(stroke
			(width 0.2)
			(type default)
		)
		(layer "In3.Cu")
	)
	(gr_line
		(start 5.59054 -195.1482)
		(end 5.59054 -194.335654)
		(stroke
			(width 0.2)
			(type default)
		)
		(layer "In3.Cu")
	)
	(gr_arc
		(start 5.59054 -194.335654)
		(mid 5.080127 -193.82486)
		(end 4.56946 -194.3354)
		(stroke
			(width 0.2)
			(type default)
		)
		(layer "In3.Cu")
	)
	(gr_line
		(start 5.59054 -191.948308)
		(end 5.59054 -191.135762)
		(stroke
			(width 0.2)
			(type default)
		)
		(layer "In3.Cu")
	)
	(gr_arc
		(start 5.59054 -191.135762)
		(mid 5.080127 -190.624968)
		(end 4.56946 -191.135508)
		(stroke
			(width 0.2)
			(type default)
		)
		(layer "In3.Cu")
	)
	(gr_line
		(start 5.59054 -183.948324)
		(end 5.59054 -183.135778)
		(stroke
			(width 0.2)
			(type default)
		)
		(layer "In3.Cu")
	)
	(gr_arc
		(start 5.59054 -183.135778)
		(mid 5.080127 -182.624984)
		(end 4.56946 -183.135524)
		(stroke
			(width 0.2)
			(type default)
		)
		(layer "In3.Cu")
	)
	(gr_line
		(start 5.59054 -180.748178)
		(end 5.59054 -179.935632)
		(stroke
			(width 0.2)
			(type default)
		)
		(layer "In3.Cu")
	)
	(gr_arc
		(start 5.59054 -179.935632)
		(mid 5.080127 -179.424838)
		(end 4.56946 -179.935378)
		(stroke
			(width 0.2)
			(type default)
		)
		(layer "In3.Cu")
	)
	(gr_line
		(start 5.59054 -177.548286)
		(end 5.59054 -176.73574)
		(stroke
			(width 0.2)
			(type default)
		)
		(layer "In3.Cu")
	)
	(gr_arc
		(start 5.59054 -176.73574)
		(mid 5.080127 -176.224946)
		(end 4.56946 -176.735486)
		(stroke
			(width 0.2)
			(type default)
		)
		(layer "In3.Cu")
	)
	(gr_line
		(start 5.59054 -174.34814)
		(end 5.59054 -173.535594)
		(stroke
			(width 0.2)
			(type default)
		)
		(layer "In3.Cu")
	)
	(gr_arc
		(start 5.59054 -173.535594)
		(mid 5.080127 -173.0248)
		(end 4.56946 -173.53534)
		(stroke
			(width 0.2)
			(type default)
		)
		(layer "In3.Cu")
	)
	(gr_line
		(start 5.59054 -171.148248)
		(end 5.59054 -170.335702)
		(stroke
			(width 0.2)
			(type default)
		)
		(layer "In3.Cu")
	)
	(gr_arc
		(start 5.59054 -170.335702)
		(mid 5.080127 -169.824908)
		(end 4.56946 -170.335448)
		(stroke
			(width 0.2)
			(type default)
		)
		(layer "In3.Cu")
	)
	(gr_line
		(start 5.59054 -167.948102)
		(end 5.59054 -167.135556)
		(stroke
			(width 0.2)
			(type default)
		)
		(layer "In3.Cu")
	)
	(gr_arc
		(start 5.59054 -167.135556)
		(mid 5.080127 -166.624762)
		(end 4.56946 -167.135302)
		(stroke
			(width 0.2)
			(type default)
		)
		(layer "In3.Cu")
	)
	(gr_line
		(start 5.59054 -164.74821)
		(end 5.59054 -163.935664)
		(stroke
			(width 0.2)
			(type default)
		)
		(layer "In3.Cu")
	)
	(gr_arc
		(start 5.59054 -163.935664)
		(mid 5.080127 -163.42487)
		(end 4.56946 -163.93541)
		(stroke
			(width 0.2)
			(type default)
		)
		(layer "In3.Cu")
	)
	(gr_line
		(start 5.59054 -161.548318)
		(end 5.59054 -160.735772)
		(stroke
			(width 0.2)
			(type default)
		)
		(layer "In3.Cu")
	)
	(gr_arc
		(start 5.59054 -160.735772)
		(mid 5.080127 -160.224978)
		(end 4.56946 -160.735518)
		(stroke
			(width 0.2)
			(type default)
		)
		(layer "In3.Cu")
	)
	(gr_line
		(start 5.59054 -158.348172)
		(end 5.59054 -157.535626)
		(stroke
			(width 0.2)
			(type default)
		)
		(layer "In3.Cu")
	)
	(gr_arc
		(start 5.59054 -157.535626)
		(mid 5.080127 -157.024832)
		(end 4.56946 -157.535372)
		(stroke
			(width 0.2)
			(type default)
		)
		(layer "In3.Cu")
	)
	(gr_line
		(start 5.59054 -155.14828)
		(end 5.59054 -154.335734)
		(stroke
			(width 0.2)
			(type default)
		)
		(layer "In3.Cu")
	)
	(gr_arc
		(start 5.59054 -154.335734)
		(mid 5.080127 -153.82494)
		(end 4.56946 -154.33548)
		(stroke
			(width 0.2)
			(type default)
		)
		(layer "In3.Cu")
	)
	(gr_line
		(start 6.477 -449.978272)
		(end 7.2898 -449.978272)
		(stroke
			(width 0.2)
			(type default)
		)
		(layer "In3.Cu")
	)
	(gr_arc
		(start 6.477254 -448.957192)
		(mid 5.96646 -449.467605)
		(end 6.477 -449.978272)
		(stroke
			(width 0.2)
			(type default)
		)
		(layer "In3.Cu")
	)
	(gr_arc
		(start 6.481826 -447.196718)
		(mid 6.992239 -447.707512)
		(end 7.502906 -447.196972)
		(stroke
			(width 0.2)
			(type default)
		)
		(layer "In3.Cu")
	)
	(gr_line
		(start 6.481826 -446.384172)
		(end 6.481826 -447.196718)
		(stroke
			(width 0.2)
			(type default)
		)
		(layer "In3.Cu")
	)
	(gr_arc
		(start 6.481826 -443.996826)
		(mid 6.992239 -444.50762)
		(end 7.502906 -443.99708)
		(stroke
			(width 0.2)
			(type default)
		)
		(layer "In3.Cu")
	)
	(gr_line
		(start 6.481826 -443.18428)
		(end 6.481826 -443.996826)
		(stroke
			(width 0.2)
			(type default)
		)
		(layer "In3.Cu")
	)
	(gr_arc
		(start 6.481826 -440.79668)
		(mid 6.992239 -441.307474)
		(end 7.502906 -440.796934)
		(stroke
			(width 0.2)
			(type default)
		)
		(layer "In3.Cu")
	)
	(gr_line
		(start 6.481826 -439.984134)
		(end 6.481826 -440.79668)
		(stroke
			(width 0.2)
			(type default)
		)
		(layer "In3.Cu")
	)
	(gr_arc
		(start 6.481826 -437.596788)
		(mid 6.992239 -438.107582)
		(end 7.502906 -437.597042)
		(stroke
			(width 0.2)
			(type default)
		)
		(layer "In3.Cu")
	)
	(gr_line
		(start 6.481826 -436.784242)
		(end 6.481826 -437.596788)
		(stroke
			(width 0.2)
			(type default)
		)
		(layer "In3.Cu")
	)
	(gr_arc
		(start 6.481826 -431.997104)
		(mid 6.992366 -432.507644)
		(end 7.502906 -431.997104)
		(stroke
			(width 0.2)
			(type default)
		)
		(layer "In3.Cu")
	)
	(gr_line
		(start 6.481826 -431.184304)
		(end 6.481826 -431.997104)
		(stroke
			(width 0.2)
			(type default)
		)
		(layer "In3.Cu")
	)
	(gr_arc
		(start 6.481826 -428.796958)
		(mid 6.992366 -429.307498)
		(end 7.502906 -428.796958)
		(stroke
			(width 0.2)
			(type default)
		)
		(layer "In3.Cu")
	)
	(gr_line
		(start 6.481826 -427.984158)
		(end 6.481826 -428.796958)
		(stroke
			(width 0.2)
			(type default)
		)
		(layer "In3.Cu")
	)
	(gr_arc
		(start 6.481826 -425.597066)
		(mid 6.992366 -426.107606)
		(end 7.502906 -425.597066)
		(stroke
			(width 0.2)
			(type default)
		)
		(layer "In3.Cu")
	)
	(gr_line
		(start 6.481826 -424.784266)
		(end 6.481826 -425.597066)
		(stroke
			(width 0.2)
			(type default)
		)
		(layer "In3.Cu")
	)
	(gr_arc
		(start 6.481826 -415.948622)
		(mid 6.992366 -416.459162)
		(end 7.502906 -415.948622)
		(stroke
			(width 0.2)
			(type default)
		)
		(layer "In3.Cu")
	)
	(gr_line
		(start 6.481826 -415.135822)
		(end 6.481826 -415.948622)
		(stroke
			(width 0.2)
			(type default)
		)
		(layer "In3.Cu")
	)
	(gr_arc
		(start 6.481826 -412.748222)
		(mid 6.992239 -413.259016)
		(end 7.502906 -412.748476)
		(stroke
			(width 0.2)
			(type default)
		)
		(layer "In3.Cu")
	)
	(gr_line
		(start 6.481826 -411.935676)
		(end 6.481826 -412.748222)
		(stroke
			(width 0.2)
			(type default)
		)
		(layer "In3.Cu")
	)
	(gr_arc
		(start 6.481826 -409.54833)
		(mid 6.992239 -410.059124)
		(end 7.502906 -409.548584)
		(stroke
			(width 0.2)
			(type default)
		)
		(layer "In3.Cu")
	)
	(gr_line
		(start 6.481826 -408.735784)
		(end 6.481826 -409.54833)
		(stroke
			(width 0.2)
			(type default)
		)
		(layer "In3.Cu")
	)
	(gr_arc
		(start 6.481826 -406.348184)
		(mid 6.992239 -406.858978)
		(end 7.502906 -406.348438)
		(stroke
			(width 0.2)
			(type default)
		)
		(layer "In3.Cu")
	)
	(gr_line
		(start 6.481826 -405.535638)
		(end 6.481826 -406.348184)
		(stroke
			(width 0.2)
			(type default)
		)
		(layer "In3.Cu")
	)
	(gr_arc
		(start 6.481826 -403.148292)
		(mid 6.992239 -403.659086)
		(end 7.502906 -403.148546)
		(stroke
			(width 0.2)
			(type default)
		)
		(layer "In3.Cu")
	)
	(gr_line
		(start 6.481826 -402.335746)
		(end 6.481826 -403.148292)
		(stroke
			(width 0.2)
			(type default)
		)
		(layer "In3.Cu")
	)
	(gr_arc
		(start 6.481826 -397.548608)
		(mid 6.992366 -398.059148)
		(end 7.502906 -397.548608)
		(stroke
			(width 0.2)
			(type default)
		)
		(layer "In3.Cu")
	)
	(gr_line
		(start 6.481826 -396.735808)
		(end 6.481826 -397.548608)
		(stroke
			(width 0.2)
			(type default)
		)
		(layer "In3.Cu")
	)
	(gr_arc
		(start 6.481826 -394.348462)
		(mid 6.992366 -394.859002)
		(end 7.502906 -394.348462)
		(stroke
			(width 0.2)
			(type default)
		)
		(layer "In3.Cu")
	)
	(gr_line
		(start 6.481826 -393.535662)
		(end 6.481826 -394.348462)
		(stroke
			(width 0.2)
			(type default)
		)
		(layer "In3.Cu")
	)
	(gr_arc
		(start 6.481826 -391.14857)
		(mid 6.992366 -391.65911)
		(end 7.502906 -391.14857)
		(stroke
			(width 0.2)
			(type default)
		)
		(layer "In3.Cu")
	)
	(gr_line
		(start 6.481826 -390.33577)
		(end 6.481826 -391.14857)
		(stroke
			(width 0.2)
			(type default)
		)
		(layer "In3.Cu")
	)
	(gr_arc
		(start 6.481826 -387.948424)
		(mid 6.992366 -388.458964)
		(end 7.502906 -387.948424)
		(stroke
			(width 0.2)
			(type default)
		)
		(layer "In3.Cu")
	)
	(gr_line
		(start 6.481826 -387.135624)
		(end 6.481826 -387.948424)
		(stroke
			(width 0.2)
			(type default)
		)
		(layer "In3.Cu")
	)
	(gr_arc
		(start 6.481826 -357.148384)
		(mid 6.992239 -357.659178)
		(end 7.502906 -357.148638)
		(stroke
			(width 0.2)
			(type default)
		)
		(layer "In3.Cu")
	)
	(gr_line
		(start 6.481826 -356.335838)
		(end 6.481826 -357.148384)
		(stroke
			(width 0.2)
			(type default)
		)
		(layer "In3.Cu")
	)
	(gr_arc
		(start 6.481826 -353.948746)
		(mid 6.992366 -354.459286)
		(end 7.502906 -353.948746)
		(stroke
			(width 0.2)
			(type default)
		)
		(layer "In3.Cu")
	)
	(gr_line
		(start 6.481826 -353.135946)
		(end 6.481826 -353.948746)
		(stroke
			(width 0.2)
			(type default)
		)
		(layer "In3.Cu")
	)
	(gr_arc
		(start 6.481826 -350.748346)
		(mid 6.992239 -351.25914)
		(end 7.502906 -350.7486)
		(stroke
			(width 0.2)
			(type default)
		)
		(layer "In3.Cu")
	)
	(gr_line
		(start 6.481826 -349.9358)
		(end 6.481826 -350.748346)
		(stroke
			(width 0.2)
			(type default)
		)
		(layer "In3.Cu")
	)
	(gr_arc
		(start 6.481826 -347.548454)
		(mid 6.992239 -348.059248)
		(end 7.502906 -347.548708)
		(stroke
			(width 0.2)
			(type default)
		)
		(layer "In3.Cu")
	)
	(gr_line
		(start 6.481826 -346.735908)
		(end 6.481826 -347.548454)
		(stroke
			(width 0.2)
			(type default)
		)
		(layer "In3.Cu")
	)
	(gr_arc
		(start 6.481826 -344.399616)
		(mid 6.992366 -344.910156)
		(end 7.502906 -344.399616)
		(stroke
			(width 0.2)
			(type default)
		)
		(layer "In3.Cu")
	)
	(gr_line
		(start 6.481826 -343.586816)
		(end 6.481826 -344.399616)
		(stroke
			(width 0.2)
			(type default)
		)
		(layer "In3.Cu")
	)
	(gr_arc
		(start 6.481826 -341.19947)
		(mid 6.992366 -341.71001)
		(end 7.502906 -341.19947)
		(stroke
			(width 0.2)
			(type default)
		)
		(layer "In3.Cu")
	)
	(gr_line
		(start 6.481826 -340.38667)
		(end 6.481826 -341.19947)
		(stroke
			(width 0.2)
			(type default)
		)
		(layer "In3.Cu")
	)
	(gr_arc
		(start 6.481826 -337.999578)
		(mid 6.992366 -338.510118)
		(end 7.502906 -337.999578)
		(stroke
			(width 0.2)
			(type default)
		)
		(layer "In3.Cu")
	)
	(gr_line
		(start 6.481826 -337.186778)
		(end 6.481826 -337.999578)
		(stroke
			(width 0.2)
			(type default)
		)
		(layer "In3.Cu")
	)
	(gr_arc
		(start 6.481826 -334.799432)
		(mid 6.992366 -335.309972)
		(end 7.502906 -334.799432)
		(stroke
			(width 0.2)
			(type default)
		)
		(layer "In3.Cu")
	)
	(gr_line
		(start 6.481826 -333.986632)
		(end 6.481826 -334.799432)
		(stroke
			(width 0.2)
			(type default)
		)
		(layer "In3.Cu")
	)
	(gr_arc
		(start 6.481826 -329.14844)
		(mid 6.992239 -329.659234)
		(end 7.502906 -329.148694)
		(stroke
			(width 0.2)
			(type default)
		)
		(layer "In3.Cu")
	)
	(gr_line
		(start 6.481826 -328.335894)
		(end 6.481826 -329.14844)
		(stroke
			(width 0.2)
			(type default)
		)
		(layer "In3.Cu")
	)
	(gr_arc
		(start 6.481826 -325.948548)
		(mid 6.992239 -326.459342)
		(end 7.502906 -325.948802)
		(stroke
			(width 0.2)
			(type default)
		)
		(layer "In3.Cu")
	)
	(gr_line
		(start 6.481826 -325.136002)
		(end 6.481826 -325.948548)
		(stroke
			(width 0.2)
			(type default)
		)
		(layer "In3.Cu")
	)
	(gr_arc
		(start 6.481826 -322.748402)
		(mid 6.992239 -323.259196)
		(end 7.502906 -322.748656)
		(stroke
			(width 0.2)
			(type default)
		)
		(layer "In3.Cu")
	)
	(gr_line
		(start 6.481826 -321.935856)
		(end 6.481826 -322.748402)
		(stroke
			(width 0.2)
			(type default)
		)
		(layer "In3.Cu")
	)
	(gr_arc
		(start 6.481826 -319.54851)
		(mid 6.992239 -320.059304)
		(end 7.502906 -319.548764)
		(stroke
			(width 0.2)
			(type default)
		)
		(layer "In3.Cu")
	)
	(gr_line
		(start 6.481826 -318.735964)
		(end 6.481826 -319.54851)
		(stroke
			(width 0.2)
			(type default)
		)
		(layer "In3.Cu")
	)
	(gr_arc
		(start 6.481826 -311.548526)
		(mid 6.992239 -312.05932)
		(end 7.502906 -311.54878)
		(stroke
			(width 0.2)
			(type default)
		)
		(layer "In3.Cu")
	)
	(gr_line
		(start 6.481826 -310.73598)
		(end 6.481826 -311.548526)
		(stroke
			(width 0.2)
			(type default)
		)
		(layer "In3.Cu")
	)
	(gr_arc
		(start 6.481826 -308.34838)
		(mid 6.992239 -308.859174)
		(end 7.502906 -308.348634)
		(stroke
			(width 0.2)
			(type default)
		)
		(layer "In3.Cu")
	)
	(gr_line
		(start 6.481826 -307.535834)
		(end 6.481826 -308.34838)
		(stroke
			(width 0.2)
			(type default)
		)
		(layer "In3.Cu")
	)
	(gr_arc
		(start 6.481826 -305.148488)
		(mid 6.992239 -305.659282)
		(end 7.502906 -305.148742)
		(stroke
			(width 0.2)
			(type default)
		)
		(layer "In3.Cu")
	)
	(gr_line
		(start 6.481826 -304.335942)
		(end 6.481826 -305.148488)
		(stroke
			(width 0.2)
			(type default)
		)
		(layer "In3.Cu")
	)
	(gr_arc
		(start 6.481826 -301.948342)
		(mid 6.992239 -302.459136)
		(end 7.502906 -301.948596)
		(stroke
			(width 0.2)
			(type default)
		)
		(layer "In3.Cu")
	)
	(gr_line
		(start 6.481826 -301.135796)
		(end 6.481826 -301.948342)
		(stroke
			(width 0.2)
			(type default)
		)
		(layer "In3.Cu")
	)
	(gr_arc
		(start 6.481826 -298.74845)
		(mid 6.992239 -299.259244)
		(end 7.502906 -298.748704)
		(stroke
			(width 0.2)
			(type default)
		)
		(layer "In3.Cu")
	)
	(gr_line
		(start 6.481826 -297.935904)
		(end 6.481826 -298.74845)
		(stroke
			(width 0.2)
			(type default)
		)
		(layer "In3.Cu")
	)
	(gr_arc
		(start 6.481826 -295.548558)
		(mid 6.992239 -296.059352)
		(end 7.502906 -295.548812)
		(stroke
			(width 0.2)
			(type default)
		)
		(layer "In3.Cu")
	)
	(gr_line
		(start 6.481826 -294.736012)
		(end 6.481826 -295.548558)
		(stroke
			(width 0.2)
			(type default)
		)
		(layer "In3.Cu")
	)
	(gr_arc
		(start 6.481826 -292.348412)
		(mid 6.992239 -292.859206)
		(end 7.502906 -292.348666)
		(stroke
			(width 0.2)
			(type default)
		)
		(layer "In3.Cu")
	)
	(gr_line
		(start 6.481826 -291.535866)
		(end 6.481826 -292.348412)
		(stroke
			(width 0.2)
			(type default)
		)
		(layer "In3.Cu")
	)
	(gr_arc
		(start 6.481826 -289.148774)
		(mid 6.992366 -289.659314)
		(end 7.502906 -289.148774)
		(stroke
			(width 0.2)
			(type default)
		)
		(layer "In3.Cu")
	)
	(gr_line
		(start 6.481826 -288.335974)
		(end 6.481826 -289.148774)
		(stroke
			(width 0.2)
			(type default)
		)
		(layer "In3.Cu")
	)
	(gr_arc
		(start 6.481826 -282.799536)
		(mid 6.992366 -283.310076)
		(end 7.502906 -282.799536)
		(stroke
			(width 0.2)
			(type default)
		)
		(layer "In3.Cu")
	)
	(gr_line
		(start 6.481826 -281.986736)
		(end 6.481826 -282.799536)
		(stroke
			(width 0.2)
			(type default)
		)
		(layer "In3.Cu")
	)
	(gr_arc
		(start 6.481826 -279.59939)
		(mid 6.992366 -280.10993)
		(end 7.502906 -279.59939)
		(stroke
			(width 0.2)
			(type default)
		)
		(layer "In3.Cu")
	)
	(gr_line
		(start 6.481826 -278.78659)
		(end 6.481826 -279.59939)
		(stroke
			(width 0.2)
			(type default)
		)
		(layer "In3.Cu")
	)
	(gr_arc
		(start 6.481826 -231.148636)
		(mid 6.992366 -231.659176)
		(end 7.502906 -231.148636)
		(stroke
			(width 0.2)
			(type default)
		)
		(layer "In3.Cu")
	)
	(gr_line
		(start 6.481826 -230.335836)
		(end 6.481826 -231.148636)
		(stroke
			(width 0.2)
			(type default)
		)
		(layer "In3.Cu")
	)
	(gr_arc
		(start 6.481826 -227.948744)
		(mid 6.992366 -228.459284)
		(end 7.502906 -227.948744)
		(stroke
			(width 0.2)
			(type default)
		)
		(layer "In3.Cu")
	)
	(gr_line
		(start 6.481826 -227.135944)
		(end 6.481826 -227.948744)
		(stroke
			(width 0.2)
			(type default)
		)
		(layer "In3.Cu")
	)
	(gr_arc
		(start 6.481826 -224.710498)
		(mid 6.992366 -225.221038)
		(end 7.502906 -224.710498)
		(stroke
			(width 0.2)
			(type default)
		)
		(layer "In3.Cu")
	)
	(gr_line
		(start 6.481826 -223.897698)
		(end 6.481826 -224.710498)
		(stroke
			(width 0.2)
			(type default)
		)
		(layer "In3.Cu")
	)
	(gr_arc
		(start 6.481826 -221.497652)
		(mid 6.992239 -222.008446)
		(end 7.502906 -221.497906)
		(stroke
			(width 0.2)
			(type default)
		)
		(layer "In3.Cu")
	)
	(gr_line
		(start 6.481826 -220.685106)
		(end 6.481826 -221.497652)
		(stroke
			(width 0.2)
			(type default)
		)
		(layer "In3.Cu")
	)
	(gr_arc
		(start 6.481826 -218.298014)
		(mid 6.992366 -218.808554)
		(end 7.502906 -218.298014)
		(stroke
			(width 0.2)
			(type default)
		)
		(layer "In3.Cu")
	)
	(gr_line
		(start 6.481826 -217.485214)
		(end 6.481826 -218.298014)
		(stroke
			(width 0.2)
			(type default)
		)
		(layer "In3.Cu")
	)
	(gr_arc
		(start 6.481826 -215.097868)
		(mid 6.992366 -215.608408)
		(end 7.502906 -215.097868)
		(stroke
			(width 0.2)
			(type default)
		)
		(layer "In3.Cu")
	)
	(gr_line
		(start 6.481826 -214.285068)
		(end 6.481826 -215.097868)
		(stroke
			(width 0.2)
			(type default)
		)
		(layer "In3.Cu")
	)
	(gr_arc
		(start 6.481826 -211.948776)
		(mid 6.992366 -212.459316)
		(end 7.502906 -211.948776)
		(stroke
			(width 0.2)
			(type default)
		)
		(layer "In3.Cu")
	)
	(gr_line
		(start 6.481826 -211.135976)
		(end 6.481826 -211.948776)
		(stroke
			(width 0.2)
			(type default)
		)
		(layer "In3.Cu")
	)
	(gr_arc
		(start 6.481826 -208.74863)
		(mid 6.992366 -209.25917)
		(end 7.502906 -208.74863)
		(stroke
			(width 0.2)
			(type default)
		)
		(layer "In3.Cu")
	)
	(gr_line
		(start 6.481826 -207.93583)
		(end 6.481826 -208.74863)
		(stroke
			(width 0.2)
			(type default)
		)
		(layer "In3.Cu")
	)
	(gr_arc
		(start 6.481826 -205.548738)
		(mid 6.992366 -206.059278)
		(end 7.502906 -205.548738)
		(stroke
			(width 0.2)
			(type default)
		)
		(layer "In3.Cu")
	)
	(gr_line
		(start 6.481826 -204.735938)
		(end 6.481826 -205.548738)
		(stroke
			(width 0.2)
			(type default)
		)
		(layer "In3.Cu")
	)
	(gr_arc
		(start 6.481826 -202.348592)
		(mid 6.992366 -202.859132)
		(end 7.502906 -202.348592)
		(stroke
			(width 0.2)
			(type default)
		)
		(layer "In3.Cu")
	)
	(gr_line
		(start 6.481826 -201.535792)
		(end 6.481826 -202.348592)
		(stroke
			(width 0.2)
			(type default)
		)
		(layer "In3.Cu")
	)
	(gr_arc
		(start 6.481826 -196.748654)
		(mid 6.992366 -197.259194)
		(end 7.502906 -196.748654)
		(stroke
			(width 0.2)
			(type default)
		)
		(layer "In3.Cu")
	)
	(gr_line
		(start 6.481826 -195.935854)
		(end 6.481826 -196.748654)
		(stroke
			(width 0.2)
			(type default)
		)
		(layer "In3.Cu")
	)
	(gr_arc
		(start 6.481826 -193.548762)
		(mid 6.992366 -194.059302)
		(end 7.502906 -193.548762)
		(stroke
			(width 0.2)
			(type default)
		)
		(layer "In3.Cu")
	)
	(gr_line
		(start 6.481826 -192.735962)
		(end 6.481826 -193.548762)
		(stroke
			(width 0.2)
			(type default)
		)
		(layer "In3.Cu")
	)
	(gr_arc
		(start 6.481826 -185.548778)
		(mid 6.992366 -186.059318)
		(end 7.502906 -185.548778)
		(stroke
			(width 0.2)
			(type default)
		)
		(layer "In3.Cu")
	)
	(gr_line
		(start 6.481826 -184.735978)
		(end 6.481826 -185.548778)
		(stroke
			(width 0.2)
			(type default)
		)
		(layer "In3.Cu")
	)
	(gr_arc
		(start 6.481826 -182.348632)
		(mid 6.992366 -182.859172)
		(end 7.502906 -182.348632)
		(stroke
			(width 0.2)
			(type default)
		)
		(layer "In3.Cu")
	)
	(gr_line
		(start 6.481826 -181.535832)
		(end 6.481826 -182.348632)
		(stroke
			(width 0.2)
			(type default)
		)
		(layer "In3.Cu")
	)
	(gr_arc
		(start 6.481826 -179.19954)
		(mid 6.992366 -179.71008)
		(end 7.502906 -179.19954)
		(stroke
			(width 0.2)
			(type default)
		)
		(layer "In3.Cu")
	)
	(gr_line
		(start 6.481826 -178.38674)
		(end 6.481826 -179.19954)
		(stroke
			(width 0.2)
			(type default)
		)
		(layer "In3.Cu")
	)
	(gr_arc
		(start 6.481826 -175.999394)
		(mid 6.992366 -176.509934)
		(end 7.502906 -175.999394)
		(stroke
			(width 0.2)
			(type default)
		)
		(layer "In3.Cu")
	)
	(gr_line
		(start 6.481826 -175.186594)
		(end 6.481826 -175.999394)
		(stroke
			(width 0.2)
			(type default)
		)
		(layer "In3.Cu")
	)
	(gr_arc
		(start 6.481826 -172.799502)
		(mid 6.992366 -173.310042)
		(end 7.502906 -172.799502)
		(stroke
			(width 0.2)
			(type default)
		)
		(layer "In3.Cu")
	)
	(gr_line
		(start 6.481826 -171.986702)
		(end 6.481826 -172.799502)
		(stroke
			(width 0.2)
			(type default)
		)
		(layer "In3.Cu")
	)
	(gr_arc
		(start 6.481826 -169.59961)
		(mid 6.992366 -170.11015)
		(end 7.502906 -169.59961)
		(stroke
			(width 0.2)
			(type default)
		)
		(layer "In3.Cu")
	)
	(gr_line
		(start 6.481826 -168.78681)
		(end 6.481826 -169.59961)
		(stroke
			(width 0.2)
			(type default)
		)
		(layer "In3.Cu")
	)
	(gr_arc
		(start 6.481826 -163.199572)
		(mid 6.992366 -163.710112)
		(end 7.502906 -163.199572)
		(stroke
			(width 0.2)
			(type default)
		)
		(layer "In3.Cu")
	)
	(gr_line
		(start 6.481826 -162.386772)
		(end 6.481826 -163.199572)
		(stroke
			(width 0.2)
			(type default)
		)
		(layer "In3.Cu")
	)
	(gr_arc
		(start 6.481826 -159.999426)
		(mid 6.992366 -160.509966)
		(end 7.502906 -159.999426)
		(stroke
			(width 0.2)
			(type default)
		)
		(layer "In3.Cu")
	)
	(gr_line
		(start 6.481826 -159.186626)
		(end 6.481826 -159.999426)
		(stroke
			(width 0.2)
			(type default)
		)
		(layer "In3.Cu")
	)
	(gr_arc
		(start 6.481826 -156.786834)
		(mid 6.992366 -157.297374)
		(end 7.502906 -156.786834)
		(stroke
			(width 0.2)
			(type default)
		)
		(layer "In3.Cu")
	)
	(gr_line
		(start 6.481826 -155.974034)
		(end 6.481826 -156.786834)
		(stroke
			(width 0.2)
			(type default)
		)
		(layer "In3.Cu")
	)
	(gr_arc
		(start 6.481826 -153.599388)
		(mid 6.992366 -154.109928)
		(end 7.502906 -153.599388)
		(stroke
			(width 0.2)
			(type default)
		)
		(layer "In3.Cu")
	)
	(gr_line
		(start 6.481826 -152.786588)
		(end 6.481826 -153.599388)
		(stroke
			(width 0.2)
			(type default)
		)
		(layer "In3.Cu")
	)
	(gr_arc
		(start 7.2898 -449.978272)
		(mid 7.80034 -449.467732)
		(end 7.2898 -448.957192)
		(stroke
			(width 0.2)
			(type default)
		)
		(layer "In3.Cu")
	)
	(gr_line
		(start 7.2898 -448.957192)
		(end 6.477254 -448.957192)
		(stroke
			(width 0.2)
			(type default)
		)
		(layer "In3.Cu")
	)
	(gr_line
		(start 7.502906 -447.196972)
		(end 7.502906 -446.384172)
		(stroke
			(width 0.2)
			(type default)
		)
		(layer "In3.Cu")
	)
	(gr_arc
		(start 7.502906 -446.384172)
		(mid 6.992366 -445.873632)
		(end 6.481826 -446.384172)
		(stroke
			(width 0.2)
			(type default)
		)
		(layer "In3.Cu")
	)
	(gr_line
		(start 7.502906 -443.99708)
		(end 7.502906 -443.18428)
		(stroke
			(width 0.2)
			(type default)
		)
		(layer "In3.Cu")
	)
	(gr_arc
		(start 7.502906 -443.18428)
		(mid 6.992366 -442.67374)
		(end 6.481826 -443.18428)
		(stroke
			(width 0.2)
			(type default)
		)
		(layer "In3.Cu")
	)
	(gr_line
		(start 7.502906 -440.796934)
		(end 7.502906 -439.984134)
		(stroke
			(width 0.2)
			(type default)
		)
		(layer "In3.Cu")
	)
	(gr_arc
		(start 7.502906 -439.984134)
		(mid 6.992366 -439.473594)
		(end 6.481826 -439.984134)
		(stroke
			(width 0.2)
			(type default)
		)
		(layer "In3.Cu")
	)
	(gr_line
		(start 7.502906 -437.597042)
		(end 7.502906 -436.784242)
		(stroke
			(width 0.2)
			(type default)
		)
		(layer "In3.Cu")
	)
	(gr_arc
		(start 7.502906 -436.784242)
		(mid 6.992366 -436.273702)
		(end 6.481826 -436.784242)
		(stroke
			(width 0.2)
			(type default)
		)
		(layer "In3.Cu")
	)
	(gr_line
		(start 7.502906 -431.997104)
		(end 7.502906 -431.184558)
		(stroke
			(width 0.2)
			(type default)
		)
		(layer "In3.Cu")
	)
	(gr_arc
		(start 7.502906 -431.184558)
		(mid 6.992493 -430.673764)
		(end 6.481826 -431.184304)
		(stroke
			(width 0.2)
			(type default)
		)
		(layer "In3.Cu")
	)
	(gr_line
		(start 7.502906 -428.796958)
		(end 7.502906 -427.984412)
		(stroke
			(width 0.2)
			(type default)
		)
		(layer "In3.Cu")
	)
	(gr_arc
		(start 7.502906 -427.984412)
		(mid 6.992493 -427.473618)
		(end 6.481826 -427.984158)
		(stroke
			(width 0.2)
			(type default)
		)
		(layer "In3.Cu")
	)
	(gr_line
		(start 7.502906 -425.597066)
		(end 7.502906 -424.78452)
		(stroke
			(width 0.2)
			(type default)
		)
		(layer "In3.Cu")
	)
	(gr_arc
		(start 7.502906 -424.78452)
		(mid 6.992493 -424.273726)
		(end 6.481826 -424.784266)
		(stroke
			(width 0.2)
			(type default)
		)
		(layer "In3.Cu")
	)
	(gr_line
		(start 7.502906 -415.948622)
		(end 7.502906 -415.136076)
		(stroke
			(width 0.2)
			(type default)
		)
		(layer "In3.Cu")
	)
	(gr_arc
		(start 7.502906 -415.136076)
		(mid 6.992493 -414.625282)
		(end 6.481826 -415.135822)
		(stroke
			(width 0.2)
			(type default)
		)
		(layer "In3.Cu")
	)
	(gr_line
		(start 7.502906 -412.748476)
		(end 7.502906 -411.935676)
		(stroke
			(width 0.2)
			(type default)
		)
		(layer "In3.Cu")
	)
	(gr_arc
		(start 7.502906 -411.935676)
		(mid 6.992366 -411.425136)
		(end 6.481826 -411.935676)
		(stroke
			(width 0.2)
			(type default)
		)
		(layer "In3.Cu")
	)
	(gr_line
		(start 7.502906 -409.548584)
		(end 7.502906 -408.735784)
		(stroke
			(width 0.2)
			(type default)
		)
		(layer "In3.Cu")
	)
	(gr_arc
		(start 7.502906 -408.735784)
		(mid 6.992366 -408.225244)
		(end 6.481826 -408.735784)
		(stroke
			(width 0.2)
			(type default)
		)
		(layer "In3.Cu")
	)
	(gr_line
		(start 7.502906 -406.348438)
		(end 7.502906 -405.535638)
		(stroke
			(width 0.2)
			(type default)
		)
		(layer "In3.Cu")
	)
	(gr_arc
		(start 7.502906 -405.535638)
		(mid 6.992366 -405.025098)
		(end 6.481826 -405.535638)
		(stroke
			(width 0.2)
			(type default)
		)
		(layer "In3.Cu")
	)
	(gr_line
		(start 7.502906 -403.148546)
		(end 7.502906 -402.335746)
		(stroke
			(width 0.2)
			(type default)
		)
		(layer "In3.Cu")
	)
	(gr_arc
		(start 7.502906 -402.335746)
		(mid 6.992366 -401.825206)
		(end 6.481826 -402.335746)
		(stroke
			(width 0.2)
			(type default)
		)
		(layer "In3.Cu")
	)
	(gr_line
		(start 7.502906 -397.548608)
		(end 7.502906 -396.736062)
		(stroke
			(width 0.2)
			(type default)
		)
		(layer "In3.Cu")
	)
	(gr_arc
		(start 7.502906 -396.736062)
		(mid 6.992493 -396.225268)
		(end 6.481826 -396.735808)
		(stroke
			(width 0.2)
			(type default)
		)
		(layer "In3.Cu")
	)
	(gr_line
		(start 7.502906 -394.348462)
		(end 7.502906 -393.535916)
		(stroke
			(width 0.2)
			(type default)
		)
		(layer "In3.Cu")
	)
	(gr_arc
		(start 7.502906 -393.535916)
		(mid 6.992493 -393.025122)
		(end 6.481826 -393.535662)
		(stroke
			(width 0.2)
			(type default)
		)
		(layer "In3.Cu")
	)
	(gr_line
		(start 7.502906 -391.14857)
		(end 7.502906 -390.336024)
		(stroke
			(width 0.2)
			(type default)
		)
		(layer "In3.Cu")
	)
	(gr_arc
		(start 7.502906 -390.336024)
		(mid 6.992493 -389.82523)
		(end 6.481826 -390.33577)
		(stroke
			(width 0.2)
			(type default)
		)
		(layer "In3.Cu")
	)
	(gr_line
		(start 7.502906 -387.948424)
		(end 7.502906 -387.135878)
		(stroke
			(width 0.2)
			(type default)
		)
		(layer "In3.Cu")
	)
	(gr_arc
		(start 7.502906 -387.135878)
		(mid 6.992493 -386.625084)
		(end 6.481826 -387.135624)
		(stroke
			(width 0.2)
			(type default)
		)
		(layer "In3.Cu")
	)
	(gr_line
		(start 7.502906 -357.148638)
		(end 7.502906 -356.335838)
		(stroke
			(width 0.2)
			(type default)
		)
		(layer "In3.Cu")
	)
	(gr_arc
		(start 7.502906 -356.335838)
		(mid 6.992366 -355.825298)
		(end 6.481826 -356.335838)
		(stroke
			(width 0.2)
			(type default)
		)
		(layer "In3.Cu")
	)
	(gr_line
		(start 7.502906 -353.948746)
		(end 7.502906 -353.1362)
		(stroke
			(width 0.2)
			(type default)
		)
		(layer "In3.Cu")
	)
	(gr_arc
		(start 7.502906 -353.1362)
		(mid 6.992493 -352.625406)
		(end 6.481826 -353.135946)
		(stroke
			(width 0.2)
			(type default)
		)
		(layer "In3.Cu")
	)
	(gr_line
		(start 7.502906 -350.7486)
		(end 7.502906 -349.9358)
		(stroke
			(width 0.2)
			(type default)
		)
		(layer "In3.Cu")
	)
	(gr_arc
		(start 7.502906 -349.9358)
		(mid 6.992366 -349.42526)
		(end 6.481826 -349.9358)
		(stroke
			(width 0.2)
			(type default)
		)
		(layer "In3.Cu")
	)
	(gr_line
		(start 7.502906 -347.548708)
		(end 7.502906 -346.735908)
		(stroke
			(width 0.2)
			(type default)
		)
		(layer "In3.Cu")
	)
	(gr_arc
		(start 7.502906 -346.735908)
		(mid 6.992366 -346.225368)
		(end 6.481826 -346.735908)
		(stroke
			(width 0.2)
			(type default)
		)
		(layer "In3.Cu")
	)
	(gr_line
		(start 7.502906 -344.399616)
		(end 7.502906 -343.58707)
		(stroke
			(width 0.2)
			(type default)
		)
		(layer "In3.Cu")
	)
	(gr_arc
		(start 7.502906 -343.58707)
		(mid 6.992493 -343.076276)
		(end 6.481826 -343.586816)
		(stroke
			(width 0.2)
			(type default)
		)
		(layer "In3.Cu")
	)
	(gr_line
		(start 7.502906 -341.19947)
		(end 7.502906 -340.386924)
		(stroke
			(width 0.2)
			(type default)
		)
		(layer "In3.Cu")
	)
	(gr_arc
		(start 7.502906 -340.386924)
		(mid 6.992493 -339.87613)
		(end 6.481826 -340.38667)
		(stroke
			(width 0.2)
			(type default)
		)
		(layer "In3.Cu")
	)
	(gr_line
		(start 7.502906 -337.999578)
		(end 7.502906 -337.187032)
		(stroke
			(width 0.2)
			(type default)
		)
		(layer "In3.Cu")
	)
	(gr_arc
		(start 7.502906 -337.187032)
		(mid 6.992493 -336.676238)
		(end 6.481826 -337.186778)
		(stroke
			(width 0.2)
			(type default)
		)
		(layer "In3.Cu")
	)
	(gr_line
		(start 7.502906 -334.799432)
		(end 7.502906 -333.986886)
		(stroke
			(width 0.2)
			(type default)
		)
		(layer "In3.Cu")
	)
	(gr_arc
		(start 7.502906 -333.986886)
		(mid 6.992493 -333.476092)
		(end 6.481826 -333.986632)
		(stroke
			(width 0.2)
			(type default)
		)
		(layer "In3.Cu")
	)
	(gr_line
		(start 7.502906 -329.148694)
		(end 7.502906 -328.335894)
		(stroke
			(width 0.2)
			(type default)
		)
		(layer "In3.Cu")
	)
	(gr_arc
		(start 7.502906 -328.335894)
		(mid 6.992366 -327.825354)
		(end 6.481826 -328.335894)
		(stroke
			(width 0.2)
			(type default)
		)
		(layer "In3.Cu")
	)
	(gr_line
		(start 7.502906 -325.948802)
		(end 7.502906 -325.136002)
		(stroke
			(width 0.2)
			(type default)
		)
		(layer "In3.Cu")
	)
	(gr_arc
		(start 7.502906 -325.136002)
		(mid 6.992366 -324.625462)
		(end 6.481826 -325.136002)
		(stroke
			(width 0.2)
			(type default)
		)
		(layer "In3.Cu")
	)
	(gr_line
		(start 7.502906 -322.748656)
		(end 7.502906 -321.935856)
		(stroke
			(width 0.2)
			(type default)
		)
		(layer "In3.Cu")
	)
	(gr_arc
		(start 7.502906 -321.935856)
		(mid 6.992366 -321.425316)
		(end 6.481826 -321.935856)
		(stroke
			(width 0.2)
			(type default)
		)
		(layer "In3.Cu")
	)
	(gr_line
		(start 7.502906 -319.548764)
		(end 7.502906 -318.735964)
		(stroke
			(width 0.2)
			(type default)
		)
		(layer "In3.Cu")
	)
	(gr_arc
		(start 7.502906 -318.735964)
		(mid 6.992366 -318.225424)
		(end 6.481826 -318.735964)
		(stroke
			(width 0.2)
			(type default)
		)
		(layer "In3.Cu")
	)
	(gr_line
		(start 7.502906 -311.54878)
		(end 7.502906 -310.73598)
		(stroke
			(width 0.2)
			(type default)
		)
		(layer "In3.Cu")
	)
	(gr_arc
		(start 7.502906 -310.73598)
		(mid 6.992366 -310.22544)
		(end 6.481826 -310.73598)
		(stroke
			(width 0.2)
			(type default)
		)
		(layer "In3.Cu")
	)
	(gr_line
		(start 7.502906 -308.348634)
		(end 7.502906 -307.535834)
		(stroke
			(width 0.2)
			(type default)
		)
		(layer "In3.Cu")
	)
	(gr_arc
		(start 7.502906 -307.535834)
		(mid 6.992366 -307.025294)
		(end 6.481826 -307.535834)
		(stroke
			(width 0.2)
			(type default)
		)
		(layer "In3.Cu")
	)
	(gr_line
		(start 7.502906 -305.148742)
		(end 7.502906 -304.335942)
		(stroke
			(width 0.2)
			(type default)
		)
		(layer "In3.Cu")
	)
	(gr_arc
		(start 7.502906 -304.335942)
		(mid 6.992366 -303.825402)
		(end 6.481826 -304.335942)
		(stroke
			(width 0.2)
			(type default)
		)
		(layer "In3.Cu")
	)
	(gr_line
		(start 7.502906 -301.948596)
		(end 7.502906 -301.135796)
		(stroke
			(width 0.2)
			(type default)
		)
		(layer "In3.Cu")
	)
	(gr_arc
		(start 7.502906 -301.135796)
		(mid 6.992366 -300.625256)
		(end 6.481826 -301.135796)
		(stroke
			(width 0.2)
			(type default)
		)
		(layer "In3.Cu")
	)
	(gr_line
		(start 7.502906 -298.748704)
		(end 7.502906 -297.935904)
		(stroke
			(width 0.2)
			(type default)
		)
		(layer "In3.Cu")
	)
	(gr_arc
		(start 7.502906 -297.935904)
		(mid 6.992366 -297.425364)
		(end 6.481826 -297.935904)
		(stroke
			(width 0.2)
			(type default)
		)
		(layer "In3.Cu")
	)
	(gr_line
		(start 7.502906 -295.548812)
		(end 7.502906 -294.736012)
		(stroke
			(width 0.2)
			(type default)
		)
		(layer "In3.Cu")
	)
	(gr_arc
		(start 7.502906 -294.736012)
		(mid 6.992366 -294.225472)
		(end 6.481826 -294.736012)
		(stroke
			(width 0.2)
			(type default)
		)
		(layer "In3.Cu")
	)
	(gr_line
		(start 7.502906 -292.348666)
		(end 7.502906 -291.535866)
		(stroke
			(width 0.2)
			(type default)
		)
		(layer "In3.Cu")
	)
	(gr_arc
		(start 7.502906 -291.535866)
		(mid 6.992366 -291.025326)
		(end 6.481826 -291.535866)
		(stroke
			(width 0.2)
			(type default)
		)
		(layer "In3.Cu")
	)
	(gr_line
		(start 7.502906 -289.148774)
		(end 7.502906 -288.336228)
		(stroke
			(width 0.2)
			(type default)
		)
		(layer "In3.Cu")
	)
	(gr_arc
		(start 7.502906 -288.336228)
		(mid 6.992493 -287.825434)
		(end 6.481826 -288.335974)
		(stroke
			(width 0.2)
			(type default)
		)
		(layer "In3.Cu")
	)
	(gr_line
		(start 7.502906 -282.799536)
		(end 7.502906 -281.98699)
		(stroke
			(width 0.2)
			(type default)
		)
		(layer "In3.Cu")
	)
	(gr_arc
		(start 7.502906 -281.98699)
		(mid 6.992493 -281.476196)
		(end 6.481826 -281.986736)
		(stroke
			(width 0.2)
			(type default)
		)
		(layer "In3.Cu")
	)
	(gr_line
		(start 7.502906 -279.59939)
		(end 7.502906 -278.786844)
		(stroke
			(width 0.2)
			(type default)
		)
		(layer "In3.Cu")
	)
	(gr_arc
		(start 7.502906 -278.786844)
		(mid 6.992493 -278.27605)
		(end 6.481826 -278.78659)
		(stroke
			(width 0.2)
			(type default)
		)
		(layer "In3.Cu")
	)
	(gr_line
		(start 7.502906 -231.148636)
		(end 7.502906 -230.33609)
		(stroke
			(width 0.2)
			(type default)
		)
		(layer "In3.Cu")
	)
	(gr_arc
		(start 7.502906 -230.33609)
		(mid 6.992493 -229.825296)
		(end 6.481826 -230.335836)
		(stroke
			(width 0.2)
			(type default)
		)
		(layer "In3.Cu")
	)
	(gr_line
		(start 7.502906 -227.948744)
		(end 7.502906 -227.136198)
		(stroke
			(width 0.2)
			(type default)
		)
		(layer "In3.Cu")
	)
	(gr_arc
		(start 7.502906 -227.136198)
		(mid 6.992493 -226.625404)
		(end 6.481826 -227.135944)
		(stroke
			(width 0.2)
			(type default)
		)
		(layer "In3.Cu")
	)
	(gr_line
		(start 7.502906 -224.710498)
		(end 7.502906 -223.897952)
		(stroke
			(width 0.2)
			(type default)
		)
		(layer "In3.Cu")
	)
	(gr_arc
		(start 7.502906 -223.897952)
		(mid 6.992493 -223.387158)
		(end 6.481826 -223.897698)
		(stroke
			(width 0.2)
			(type default)
		)
		(layer "In3.Cu")
	)
	(gr_line
		(start 7.502906 -221.497906)
		(end 7.502906 -220.685106)
		(stroke
			(width 0.2)
			(type default)
		)
		(layer "In3.Cu")
	)
	(gr_arc
		(start 7.502906 -220.685106)
		(mid 6.992366 -220.174566)
		(end 6.481826 -220.685106)
		(stroke
			(width 0.2)
			(type default)
		)
		(layer "In3.Cu")
	)
	(gr_line
		(start 7.502906 -218.298014)
		(end 7.502906 -217.485468)
		(stroke
			(width 0.2)
			(type default)
		)
		(layer "In3.Cu")
	)
	(gr_arc
		(start 7.502906 -217.485468)
		(mid 6.992493 -216.974674)
		(end 6.481826 -217.485214)
		(stroke
			(width 0.2)
			(type default)
		)
		(layer "In3.Cu")
	)
	(gr_line
		(start 7.502906 -215.097868)
		(end 7.502906 -214.285322)
		(stroke
			(width 0.2)
			(type default)
		)
		(layer "In3.Cu")
	)
	(gr_arc
		(start 7.502906 -214.285322)
		(mid 6.992493 -213.774528)
		(end 6.481826 -214.285068)
		(stroke
			(width 0.2)
			(type default)
		)
		(layer "In3.Cu")
	)
	(gr_line
		(start 7.502906 -211.948776)
		(end 7.502906 -211.13623)
		(stroke
			(width 0.2)
			(type default)
		)
		(layer "In3.Cu")
	)
	(gr_arc
		(start 7.502906 -211.13623)
		(mid 6.992493 -210.625436)
		(end 6.481826 -211.135976)
		(stroke
			(width 0.2)
			(type default)
		)
		(layer "In3.Cu")
	)
	(gr_line
		(start 7.502906 -208.74863)
		(end 7.502906 -207.936084)
		(stroke
			(width 0.2)
			(type default)
		)
		(layer "In3.Cu")
	)
	(gr_arc
		(start 7.502906 -207.936084)
		(mid 6.992493 -207.42529)
		(end 6.481826 -207.93583)
		(stroke
			(width 0.2)
			(type default)
		)
		(layer "In3.Cu")
	)
	(gr_line
		(start 7.502906 -205.548738)
		(end 7.502906 -204.736192)
		(stroke
			(width 0.2)
			(type default)
		)
		(layer "In3.Cu")
	)
	(gr_arc
		(start 7.502906 -204.736192)
		(mid 6.992493 -204.225398)
		(end 6.481826 -204.735938)
		(stroke
			(width 0.2)
			(type default)
		)
		(layer "In3.Cu")
	)
	(gr_line
		(start 7.502906 -202.348592)
		(end 7.502906 -201.536046)
		(stroke
			(width 0.2)
			(type default)
		)
		(layer "In3.Cu")
	)
	(gr_arc
		(start 7.502906 -201.536046)
		(mid 6.992493 -201.025252)
		(end 6.481826 -201.535792)
		(stroke
			(width 0.2)
			(type default)
		)
		(layer "In3.Cu")
	)
	(gr_line
		(start 7.502906 -196.748654)
		(end 7.502906 -195.936108)
		(stroke
			(width 0.2)
			(type default)
		)
		(layer "In3.Cu")
	)
	(gr_arc
		(start 7.502906 -195.936108)
		(mid 6.992493 -195.425314)
		(end 6.481826 -195.935854)
		(stroke
			(width 0.2)
			(type default)
		)
		(layer "In3.Cu")
	)
	(gr_line
		(start 7.502906 -193.548762)
		(end 7.502906 -192.736216)
		(stroke
			(width 0.2)
			(type default)
		)
		(layer "In3.Cu")
	)
	(gr_arc
		(start 7.502906 -192.736216)
		(mid 6.992493 -192.225422)
		(end 6.481826 -192.735962)
		(stroke
			(width 0.2)
			(type default)
		)
		(layer "In3.Cu")
	)
	(gr_line
		(start 7.502906 -185.548778)
		(end 7.502906 -184.736232)
		(stroke
			(width 0.2)
			(type default)
		)
		(layer "In3.Cu")
	)
	(gr_arc
		(start 7.502906 -184.736232)
		(mid 6.992493 -184.225438)
		(end 6.481826 -184.735978)
		(stroke
			(width 0.2)
			(type default)
		)
		(layer "In3.Cu")
	)
	(gr_line
		(start 7.502906 -182.348632)
		(end 7.502906 -181.536086)
		(stroke
			(width 0.2)
			(type default)
		)
		(layer "In3.Cu")
	)
	(gr_arc
		(start 7.502906 -181.536086)
		(mid 6.992493 -181.025292)
		(end 6.481826 -181.535832)
		(stroke
			(width 0.2)
			(type default)
		)
		(layer "In3.Cu")
	)
	(gr_line
		(start 7.502906 -179.19954)
		(end 7.502906 -178.386994)
		(stroke
			(width 0.2)
			(type default)
		)
		(layer "In3.Cu")
	)
	(gr_arc
		(start 7.502906 -178.386994)
		(mid 6.992493 -177.8762)
		(end 6.481826 -178.38674)
		(stroke
			(width 0.2)
			(type default)
		)
		(layer "In3.Cu")
	)
	(gr_line
		(start 7.502906 -175.999394)
		(end 7.502906 -175.186848)
		(stroke
			(width 0.2)
			(type default)
		)
		(layer "In3.Cu")
	)
	(gr_arc
		(start 7.502906 -175.186848)
		(mid 6.992493 -174.676054)
		(end 6.481826 -175.186594)
		(stroke
			(width 0.2)
			(type default)
		)
		(layer "In3.Cu")
	)
	(gr_line
		(start 7.502906 -172.799502)
		(end 7.502906 -171.986956)
		(stroke
			(width 0.2)
			(type default)
		)
		(layer "In3.Cu")
	)
	(gr_arc
		(start 7.502906 -171.986956)
		(mid 6.992493 -171.476162)
		(end 6.481826 -171.986702)
		(stroke
			(width 0.2)
			(type default)
		)
		(layer "In3.Cu")
	)
	(gr_line
		(start 7.502906 -169.59961)
		(end 7.502906 -168.787064)
		(stroke
			(width 0.2)
			(type default)
		)
		(layer "In3.Cu")
	)
	(gr_arc
		(start 7.502906 -168.787064)
		(mid 6.992493 -168.27627)
		(end 6.481826 -168.78681)
		(stroke
			(width 0.2)
			(type default)
		)
		(layer "In3.Cu")
	)
	(gr_line
		(start 7.502906 -163.199572)
		(end 7.502906 -162.387026)
		(stroke
			(width 0.2)
			(type default)
		)
		(layer "In3.Cu")
	)
	(gr_arc
		(start 7.502906 -162.387026)
		(mid 6.992493 -161.876232)
		(end 6.481826 -162.386772)
		(stroke
			(width 0.2)
			(type default)
		)
		(layer "In3.Cu")
	)
	(gr_line
		(start 7.502906 -159.999426)
		(end 7.502906 -159.18688)
		(stroke
			(width 0.2)
			(type default)
		)
		(layer "In3.Cu")
	)
	(gr_arc
		(start 7.502906 -159.18688)
		(mid 6.992493 -158.676086)
		(end 6.481826 -159.186626)
		(stroke
			(width 0.2)
			(type default)
		)
		(layer "In3.Cu")
	)
	(gr_line
		(start 7.502906 -156.786834)
		(end 7.502906 -155.974288)
		(stroke
			(width 0.2)
			(type default)
		)
		(layer "In3.Cu")
	)
	(gr_arc
		(start 7.502906 -155.974288)
		(mid 6.992493 -155.463494)
		(end 6.481826 -155.974034)
		(stroke
			(width 0.2)
			(type default)
		)
		(layer "In3.Cu")
	)
	(gr_line
		(start 7.502906 -153.599388)
		(end 7.502906 -152.786842)
		(stroke
			(width 0.2)
			(type default)
		)
		(layer "In3.Cu")
	)
	(gr_arc
		(start 7.502906 -152.786842)
		(mid 6.992493 -152.276048)
		(end 6.481826 -152.786588)
		(stroke
			(width 0.2)
			(type default)
		)
		(layer "In3.Cu")
	)
	(gr_line
		(start 8.382254 -386.113782)
		(end 9.1948 -386.113782)
		(stroke
			(width 0.2)
			(type default)
		)
		(layer "In3.Cu")
	)
	(gr_arc
		(start 8.382254 -385.092702)
		(mid 7.871714 -385.603242)
		(end 8.382254 -386.113782)
		(stroke
			(width 0.2)
			(type default)
		)
		(layer "In3.Cu")
	)
	(gr_arc
		(start 9.1948 -386.113782)
		(mid 9.705594 -385.603369)
		(end 9.195054 -385.092702)
		(stroke
			(width 0.2)
			(type default)
		)
		(layer "In3.Cu")
	)
	(gr_line
		(start 9.195054 -385.092702)
		(end 8.382254 -385.092702)
		(stroke
			(width 0.2)
			(type default)
		)
		(layer "In3.Cu")
	)
	(gr_arc
		(start 16.76146 -445.415924)
		(mid 17.271873 -445.926718)
		(end 17.78254 -445.416178)
		(stroke
			(width 0.2)
			(type default)
		)
		(layer "In3.Cu")
	)
	(gr_line
		(start 16.76146 -444.603378)
		(end 16.76146 -445.415924)
		(stroke
			(width 0.2)
			(type default)
		)
		(layer "In3.Cu")
	)
	(gr_arc
		(start 16.76146 -342.415876)
		(mid 17.271873 -342.92667)
		(end 17.78254 -342.41613)
		(stroke
			(width 0.2)
			(type default)
		)
		(layer "In3.Cu")
	)
	(gr_line
		(start 16.76146 -341.60333)
		(end 16.76146 -342.415876)
		(stroke
			(width 0.2)
			(type default)
		)
		(layer "In3.Cu")
	)
	(gr_arc
		(start 16.76146 -239.415828)
		(mid 17.271873 -239.926622)
		(end 17.78254 -239.416082)
		(stroke
			(width 0.2)
			(type default)
		)
		(layer "In3.Cu")
	)
	(gr_line
		(start 16.76146 -238.603282)
		(end 16.76146 -239.415828)
		(stroke
			(width 0.2)
			(type default)
		)
		(layer "In3.Cu")
	)
	(gr_arc
		(start 16.76146 -136.41578)
		(mid 17.271873 -136.926574)
		(end 17.78254 -136.416034)
		(stroke
			(width 0.2)
			(type default)
		)
		(layer "In3.Cu")
	)
	(gr_line
		(start 16.76146 -135.603234)
		(end 16.76146 -136.41578)
		(stroke
			(width 0.2)
			(type default)
		)
		(layer "In3.Cu")
	)
	(gr_arc
		(start 16.76146 -33.415986)
		(mid 17.272 -33.926526)
		(end 17.78254 -33.415986)
		(stroke
			(width 0.2)
			(type default)
		)
		(layer "In3.Cu")
	)
	(gr_line
		(start 16.76146 -32.603186)
		(end 16.76146 -33.415986)
		(stroke
			(width 0.2)
			(type default)
		)
		(layer "In3.Cu")
	)
	(gr_line
		(start 17.78254 -445.416178)
		(end 17.78254 -444.603378)
		(stroke
			(width 0.2)
			(type default)
		)
		(layer "In3.Cu")
	)
	(gr_arc
		(start 17.78254 -444.603378)
		(mid 17.272 -444.092838)
		(end 16.76146 -444.603378)
		(stroke
			(width 0.2)
			(type default)
		)
		(layer "In3.Cu")
	)
	(gr_line
		(start 17.78254 -342.41613)
		(end 17.78254 -341.60333)
		(stroke
			(width 0.2)
			(type default)
		)
		(layer "In3.Cu")
	)
	(gr_arc
		(start 17.78254 -341.60333)
		(mid 17.272 -341.09279)
		(end 16.76146 -341.60333)
		(stroke
			(width 0.2)
			(type default)
		)
		(layer "In3.Cu")
	)
	(gr_line
		(start 17.78254 -239.416082)
		(end 17.78254 -238.603282)
		(stroke
			(width 0.2)
			(type default)
		)
		(layer "In3.Cu")
	)
	(gr_arc
		(start 17.78254 -238.603282)
		(mid 17.272 -238.092742)
		(end 16.76146 -238.603282)
		(stroke
			(width 0.2)
			(type default)
		)
		(layer "In3.Cu")
	)
	(gr_line
		(start 17.78254 -136.416034)
		(end 17.78254 -135.603234)
		(stroke
			(width 0.2)
			(type default)
		)
		(layer "In3.Cu")
	)
	(gr_arc
		(start 17.78254 -135.603234)
		(mid 17.272 -135.092694)
		(end 16.76146 -135.603234)
		(stroke
			(width 0.2)
			(type default)
		)
		(layer "In3.Cu")
	)
	(gr_line
		(start 17.78254 -33.415986)
		(end 17.78254 -32.60344)
		(stroke
			(width 0.2)
			(type default)
		)
		(layer "In3.Cu")
	)
	(gr_arc
		(start 17.78254 -32.60344)
		(mid 17.272127 -32.092646)
		(end 16.76146 -32.603186)
		(stroke
			(width 0.2)
			(type default)
		)
		(layer "In3.Cu")
	)
	(gr_arc
		(start 24.66086 -449.168774)
		(mid 25.273 -449.780914)
		(end 25.88514 -449.168774)
		(stroke
			(width 0.2)
			(type default)
		)
		(layer "In3.Cu")
	)
	(gr_line
		(start 24.66086 -448.051174)
		(end 24.66086 -449.168774)
		(stroke
			(width 0.2)
			(type default)
		)
		(layer "In3.Cu")
	)
	(gr_arc
		(start 24.66086 -436.368952)
		(mid 25.273 -436.981092)
		(end 25.88514 -436.368952)
		(stroke
			(width 0.2)
			(type default)
		)
		(layer "In3.Cu")
	)
	(gr_line
		(start 24.66086 -435.251352)
		(end 24.66086 -436.368952)
		(stroke
			(width 0.2)
			(type default)
		)
		(layer "In3.Cu")
	)
	(gr_arc
		(start 24.66086 -431.56886)
		(mid 25.273 -432.181)
		(end 25.88514 -431.56886)
		(stroke
			(width 0.2)
			(type default)
		)
		(layer "In3.Cu")
	)
	(gr_line
		(start 24.66086 -430.45126)
		(end 24.66086 -431.56886)
		(stroke
			(width 0.2)
			(type default)
		)
		(layer "In3.Cu")
	)
	(gr_arc
		(start 24.66086 -426.768768)
		(mid 25.273 -427.380908)
		(end 25.88514 -426.768768)
		(stroke
			(width 0.2)
			(type default)
		)
		(layer "In3.Cu")
	)
	(gr_line
		(start 24.66086 -425.651168)
		(end 24.66086 -426.768768)
		(stroke
			(width 0.2)
			(type default)
		)
		(layer "In3.Cu")
	)
	(gr_arc
		(start 24.66086 -346.168726)
		(mid 25.273 -346.780866)
		(end 25.88514 -346.168726)
		(stroke
			(width 0.2)
			(type default)
		)
		(layer "In3.Cu")
	)
	(gr_line
		(start 24.66086 -345.051126)
		(end 24.66086 -346.168726)
		(stroke
			(width 0.2)
			(type default)
		)
		(layer "In3.Cu")
	)
	(gr_arc
		(start 24.66086 -333.36865)
		(mid 25.272873 -333.981044)
		(end 25.88514 -333.368904)
		(stroke
			(width 0.2)
			(type default)
		)
		(layer "In3.Cu")
	)
	(gr_line
		(start 24.66086 -332.251304)
		(end 24.66086 -333.36865)
		(stroke
			(width 0.2)
			(type default)
		)
		(layer "In3.Cu")
	)
	(gr_arc
		(start 24.66086 -328.568558)
		(mid 25.272873 -329.180952)
		(end 25.88514 -328.568812)
		(stroke
			(width 0.2)
			(type default)
		)
		(layer "In3.Cu")
	)
	(gr_line
		(start 24.66086 -327.451212)
		(end 24.66086 -328.568558)
		(stroke
			(width 0.2)
			(type default)
		)
		(layer "In3.Cu")
	)
	(gr_arc
		(start 24.66086 -323.768466)
		(mid 25.272873 -324.38086)
		(end 25.88514 -323.76872)
		(stroke
			(width 0.2)
			(type default)
		)
		(layer "In3.Cu")
	)
	(gr_line
		(start 24.66086 -322.65112)
		(end 24.66086 -323.768466)
		(stroke
			(width 0.2)
			(type default)
		)
		(layer "In3.Cu")
	)
	(gr_arc
		(start 24.66086 -243.168424)
		(mid 25.272873 -243.780818)
		(end 25.88514 -243.168678)
		(stroke
			(width 0.2)
			(type default)
		)
		(layer "In3.Cu")
	)
	(gr_line
		(start 24.66086 -242.051078)
		(end 24.66086 -243.168424)
		(stroke
			(width 0.2)
			(type default)
		)
		(layer "In3.Cu")
	)
	(gr_arc
		(start 24.66086 -230.368602)
		(mid 25.272873 -230.980996)
		(end 25.88514 -230.368856)
		(stroke
			(width 0.2)
			(type default)
		)
		(layer "In3.Cu")
	)
	(gr_line
		(start 24.66086 -229.251256)
		(end 24.66086 -230.368602)
		(stroke
			(width 0.2)
			(type default)
		)
		(layer "In3.Cu")
	)
	(gr_arc
		(start 24.66086 -225.56851)
		(mid 25.272873 -226.180904)
		(end 25.88514 -225.568764)
		(stroke
			(width 0.2)
			(type default)
		)
		(layer "In3.Cu")
	)
	(gr_line
		(start 24.66086 -224.451164)
		(end 24.66086 -225.56851)
		(stroke
			(width 0.2)
			(type default)
		)
		(layer "In3.Cu")
	)
	(gr_arc
		(start 24.66086 -220.768672)
		(mid 25.273 -221.380812)
		(end 25.88514 -220.768672)
		(stroke
			(width 0.2)
			(type default)
		)
		(layer "In3.Cu")
	)
	(gr_line
		(start 24.66086 -219.651072)
		(end 24.66086 -220.768672)
		(stroke
			(width 0.2)
			(type default)
		)
		(layer "In3.Cu")
	)
	(gr_arc
		(start 24.66086 -140.16863)
		(mid 25.273 -140.78077)
		(end 25.88514 -140.16863)
		(stroke
			(width 0.2)
			(type default)
		)
		(layer "In3.Cu")
	)
	(gr_line
		(start 24.66086 -139.05103)
		(end 24.66086 -140.16863)
		(stroke
			(width 0.2)
			(type default)
		)
		(layer "In3.Cu")
	)
	(gr_arc
		(start 24.66086 -127.368554)
		(mid 25.272873 -127.980948)
		(end 25.88514 -127.368808)
		(stroke
			(width 0.2)
			(type default)
		)
		(layer "In3.Cu")
	)
	(gr_line
		(start 24.66086 -126.251208)
		(end 24.66086 -127.368554)
		(stroke
			(width 0.2)
			(type default)
		)
		(layer "In3.Cu")
	)
	(gr_arc
		(start 24.66086 -122.568462)
		(mid 25.272873 -123.180856)
		(end 25.88514 -122.568716)
		(stroke
			(width 0.2)
			(type default)
		)
		(layer "In3.Cu")
	)
	(gr_line
		(start 24.66086 -121.451116)
		(end 24.66086 -122.568462)
		(stroke
			(width 0.2)
			(type default)
		)
		(layer "In3.Cu")
	)
	(gr_arc
		(start 24.66086 -117.768624)
		(mid 25.273 -118.380764)
		(end 25.88514 -117.768624)
		(stroke
			(width 0.2)
			(type default)
		)
		(layer "In3.Cu")
	)
	(gr_line
		(start 24.66086 -116.651024)
		(end 24.66086 -117.768624)
		(stroke
			(width 0.2)
			(type default)
		)
		(layer "In3.Cu")
	)
	(gr_arc
		(start 24.66086 -37.168328)
		(mid 25.272873 -37.780722)
		(end 25.88514 -37.168582)
		(stroke
			(width 0.2)
			(type default)
		)
		(layer "In3.Cu")
	)
	(gr_line
		(start 24.66086 -36.050982)
		(end 24.66086 -37.168328)
		(stroke
			(width 0.2)
			(type default)
		)
		(layer "In3.Cu")
	)
	(gr_arc
		(start 24.66086 -24.368506)
		(mid 25.272873 -24.9809)
		(end 25.88514 -24.36876)
		(stroke
			(width 0.2)
			(type default)
		)
		(layer "In3.Cu")
	)
	(gr_line
		(start 24.66086 -23.25116)
		(end 24.66086 -24.368506)
		(stroke
			(width 0.2)
			(type default)
		)
		(layer "In3.Cu")
	)
	(gr_arc
		(start 24.66086 -19.568414)
		(mid 25.272873 -20.180808)
		(end 25.88514 -19.568668)
		(stroke
			(width 0.2)
			(type default)
		)
		(layer "In3.Cu")
	)
	(gr_line
		(start 24.66086 -18.451068)
		(end 24.66086 -19.568414)
		(stroke
			(width 0.2)
			(type default)
		)
		(layer "In3.Cu")
	)
	(gr_arc
		(start 24.66086 -14.793976)
		(mid 25.273 -15.406116)
		(end 25.88514 -14.793976)
		(stroke
			(width 0.2)
			(type default)
		)
		(layer "In3.Cu")
	)
	(gr_line
		(start 24.66086 -13.676376)
		(end 24.66086 -14.793976)
		(stroke
			(width 0.2)
			(type default)
		)
		(layer "In3.Cu")
	)
	(gr_line
		(start 25.88514 -449.168774)
		(end 25.88514 -448.051428)
		(stroke
			(width 0.2)
			(type default)
		)
		(layer "In3.Cu")
	)
	(gr_arc
		(start 25.88514 -448.051428)
		(mid 25.273127 -447.439034)
		(end 24.66086 -448.051174)
		(stroke
			(width 0.2)
			(type default)
		)
		(layer "In3.Cu")
	)
	(gr_line
		(start 25.88514 -436.368952)
		(end 25.88514 -435.251606)
		(stroke
			(width 0.2)
			(type default)
		)
		(layer "In3.Cu")
	)
	(gr_arc
		(start 25.88514 -435.251606)
		(mid 25.273127 -434.639212)
		(end 24.66086 -435.251352)
		(stroke
			(width 0.2)
			(type default)
		)
		(layer "In3.Cu")
	)
	(gr_line
		(start 25.88514 -431.56886)
		(end 25.88514 -430.451514)
		(stroke
			(width 0.2)
			(type default)
		)
		(layer "In3.Cu")
	)
	(gr_arc
		(start 25.88514 -430.451514)
		(mid 25.273127 -429.83912)
		(end 24.66086 -430.45126)
		(stroke
			(width 0.2)
			(type default)
		)
		(layer "In3.Cu")
	)
	(gr_line
		(start 25.88514 -426.768768)
		(end 25.88514 -425.651422)
		(stroke
			(width 0.2)
			(type default)
		)
		(layer "In3.Cu")
	)
	(gr_arc
		(start 25.88514 -425.651422)
		(mid 25.273127 -425.039028)
		(end 24.66086 -425.651168)
		(stroke
			(width 0.2)
			(type default)
		)
		(layer "In3.Cu")
	)
	(gr_line
		(start 25.88514 -346.168726)
		(end 25.88514 -345.05138)
		(stroke
			(width 0.2)
			(type default)
		)
		(layer "In3.Cu")
	)
	(gr_arc
		(start 25.88514 -345.05138)
		(mid 25.273127 -344.438986)
		(end 24.66086 -345.051126)
		(stroke
			(width 0.2)
			(type default)
		)
		(layer "In3.Cu")
	)
	(gr_line
		(start 25.88514 -333.368904)
		(end 25.88514 -332.251304)
		(stroke
			(width 0.2)
			(type default)
		)
		(layer "In3.Cu")
	)
	(gr_arc
		(start 25.88514 -332.251304)
		(mid 25.273 -331.639164)
		(end 24.66086 -332.251304)
		(stroke
			(width 0.2)
			(type default)
		)
		(layer "In3.Cu")
	)
	(gr_line
		(start 25.88514 -328.568812)
		(end 25.88514 -327.451212)
		(stroke
			(width 0.2)
			(type default)
		)
		(layer "In3.Cu")
	)
	(gr_arc
		(start 25.88514 -327.451212)
		(mid 25.273 -326.839072)
		(end 24.66086 -327.451212)
		(stroke
			(width 0.2)
			(type default)
		)
		(layer "In3.Cu")
	)
	(gr_line
		(start 25.88514 -323.76872)
		(end 25.88514 -322.65112)
		(stroke
			(width 0.2)
			(type default)
		)
		(layer "In3.Cu")
	)
	(gr_arc
		(start 25.88514 -322.65112)
		(mid 25.273 -322.03898)
		(end 24.66086 -322.65112)
		(stroke
			(width 0.2)
			(type default)
		)
		(layer "In3.Cu")
	)
	(gr_line
		(start 25.88514 -243.168678)
		(end 25.88514 -242.051078)
		(stroke
			(width 0.2)
			(type default)
		)
		(layer "In3.Cu")
	)
	(gr_arc
		(start 25.88514 -242.051078)
		(mid 25.273 -241.438938)
		(end 24.66086 -242.051078)
		(stroke
			(width 0.2)
			(type default)
		)
		(layer "In3.Cu")
	)
	(gr_line
		(start 25.88514 -230.368856)
		(end 25.88514 -229.251256)
		(stroke
			(width 0.2)
			(type default)
		)
		(layer "In3.Cu")
	)
	(gr_arc
		(start 25.88514 -229.251256)
		(mid 25.273 -228.639116)
		(end 24.66086 -229.251256)
		(stroke
			(width 0.2)
			(type default)
		)
		(layer "In3.Cu")
	)
	(gr_line
		(start 25.88514 -225.568764)
		(end 25.88514 -224.451164)
		(stroke
			(width 0.2)
			(type default)
		)
		(layer "In3.Cu")
	)
	(gr_arc
		(start 25.88514 -224.451164)
		(mid 25.273 -223.839024)
		(end 24.66086 -224.451164)
		(stroke
			(width 0.2)
			(type default)
		)
		(layer "In3.Cu")
	)
	(gr_line
		(start 25.88514 -220.768672)
		(end 25.88514 -219.651326)
		(stroke
			(width 0.2)
			(type default)
		)
		(layer "In3.Cu")
	)
	(gr_arc
		(start 25.88514 -219.651326)
		(mid 25.273127 -219.038932)
		(end 24.66086 -219.651072)
		(stroke
			(width 0.2)
			(type default)
		)
		(layer "In3.Cu")
	)
	(gr_line
		(start 25.88514 -140.16863)
		(end 25.88514 -139.051284)
		(stroke
			(width 0.2)
			(type default)
		)
		(layer "In3.Cu")
	)
	(gr_arc
		(start 25.88514 -139.051284)
		(mid 25.273127 -138.43889)
		(end 24.66086 -139.05103)
		(stroke
			(width 0.2)
			(type default)
		)
		(layer "In3.Cu")
	)
	(gr_line
		(start 25.88514 -127.368808)
		(end 25.88514 -126.251208)
		(stroke
			(width 0.2)
			(type default)
		)
		(layer "In3.Cu")
	)
	(gr_arc
		(start 25.88514 -126.251208)
		(mid 25.273 -125.639068)
		(end 24.66086 -126.251208)
		(stroke
			(width 0.2)
			(type default)
		)
		(layer "In3.Cu")
	)
	(gr_line
		(start 25.88514 -122.568716)
		(end 25.88514 -121.451116)
		(stroke
			(width 0.2)
			(type default)
		)
		(layer "In3.Cu")
	)
	(gr_arc
		(start 25.88514 -121.451116)
		(mid 25.273 -120.838976)
		(end 24.66086 -121.451116)
		(stroke
			(width 0.2)
			(type default)
		)
		(layer "In3.Cu")
	)
	(gr_line
		(start 25.88514 -117.768624)
		(end 25.88514 -116.651278)
		(stroke
			(width 0.2)
			(type default)
		)
		(layer "In3.Cu")
	)
	(gr_arc
		(start 25.88514 -116.651278)
		(mid 25.273127 -116.038884)
		(end 24.66086 -116.651024)
		(stroke
			(width 0.2)
			(type default)
		)
		(layer "In3.Cu")
	)
	(gr_line
		(start 25.88514 -37.168582)
		(end 25.88514 -36.050982)
		(stroke
			(width 0.2)
			(type default)
		)
		(layer "In3.Cu")
	)
	(gr_arc
		(start 25.88514 -36.050982)
		(mid 25.273 -35.438842)
		(end 24.66086 -36.050982)
		(stroke
			(width 0.2)
			(type default)
		)
		(layer "In3.Cu")
	)
	(gr_line
		(start 25.88514 -24.36876)
		(end 25.88514 -23.25116)
		(stroke
			(width 0.2)
			(type default)
		)
		(layer "In3.Cu")
	)
	(gr_arc
		(start 25.88514 -23.25116)
		(mid 25.273 -22.63902)
		(end 24.66086 -23.25116)
		(stroke
			(width 0.2)
			(type default)
		)
		(layer "In3.Cu")
	)
	(gr_line
		(start 25.88514 -19.568668)
		(end 25.88514 -18.451068)
		(stroke
			(width 0.2)
			(type default)
		)
		(layer "In3.Cu")
	)
	(gr_arc
		(start 25.88514 -18.451068)
		(mid 25.273 -17.838928)
		(end 24.66086 -18.451068)
		(stroke
			(width 0.2)
			(type default)
		)
		(layer "In3.Cu")
	)
	(gr_line
		(start 25.88514 -14.793976)
		(end 25.88514 -13.67663)
		(stroke
			(width 0.2)
			(type default)
		)
		(layer "In3.Cu")
	)
	(gr_arc
		(start 25.88514 -13.67663)
		(mid 25.273127 -13.064236)
		(end 24.66086 -13.676376)
		(stroke
			(width 0.2)
			(type default)
		)
		(layer "In3.Cu")
	)
	(gr_arc
		(start 26.15946 -451.41642)
		(mid 26.67 -451.92696)
		(end 27.18054 -451.41642)
		(stroke
			(width 0.2)
			(type default)
		)
		(layer "In3.Cu")
	)
	(gr_line
		(start 26.15946 -450.60362)
		(end 26.15946 -451.41642)
		(stroke
			(width 0.2)
			(type default)
		)
		(layer "In3.Cu")
	)
	(gr_arc
		(start 26.15946 -438.616344)
		(mid 26.67 -439.126884)
		(end 27.18054 -438.616344)
		(stroke
			(width 0.2)
			(type default)
		)
		(layer "In3.Cu")
	)
	(gr_line
		(start 26.15946 -437.803544)
		(end 26.15946 -438.616344)
		(stroke
			(width 0.2)
			(type default)
		)
		(layer "In3.Cu")
	)
	(gr_arc
		(start 26.15946 -433.816506)
		(mid 26.67 -434.327046)
		(end 27.18054 -433.816506)
		(stroke
			(width 0.2)
			(type default)
		)
		(layer "In3.Cu")
	)
	(gr_line
		(start 26.15946 -433.003706)
		(end 26.15946 -433.816506)
		(stroke
			(width 0.2)
			(type default)
		)
		(layer "In3.Cu")
	)
	(gr_arc
		(start 26.15946 -429.016414)
		(mid 26.67 -429.526954)
		(end 27.18054 -429.016414)
		(stroke
			(width 0.2)
			(type default)
		)
		(layer "In3.Cu")
	)
	(gr_line
		(start 26.15946 -428.203614)
		(end 26.15946 -429.016414)
		(stroke
			(width 0.2)
			(type default)
		)
		(layer "In3.Cu")
	)
	(gr_arc
		(start 26.15946 -348.416118)
		(mid 26.669873 -348.926912)
		(end 27.18054 -348.416372)
		(stroke
			(width 0.2)
			(type default)
		)
		(layer "In3.Cu")
	)
	(gr_line
		(start 26.15946 -347.603572)
		(end 26.15946 -348.416118)
		(stroke
			(width 0.2)
			(type default)
		)
		(layer "In3.Cu")
	)
	(gr_arc
		(start 26.15946 -335.616042)
		(mid 26.669873 -336.126836)
		(end 27.18054 -335.616296)
		(stroke
			(width 0.2)
			(type default)
		)
		(layer "In3.Cu")
	)
	(gr_line
		(start 26.15946 -334.803496)
		(end 26.15946 -335.616042)
		(stroke
			(width 0.2)
			(type default)
		)
		(layer "In3.Cu")
	)
	(gr_arc
		(start 26.15946 -330.816204)
		(mid 26.669873 -331.326998)
		(end 27.18054 -330.816458)
		(stroke
			(width 0.2)
			(type default)
		)
		(layer "In3.Cu")
	)
	(gr_line
		(start 26.15946 -330.003658)
		(end 26.15946 -330.816204)
		(stroke
			(width 0.2)
			(type default)
		)
		(layer "In3.Cu")
	)
	(gr_arc
		(start 26.15946 -326.016112)
		(mid 26.669873 -326.526906)
		(end 27.18054 -326.016366)
		(stroke
			(width 0.2)
			(type default)
		)
		(layer "In3.Cu")
	)
	(gr_line
		(start 26.15946 -325.203566)
		(end 26.15946 -326.016112)
		(stroke
			(width 0.2)
			(type default)
		)
		(layer "In3.Cu")
	)
	(gr_arc
		(start 26.15946 -245.41607)
		(mid 26.669873 -245.926864)
		(end 27.18054 -245.416324)
		(stroke
			(width 0.2)
			(type default)
		)
		(layer "In3.Cu")
	)
	(gr_line
		(start 26.15946 -244.603524)
		(end 26.15946 -245.41607)
		(stroke
			(width 0.2)
			(type default)
		)
		(layer "In3.Cu")
	)
	(gr_arc
		(start 26.15946 -232.615994)
		(mid 26.669873 -233.126788)
		(end 27.18054 -232.616248)
		(stroke
			(width 0.2)
			(type default)
		)
		(layer "In3.Cu")
	)
	(gr_line
		(start 26.15946 -231.803448)
		(end 26.15946 -232.615994)
		(stroke
			(width 0.2)
			(type default)
		)
		(layer "In3.Cu")
	)
	(gr_arc
		(start 26.15946 -227.816156)
		(mid 26.669873 -228.32695)
		(end 27.18054 -227.81641)
		(stroke
			(width 0.2)
			(type default)
		)
		(layer "In3.Cu")
	)
	(gr_line
		(start 26.15946 -227.00361)
		(end 26.15946 -227.816156)
		(stroke
			(width 0.2)
			(type default)
		)
		(layer "In3.Cu")
	)
	(gr_arc
		(start 26.15946 -223.016064)
		(mid 26.669873 -223.526858)
		(end 27.18054 -223.016318)
		(stroke
			(width 0.2)
			(type default)
		)
		(layer "In3.Cu")
	)
	(gr_line
		(start 26.15946 -222.203518)
		(end 26.15946 -223.016064)
		(stroke
			(width 0.2)
			(type default)
		)
		(layer "In3.Cu")
	)
	(gr_arc
		(start 26.15946 -142.416022)
		(mid 26.669873 -142.926816)
		(end 27.18054 -142.416276)
		(stroke
			(width 0.2)
			(type default)
		)
		(layer "In3.Cu")
	)
	(gr_line
		(start 26.15946 -141.603476)
		(end 26.15946 -142.416022)
		(stroke
			(width 0.2)
			(type default)
		)
		(layer "In3.Cu")
	)
	(gr_arc
		(start 26.15946 -129.615946)
		(mid 26.669873 -130.12674)
		(end 27.18054 -129.6162)
		(stroke
			(width 0.2)
			(type default)
		)
		(layer "In3.Cu")
	)
	(gr_line
		(start 26.15946 -128.8034)
		(end 26.15946 -129.615946)
		(stroke
			(width 0.2)
			(type default)
		)
		(layer "In3.Cu")
	)
	(gr_arc
		(start 26.15946 -124.816108)
		(mid 26.669873 -125.326902)
		(end 27.18054 -124.816362)
		(stroke
			(width 0.2)
			(type default)
		)
		(layer "In3.Cu")
	)
	(gr_line
		(start 26.15946 -124.003562)
		(end 26.15946 -124.816108)
		(stroke
			(width 0.2)
			(type default)
		)
		(layer "In3.Cu")
	)
	(gr_arc
		(start 26.15946 -120.016016)
		(mid 26.669873 -120.52681)
		(end 27.18054 -120.01627)
		(stroke
			(width 0.2)
			(type default)
		)
		(layer "In3.Cu")
	)
	(gr_line
		(start 26.15946 -119.20347)
		(end 26.15946 -120.016016)
		(stroke
			(width 0.2)
			(type default)
		)
		(layer "In3.Cu")
	)
	(gr_arc
		(start 26.15946 -39.415974)
		(mid 26.669873 -39.926768)
		(end 27.18054 -39.416228)
		(stroke
			(width 0.2)
			(type default)
		)
		(layer "In3.Cu")
	)
	(gr_line
		(start 26.15946 -38.603428)
		(end 26.15946 -39.415974)
		(stroke
			(width 0.2)
			(type default)
		)
		(layer "In3.Cu")
	)
	(gr_arc
		(start 26.15946 -26.615898)
		(mid 26.669873 -27.126692)
		(end 27.18054 -26.616152)
		(stroke
			(width 0.2)
			(type default)
		)
		(layer "In3.Cu")
	)
	(gr_line
		(start 26.15946 -25.803352)
		(end 26.15946 -26.615898)
		(stroke
			(width 0.2)
			(type default)
		)
		(layer "In3.Cu")
	)
	(gr_arc
		(start 26.15946 -21.81606)
		(mid 26.669873 -22.326854)
		(end 27.18054 -21.816314)
		(stroke
			(width 0.2)
			(type default)
		)
		(layer "In3.Cu")
	)
	(gr_line
		(start 26.15946 -21.003514)
		(end 26.15946 -21.81606)
		(stroke
			(width 0.2)
			(type default)
		)
		(layer "In3.Cu")
	)
	(gr_arc
		(start 26.15946 -17.015968)
		(mid 26.669873 -17.526762)
		(end 27.18054 -17.016222)
		(stroke
			(width 0.2)
			(type default)
		)
		(layer "In3.Cu")
	)
	(gr_line
		(start 26.15946 -16.203422)
		(end 26.15946 -17.015968)
		(stroke
			(width 0.2)
			(type default)
		)
		(layer "In3.Cu")
	)
	(gr_line
		(start 27.18054 -451.41642)
		(end 27.18054 -450.603874)
		(stroke
			(width 0.2)
			(type default)
		)
		(layer "In3.Cu")
	)
	(gr_arc
		(start 27.18054 -450.603874)
		(mid 26.670127 -450.09308)
		(end 26.15946 -450.60362)
		(stroke
			(width 0.2)
			(type default)
		)
		(layer "In3.Cu")
	)
	(gr_line
		(start 27.18054 -438.616344)
		(end 27.18054 -437.803798)
		(stroke
			(width 0.2)
			(type default)
		)
		(layer "In3.Cu")
	)
	(gr_arc
		(start 27.18054 -437.803798)
		(mid 26.670127 -437.293004)
		(end 26.15946 -437.803544)
		(stroke
			(width 0.2)
			(type default)
		)
		(layer "In3.Cu")
	)
	(gr_line
		(start 27.18054 -433.816506)
		(end 27.18054 -433.00396)
		(stroke
			(width 0.2)
			(type default)
		)
		(layer "In3.Cu")
	)
	(gr_arc
		(start 27.18054 -433.00396)
		(mid 26.670127 -432.493166)
		(end 26.15946 -433.003706)
		(stroke
			(width 0.2)
			(type default)
		)
		(layer "In3.Cu")
	)
	(gr_line
		(start 27.18054 -429.016414)
		(end 27.18054 -428.203868)
		(stroke
			(width 0.2)
			(type default)
		)
		(layer "In3.Cu")
	)
	(gr_arc
		(start 27.18054 -428.203868)
		(mid 26.670127 -427.693074)
		(end 26.15946 -428.203614)
		(stroke
			(width 0.2)
			(type default)
		)
		(layer "In3.Cu")
	)
	(gr_line
		(start 27.18054 -348.416372)
		(end 27.18054 -347.603572)
		(stroke
			(width 0.2)
			(type default)
		)
		(layer "In3.Cu")
	)
	(gr_arc
		(start 27.18054 -347.603572)
		(mid 26.67 -347.093032)
		(end 26.15946 -347.603572)
		(stroke
			(width 0.2)
			(type default)
		)
		(layer "In3.Cu")
	)
	(gr_line
		(start 27.18054 -335.616296)
		(end 27.18054 -334.803496)
		(stroke
			(width 0.2)
			(type default)
		)
		(layer "In3.Cu")
	)
	(gr_arc
		(start 27.18054 -334.803496)
		(mid 26.67 -334.292956)
		(end 26.15946 -334.803496)
		(stroke
			(width 0.2)
			(type default)
		)
		(layer "In3.Cu")
	)
	(gr_line
		(start 27.18054 -330.816458)
		(end 27.18054 -330.003658)
		(stroke
			(width 0.2)
			(type default)
		)
		(layer "In3.Cu")
	)
	(gr_arc
		(start 27.18054 -330.003658)
		(mid 26.67 -329.493118)
		(end 26.15946 -330.003658)
		(stroke
			(width 0.2)
			(type default)
		)
		(layer "In3.Cu")
	)
	(gr_line
		(start 27.18054 -326.016366)
		(end 27.18054 -325.203566)
		(stroke
			(width 0.2)
			(type default)
		)
		(layer "In3.Cu")
	)
	(gr_arc
		(start 27.18054 -325.203566)
		(mid 26.67 -324.693026)
		(end 26.15946 -325.203566)
		(stroke
			(width 0.2)
			(type default)
		)
		(layer "In3.Cu")
	)
	(gr_line
		(start 27.18054 -245.416324)
		(end 27.18054 -244.603524)
		(stroke
			(width 0.2)
			(type default)
		)
		(layer "In3.Cu")
	)
	(gr_arc
		(start 27.18054 -244.603524)
		(mid 26.67 -244.092984)
		(end 26.15946 -244.603524)
		(stroke
			(width 0.2)
			(type default)
		)
		(layer "In3.Cu")
	)
	(gr_line
		(start 27.18054 -232.616248)
		(end 27.18054 -231.803448)
		(stroke
			(width 0.2)
			(type default)
		)
		(layer "In3.Cu")
	)
	(gr_arc
		(start 27.18054 -231.803448)
		(mid 26.67 -231.292908)
		(end 26.15946 -231.803448)
		(stroke
			(width 0.2)
			(type default)
		)
		(layer "In3.Cu")
	)
	(gr_line
		(start 27.18054 -227.81641)
		(end 27.18054 -227.00361)
		(stroke
			(width 0.2)
			(type default)
		)
		(layer "In3.Cu")
	)
	(gr_arc
		(start 27.18054 -227.00361)
		(mid 26.67 -226.49307)
		(end 26.15946 -227.00361)
		(stroke
			(width 0.2)
			(type default)
		)
		(layer "In3.Cu")
	)
	(gr_line
		(start 27.18054 -223.016318)
		(end 27.18054 -222.203518)
		(stroke
			(width 0.2)
			(type default)
		)
		(layer "In3.Cu")
	)
	(gr_arc
		(start 27.18054 -222.203518)
		(mid 26.67 -221.692978)
		(end 26.15946 -222.203518)
		(stroke
			(width 0.2)
			(type default)
		)
		(layer "In3.Cu")
	)
	(gr_line
		(start 27.18054 -142.416276)
		(end 27.18054 -141.603476)
		(stroke
			(width 0.2)
			(type default)
		)
		(layer "In3.Cu")
	)
	(gr_arc
		(start 27.18054 -141.603476)
		(mid 26.67 -141.092936)
		(end 26.15946 -141.603476)
		(stroke
			(width 0.2)
			(type default)
		)
		(layer "In3.Cu")
	)
	(gr_line
		(start 27.18054 -129.6162)
		(end 27.18054 -128.8034)
		(stroke
			(width 0.2)
			(type default)
		)
		(layer "In3.Cu")
	)
	(gr_arc
		(start 27.18054 -128.8034)
		(mid 26.67 -128.29286)
		(end 26.15946 -128.8034)
		(stroke
			(width 0.2)
			(type default)
		)
		(layer "In3.Cu")
	)
	(gr_line
		(start 27.18054 -124.816362)
		(end 27.18054 -124.003562)
		(stroke
			(width 0.2)
			(type default)
		)
		(layer "In3.Cu")
	)
	(gr_arc
		(start 27.18054 -124.003562)
		(mid 26.67 -123.493022)
		(end 26.15946 -124.003562)
		(stroke
			(width 0.2)
			(type default)
		)
		(layer "In3.Cu")
	)
	(gr_line
		(start 27.18054 -120.01627)
		(end 27.18054 -119.20347)
		(stroke
			(width 0.2)
			(type default)
		)
		(layer "In3.Cu")
	)
	(gr_arc
		(start 27.18054 -119.20347)
		(mid 26.67 -118.69293)
		(end 26.15946 -119.20347)
		(stroke
			(width 0.2)
			(type default)
		)
		(layer "In3.Cu")
	)
	(gr_line
		(start 27.18054 -39.416228)
		(end 27.18054 -38.603428)
		(stroke
			(width 0.2)
			(type default)
		)
		(layer "In3.Cu")
	)
	(gr_arc
		(start 27.18054 -38.603428)
		(mid 26.67 -38.092888)
		(end 26.15946 -38.603428)
		(stroke
			(width 0.2)
			(type default)
		)
		(layer "In3.Cu")
	)
	(gr_line
		(start 27.18054 -26.616152)
		(end 27.18054 -25.803352)
		(stroke
			(width 0.2)
			(type default)
		)
		(layer "In3.Cu")
	)
	(gr_arc
		(start 27.18054 -25.803352)
		(mid 26.67 -25.292812)
		(end 26.15946 -25.803352)
		(stroke
			(width 0.2)
			(type default)
		)
		(layer "In3.Cu")
	)
	(gr_line
		(start 27.18054 -21.816314)
		(end 27.18054 -21.003514)
		(stroke
			(width 0.2)
			(type default)
		)
		(layer "In3.Cu")
	)
	(gr_arc
		(start 27.18054 -21.003514)
		(mid 26.67 -20.492974)
		(end 26.15946 -21.003514)
		(stroke
			(width 0.2)
			(type default)
		)
		(layer "In3.Cu")
	)
	(gr_line
		(start 27.18054 -17.016222)
		(end 27.18054 -16.203422)
		(stroke
			(width 0.2)
			(type default)
		)
		(layer "In3.Cu")
	)
	(gr_arc
		(start 27.18054 -16.203422)
		(mid 26.67 -15.692882)
		(end 26.15946 -16.203422)
		(stroke
			(width 0.2)
			(type default)
		)
		(layer "In3.Cu")
	)
	(gr_line
		(start 30.80004 0)
		(end 32.33674 -3.019552)
		(stroke
			(width 1.524)
			(type default)
		)
		(layer "In3.Cu")
	)
	(gr_arc
		(start 30.98546 -136.416542)
		(mid 31.496 -136.927082)
		(end 32.00654 -136.416542)
		(stroke
			(width 0.2)
			(type default)
		)
		(layer "In3.Cu")
	)
	(gr_line
		(start 30.98546 -135.603742)
		(end 30.98546 -136.416542)
		(stroke
			(width 0.2)
			(type default)
		)
		(layer "In3.Cu")
	)
	(gr_arc
		(start 30.98546 -33.415986)
		(mid 31.496 -33.926526)
		(end 32.00654 -33.415986)
		(stroke
			(width 0.2)
			(type default)
		)
		(layer "In3.Cu")
	)
	(gr_line
		(start 30.98546 -32.603186)
		(end 30.98546 -33.415986)
		(stroke
			(width 0.2)
			(type default)
		)
		(layer "In3.Cu")
	)
	(gr_arc
		(start 31.23946 -445.397636)
		(mid 31.75 -445.908176)
		(end 32.26054 -445.397636)
		(stroke
			(width 0.2)
			(type default)
		)
		(layer "In3.Cu")
	)
	(gr_line
		(start 31.23946 -444.584836)
		(end 31.23946 -445.397636)
		(stroke
			(width 0.2)
			(type default)
		)
		(layer "In3.Cu")
	)
	(gr_line
		(start 32.00654 -136.416542)
		(end 32.00654 -135.603996)
		(stroke
			(width 0.2)
			(type default)
		)
		(layer "In3.Cu")
	)
	(gr_arc
		(start 32.00654 -135.603996)
		(mid 31.496127 -135.093202)
		(end 30.98546 -135.603742)
		(stroke
			(width 0.2)
			(type default)
		)
		(layer "In3.Cu")
	)
	(gr_line
		(start 32.00654 -33.415986)
		(end 32.00654 -32.60344)
		(stroke
			(width 0.2)
			(type default)
		)
		(layer "In3.Cu")
	)
	(gr_arc
		(start 32.00654 -32.60344)
		(mid 31.496127 -32.092646)
		(end 30.98546 -32.603186)
		(stroke
			(width 0.2)
			(type default)
		)
		(layer "In3.Cu")
	)
	(gr_line
		(start 32.26054 -445.397636)
		(end 32.26054 -444.58509)
		(stroke
			(width 0.2)
			(type default)
		)
		(layer "In3.Cu")
	)
	(gr_arc
		(start 32.26054 -444.58509)
		(mid 31.750127 -444.074296)
		(end 31.23946 -444.584836)
		(stroke
			(width 0.2)
			(type default)
		)
		(layer "In3.Cu")
	)
	(gr_arc
		(start 32.38246 -342.397334)
		(mid 32.893 -342.907874)
		(end 33.40354 -342.397334)
		(stroke
			(width 0.2)
			(type default)
		)
		(layer "In3.Cu")
	)
	(gr_line
		(start 32.38246 -341.584534)
		(end 32.38246 -342.397334)
		(stroke
			(width 0.2)
			(type default)
		)
		(layer "In3.Cu")
	)
	(gr_arc
		(start 32.500062 -4.500118)
		(mid 34.000186 -6.000242)
		(end 35.500056 -4.500118)
		(stroke
			(width 1.524)
			(type default)
		)
		(layer "In3.Cu")
	)
	(gr_arc
		(start 32.500062 -3.700018)
		(mid 32.458636 -3.350129)
		(end 32.33674 -3.019552)
		(stroke
			(width 1.524)
			(type default)
		)
		(layer "In3.Cu")
	)
	(gr_line
		(start 32.500062 -3.700018)
		(end 32.500062 -4.500118)
		(stroke
			(width 1.524)
			(type default)
		)
		(layer "In3.Cu")
	)
	(gr_line
		(start 33.40354 -342.397334)
		(end 33.40354 -341.584788)
		(stroke
			(width 0.2)
			(type default)
		)
		(layer "In3.Cu")
	)
	(gr_arc
		(start 33.40354 -341.584788)
		(mid 32.893127 -341.073994)
		(end 32.38246 -341.584534)
		(stroke
			(width 0.2)
			(type default)
		)
		(layer "In3.Cu")
	)
	(gr_arc
		(start 34.81959 -489.796328)
		(mid 35.330003 -490.307122)
		(end 35.84067 -489.796582)
		(stroke
			(width 0.2)
			(type default)
		)
		(layer "In3.Cu")
	)
	(gr_line
		(start 34.81959 -488.983782)
		(end 34.81959 -489.796328)
		(stroke
			(width 0.2)
			(type default)
		)
		(layer "In3.Cu")
	)
	(gr_arc
		(start 34.81959 -484.996236)
		(mid 35.330003 -485.50703)
		(end 35.84067 -484.99649)
		(stroke
			(width 0.2)
			(type default)
		)
		(layer "In3.Cu")
	)
	(gr_line
		(start 34.81959 -484.18369)
		(end 34.81959 -484.996236)
		(stroke
			(width 0.2)
			(type default)
		)
		(layer "In3.Cu")
	)
	(gr_arc
		(start 34.81959 -480.196398)
		(mid 35.330003 -480.707192)
		(end 35.84067 -480.196652)
		(stroke
			(width 0.2)
			(type default)
		)
		(layer "In3.Cu")
	)
	(gr_line
		(start 34.81959 -479.383852)
		(end 34.81959 -480.196398)
		(stroke
			(width 0.2)
			(type default)
		)
		(layer "In3.Cu")
	)
	(gr_arc
		(start 34.81959 -467.396322)
		(mid 35.330003 -467.907116)
		(end 35.84067 -467.396576)
		(stroke
			(width 0.2)
			(type default)
		)
		(layer "In3.Cu")
	)
	(gr_line
		(start 34.81959 -466.583776)
		(end 34.81959 -467.396322)
		(stroke
			(width 0.2)
			(type default)
		)
		(layer "In3.Cu")
	)
	(gr_arc
		(start 34.81959 -386.796534)
		(mid 35.33013 -387.307074)
		(end 35.84067 -386.796534)
		(stroke
			(width 0.2)
			(type default)
		)
		(layer "In3.Cu")
	)
	(gr_line
		(start 34.81959 -385.983734)
		(end 34.81959 -386.796534)
		(stroke
			(width 0.2)
			(type default)
		)
		(layer "In3.Cu")
	)
	(gr_arc
		(start 34.81959 -381.996442)
		(mid 35.33013 -382.506982)
		(end 35.84067 -381.996442)
		(stroke
			(width 0.2)
			(type default)
		)
		(layer "In3.Cu")
	)
	(gr_line
		(start 34.81959 -381.183642)
		(end 34.81959 -381.996442)
		(stroke
			(width 0.2)
			(type default)
		)
		(layer "In3.Cu")
	)
	(gr_arc
		(start 34.81959 -377.196604)
		(mid 35.33013 -377.707144)
		(end 35.84067 -377.196604)
		(stroke
			(width 0.2)
			(type default)
		)
		(layer "In3.Cu")
	)
	(gr_line
		(start 34.81959 -376.383804)
		(end 34.81959 -377.196604)
		(stroke
			(width 0.2)
			(type default)
		)
		(layer "In3.Cu")
	)
	(gr_arc
		(start 34.81959 -364.396528)
		(mid 35.33013 -364.907068)
		(end 35.84067 -364.396528)
		(stroke
			(width 0.2)
			(type default)
		)
		(layer "In3.Cu")
	)
	(gr_line
		(start 34.81959 -363.583728)
		(end 34.81959 -364.396528)
		(stroke
			(width 0.2)
			(type default)
		)
		(layer "In3.Cu")
	)
	(gr_arc
		(start 34.81959 -283.796486)
		(mid 35.33013 -284.307026)
		(end 35.84067 -283.796486)
		(stroke
			(width 0.2)
			(type default)
		)
		(layer "In3.Cu")
	)
	(gr_line
		(start 34.81959 -282.983686)
		(end 34.81959 -283.796486)
		(stroke
			(width 0.2)
			(type default)
		)
		(layer "In3.Cu")
	)
	(gr_arc
		(start 34.81959 -278.996394)
		(mid 35.33013 -279.506934)
		(end 35.84067 -278.996394)
		(stroke
			(width 0.2)
			(type default)
		)
		(layer "In3.Cu")
	)
	(gr_line
		(start 34.81959 -278.183594)
		(end 34.81959 -278.996394)
		(stroke
			(width 0.2)
			(type default)
		)
		(layer "In3.Cu")
	)
	(gr_arc
		(start 34.81959 -274.196556)
		(mid 35.33013 -274.707096)
		(end 35.84067 -274.196556)
		(stroke
			(width 0.2)
			(type default)
		)
		(layer "In3.Cu")
	)
	(gr_line
		(start 34.81959 -273.383756)
		(end 34.81959 -274.196556)
		(stroke
			(width 0.2)
			(type default)
		)
		(layer "In3.Cu")
	)
	(gr_arc
		(start 34.81959 -261.39648)
		(mid 35.33013 -261.90702)
		(end 35.84067 -261.39648)
		(stroke
			(width 0.2)
			(type default)
		)
		(layer "In3.Cu")
	)
	(gr_line
		(start 34.81959 -260.58368)
		(end 34.81959 -261.39648)
		(stroke
			(width 0.2)
			(type default)
		)
		(layer "In3.Cu")
	)
	(gr_arc
		(start 34.81959 -180.796438)
		(mid 35.33013 -181.306978)
		(end 35.84067 -180.796438)
		(stroke
			(width 0.2)
			(type default)
		)
		(layer "In3.Cu")
	)
	(gr_line
		(start 34.81959 -179.983638)
		(end 34.81959 -180.796438)
		(stroke
			(width 0.2)
			(type default)
		)
		(layer "In3.Cu")
	)
	(gr_arc
		(start 34.81959 -175.996346)
		(mid 35.33013 -176.506886)
		(end 35.84067 -175.996346)
		(stroke
			(width 0.2)
			(type default)
		)
		(layer "In3.Cu")
	)
	(gr_line
		(start 34.81959 -175.183546)
		(end 34.81959 -175.996346)
		(stroke
			(width 0.2)
			(type default)
		)
		(layer "In3.Cu")
	)
	(gr_arc
		(start 34.81959 -171.196508)
		(mid 35.33013 -171.707048)
		(end 35.84067 -171.196508)
		(stroke
			(width 0.2)
			(type default)
		)
		(layer "In3.Cu")
	)
	(gr_line
		(start 34.81959 -170.383708)
		(end 34.81959 -171.196508)
		(stroke
			(width 0.2)
			(type default)
		)
		(layer "In3.Cu")
	)
	(gr_arc
		(start 34.81959 -158.396432)
		(mid 35.33013 -158.906972)
		(end 35.84067 -158.396432)
		(stroke
			(width 0.2)
			(type default)
		)
		(layer "In3.Cu")
	)
	(gr_line
		(start 34.81959 -157.583632)
		(end 34.81959 -158.396432)
		(stroke
			(width 0.2)
			(type default)
		)
		(layer "In3.Cu")
	)
	(gr_arc
		(start 34.81959 -77.79639)
		(mid 35.33013 -78.30693)
		(end 35.84067 -77.79639)
		(stroke
			(width 0.2)
			(type default)
		)
		(layer "In3.Cu")
	)
	(gr_line
		(start 34.81959 -76.98359)
		(end 34.81959 -77.79639)
		(stroke
			(width 0.2)
			(type default)
		)
		(layer "In3.Cu")
	)
	(gr_arc
		(start 34.81959 -72.996298)
		(mid 35.33013 -73.506838)
		(end 35.84067 -72.996298)
		(stroke
			(width 0.2)
			(type default)
		)
		(layer "In3.Cu")
	)
	(gr_line
		(start 34.81959 -72.183498)
		(end 34.81959 -72.996298)
		(stroke
			(width 0.2)
			(type default)
		)
		(layer "In3.Cu")
	)
	(gr_arc
		(start 34.81959 -68.19646)
		(mid 35.33013 -68.707)
		(end 35.84067 -68.19646)
		(stroke
			(width 0.2)
			(type default)
		)
		(layer "In3.Cu")
	)
	(gr_line
		(start 34.81959 -67.38366)
		(end 34.81959 -68.19646)
		(stroke
			(width 0.2)
			(type default)
		)
		(layer "In3.Cu")
	)
	(gr_arc
		(start 34.81959 -55.396384)
		(mid 35.33013 -55.906924)
		(end 35.84067 -55.396384)
		(stroke
			(width 0.2)
			(type default)
		)
		(layer "In3.Cu")
	)
	(gr_line
		(start 34.81959 -54.583584)
		(end 34.81959 -55.396384)
		(stroke
			(width 0.2)
			(type default)
		)
		(layer "In3.Cu")
	)
	(gr_line
		(start 35.500056 -4.500118)
		(end 35.500056 -3.700018)
		(stroke
			(width 1.524)
			(type default)
		)
		(layer "In3.Cu")
	)
	(gr_arc
		(start 35.663124 -3.019552)
		(mid 35.541364 -3.350145)
		(end 35.500056 -3.700018)
		(stroke
			(width 1.524)
			(type default)
		)
		(layer "In3.Cu")
	)
	(gr_line
		(start 35.663124 -3.019552)
		(end 37.200078 0)
		(stroke
			(width 1.524)
			(type default)
		)
		(layer "In3.Cu")
	)
	(gr_line
		(start 35.84067 -489.796582)
		(end 35.84067 -488.983782)
		(stroke
			(width 0.2)
			(type default)
		)
		(layer "In3.Cu")
	)
	(gr_arc
		(start 35.84067 -488.983782)
		(mid 35.33013 -488.473242)
		(end 34.81959 -488.983782)
		(stroke
			(width 0.2)
			(type default)
		)
		(layer "In3.Cu")
	)
	(gr_line
		(start 35.84067 -484.99649)
		(end 35.84067 -484.18369)
		(stroke
			(width 0.2)
			(type default)
		)
		(layer "In3.Cu")
	)
	(gr_arc
		(start 35.84067 -484.18369)
		(mid 35.33013 -483.67315)
		(end 34.81959 -484.18369)
		(stroke
			(width 0.2)
			(type default)
		)
		(layer "In3.Cu")
	)
	(gr_line
		(start 35.84067 -480.196652)
		(end 35.84067 -479.383852)
		(stroke
			(width 0.2)
			(type default)
		)
		(layer "In3.Cu")
	)
	(gr_arc
		(start 35.84067 -479.383852)
		(mid 35.33013 -478.873312)
		(end 34.81959 -479.383852)
		(stroke
			(width 0.2)
			(type default)
		)
		(layer "In3.Cu")
	)
	(gr_line
		(start 35.84067 -467.396576)
		(end 35.84067 -466.583776)
		(stroke
			(width 0.2)
			(type default)
		)
		(layer "In3.Cu")
	)
	(gr_arc
		(start 35.84067 -466.583776)
		(mid 35.33013 -466.073236)
		(end 34.81959 -466.583776)
		(stroke
			(width 0.2)
			(type default)
		)
		(layer "In3.Cu")
	)
	(gr_line
		(start 35.84067 -386.796534)
		(end 35.84067 -385.983988)
		(stroke
			(width 0.2)
			(type default)
		)
		(layer "In3.Cu")
	)
	(gr_arc
		(start 35.84067 -385.983988)
		(mid 35.330257 -385.473194)
		(end 34.81959 -385.983734)
		(stroke
			(width 0.2)
			(type default)
		)
		(layer "In3.Cu")
	)
	(gr_line
		(start 35.84067 -381.996442)
		(end 35.84067 -381.183896)
		(stroke
			(width 0.2)
			(type default)
		)
		(layer "In3.Cu")
	)
	(gr_arc
		(start 35.84067 -381.183896)
		(mid 35.330257 -380.673102)
		(end 34.81959 -381.183642)
		(stroke
			(width 0.2)
			(type default)
		)
		(layer "In3.Cu")
	)
	(gr_line
		(start 35.84067 -377.196604)
		(end 35.84067 -376.384058)
		(stroke
			(width 0.2)
			(type default)
		)
		(layer "In3.Cu")
	)
	(gr_arc
		(start 35.84067 -376.384058)
		(mid 35.330257 -375.873264)
		(end 34.81959 -376.383804)
		(stroke
			(width 0.2)
			(type default)
		)
		(layer "In3.Cu")
	)
	(gr_line
		(start 35.84067 -364.396528)
		(end 35.84067 -363.583982)
		(stroke
			(width 0.2)
			(type default)
		)
		(layer "In3.Cu")
	)
	(gr_arc
		(start 35.84067 -363.583982)
		(mid 35.330257 -363.073188)
		(end 34.81959 -363.583728)
		(stroke
			(width 0.2)
			(type default)
		)
		(layer "In3.Cu")
	)
	(gr_line
		(start 35.84067 -283.796486)
		(end 35.84067 -282.98394)
		(stroke
			(width 0.2)
			(type default)
		)
		(layer "In3.Cu")
	)
	(gr_arc
		(start 35.84067 -282.98394)
		(mid 35.330257 -282.473146)
		(end 34.81959 -282.983686)
		(stroke
			(width 0.2)
			(type default)
		)
		(layer "In3.Cu")
	)
	(gr_line
		(start 35.84067 -278.996394)
		(end 35.84067 -278.183848)
		(stroke
			(width 0.2)
			(type default)
		)
		(layer "In3.Cu")
	)
	(gr_arc
		(start 35.84067 -278.183848)
		(mid 35.330257 -277.673054)
		(end 34.81959 -278.183594)
		(stroke
			(width 0.2)
			(type default)
		)
		(layer "In3.Cu")
	)
	(gr_line
		(start 35.84067 -274.196556)
		(end 35.84067 -273.38401)
		(stroke
			(width 0.2)
			(type default)
		)
		(layer "In3.Cu")
	)
	(gr_arc
		(start 35.84067 -273.38401)
		(mid 35.330257 -272.873216)
		(end 34.81959 -273.383756)
		(stroke
			(width 0.2)
			(type default)
		)
		(layer "In3.Cu")
	)
	(gr_line
		(start 35.84067 -261.39648)
		(end 35.84067 -260.583934)
		(stroke
			(width 0.2)
			(type default)
		)
		(layer "In3.Cu")
	)
	(gr_arc
		(start 35.84067 -260.583934)
		(mid 35.330257 -260.07314)
		(end 34.81959 -260.58368)
		(stroke
			(width 0.2)
			(type default)
		)
		(layer "In3.Cu")
	)
	(gr_line
		(start 35.84067 -180.796438)
		(end 35.84067 -179.983892)
		(stroke
			(width 0.2)
			(type default)
		)
		(layer "In3.Cu")
	)
	(gr_arc
		(start 35.84067 -179.983892)
		(mid 35.330257 -179.473098)
		(end 34.81959 -179.983638)
		(stroke
			(width 0.2)
			(type default)
		)
		(layer "In3.Cu")
	)
	(gr_line
		(start 35.84067 -175.996346)
		(end 35.84067 -175.1838)
		(stroke
			(width 0.2)
			(type default)
		)
		(layer "In3.Cu")
	)
	(gr_arc
		(start 35.84067 -175.1838)
		(mid 35.330257 -174.673006)
		(end 34.81959 -175.183546)
		(stroke
			(width 0.2)
			(type default)
		)
		(layer "In3.Cu")
	)
	(gr_line
		(start 35.84067 -171.196508)
		(end 35.84067 -170.383962)
		(stroke
			(width 0.2)
			(type default)
		)
		(layer "In3.Cu")
	)
	(gr_arc
		(start 35.84067 -170.383962)
		(mid 35.330257 -169.873168)
		(end 34.81959 -170.383708)
		(stroke
			(width 0.2)
			(type default)
		)
		(layer "In3.Cu")
	)
	(gr_line
		(start 35.84067 -158.396432)
		(end 35.84067 -157.583886)
		(stroke
			(width 0.2)
			(type default)
		)
		(layer "In3.Cu")
	)
	(gr_arc
		(start 35.84067 -157.583886)
		(mid 35.330257 -157.073092)
		(end 34.81959 -157.583632)
		(stroke
			(width 0.2)
			(type default)
		)
		(layer "In3.Cu")
	)
	(gr_line
		(start 35.84067 -77.79639)
		(end 35.84067 -76.983844)
		(stroke
			(width 0.2)
			(type default)
		)
		(layer "In3.Cu")
	)
	(gr_arc
		(start 35.84067 -76.983844)
		(mid 35.330257 -76.47305)
		(end 34.81959 -76.98359)
		(stroke
			(width 0.2)
			(type default)
		)
		(layer "In3.Cu")
	)
	(gr_line
		(start 35.84067 -72.996298)
		(end 35.84067 -72.183752)
		(stroke
			(width 0.2)
			(type default)
		)
		(layer "In3.Cu")
	)
	(gr_arc
		(start 35.84067 -72.183752)
		(mid 35.330257 -71.672958)
		(end 34.81959 -72.183498)
		(stroke
			(width 0.2)
			(type default)
		)
		(layer "In3.Cu")
	)
	(gr_line
		(start 35.84067 -68.19646)
		(end 35.84067 -67.383914)
		(stroke
			(width 0.2)
			(type default)
		)
		(layer "In3.Cu")
	)
	(gr_arc
		(start 35.84067 -67.383914)
		(mid 35.330257 -66.87312)
		(end 34.81959 -67.38366)
		(stroke
			(width 0.2)
			(type default)
		)
		(layer "In3.Cu")
	)
	(gr_line
		(start 35.84067 -55.396384)
		(end 35.84067 -54.583838)
		(stroke
			(width 0.2)
			(type default)
		)
		(layer "In3.Cu")
	)
	(gr_arc
		(start 35.84067 -54.583838)
		(mid 35.330257 -54.073044)
		(end 34.81959 -54.583584)
		(stroke
			(width 0.2)
			(type default)
		)
		(layer "In3.Cu")
	)
	(gr_arc
		(start 36.11499 -492.348774)
		(mid 36.727003 -492.961168)
		(end 37.33927 -492.349028)
		(stroke
			(width 0.2)
			(type default)
		)
		(layer "In3.Cu")
	)
	(gr_line
		(start 36.11499 -491.231428)
		(end 36.11499 -492.348774)
		(stroke
			(width 0.2)
			(type default)
		)
		(layer "In3.Cu")
	)
	(gr_arc
		(start 36.11499 -487.548936)
		(mid 36.72713 -488.161076)
		(end 37.33927 -487.548936)
		(stroke
			(width 0.2)
			(type default)
		)
		(layer "In3.Cu")
	)
	(gr_line
		(start 36.11499 -486.431336)
		(end 36.11499 -487.548936)
		(stroke
			(width 0.2)
			(type default)
		)
		(layer "In3.Cu")
	)
	(gr_arc
		(start 36.11499 -482.74859)
		(mid 36.727003 -483.360984)
		(end 37.33927 -482.748844)
		(stroke
			(width 0.2)
			(type default)
		)
		(layer "In3.Cu")
	)
	(gr_line
		(start 36.11499 -481.631244)
		(end 36.11499 -482.74859)
		(stroke
			(width 0.2)
			(type default)
		)
		(layer "In3.Cu")
	)
	(gr_arc
		(start 36.11499 -469.948768)
		(mid 36.727003 -470.561162)
		(end 37.33927 -469.949022)
		(stroke
			(width 0.2)
			(type default)
		)
		(layer "In3.Cu")
	)
	(gr_line
		(start 36.11499 -468.831422)
		(end 36.11499 -469.948768)
		(stroke
			(width 0.2)
			(type default)
		)
		(layer "In3.Cu")
	)
	(gr_arc
		(start 36.11499 -389.34898)
		(mid 36.72713 -389.96112)
		(end 37.33927 -389.34898)
		(stroke
			(width 0.2)
			(type default)
		)
		(layer "In3.Cu")
	)
	(gr_line
		(start 36.11499 -388.23138)
		(end 36.11499 -389.34898)
		(stroke
			(width 0.2)
			(type default)
		)
		(layer "In3.Cu")
	)
	(gr_arc
		(start 36.11499 -384.548888)
		(mid 36.72713 -385.161028)
		(end 37.33927 -384.548888)
		(stroke
			(width 0.2)
			(type default)
		)
		(layer "In3.Cu")
	)
	(gr_line
		(start 36.11499 -383.431288)
		(end 36.11499 -384.548888)
		(stroke
			(width 0.2)
			(type default)
		)
		(layer "In3.Cu")
	)
	(gr_arc
		(start 36.11499 -379.748796)
		(mid 36.72713 -380.360936)
		(end 37.33927 -379.748796)
		(stroke
			(width 0.2)
			(type default)
		)
		(layer "In3.Cu")
	)
	(gr_line
		(start 36.11499 -378.631196)
		(end 36.11499 -379.748796)
		(stroke
			(width 0.2)
			(type default)
		)
		(layer "In3.Cu")
	)
	(gr_arc
		(start 36.11499 -366.948974)
		(mid 36.72713 -367.561114)
		(end 37.33927 -366.948974)
		(stroke
			(width 0.2)
			(type default)
		)
		(layer "In3.Cu")
	)
	(gr_line
		(start 36.11499 -365.831374)
		(end 36.11499 -366.948974)
		(stroke
			(width 0.2)
			(type default)
		)
		(layer "In3.Cu")
	)
	(gr_arc
		(start 36.11499 -286.348932)
		(mid 36.72713 -286.961072)
		(end 37.33927 -286.348932)
		(stroke
			(width 0.2)
			(type default)
		)
		(layer "In3.Cu")
	)
	(gr_line
		(start 36.11499 -285.231332)
		(end 36.11499 -286.348932)
		(stroke
			(width 0.2)
			(type default)
		)
		(layer "In3.Cu")
	)
	(gr_arc
		(start 36.11499 -281.54884)
		(mid 36.72713 -282.16098)
		(end 37.33927 -281.54884)
		(stroke
			(width 0.2)
			(type default)
		)
		(layer "In3.Cu")
	)
	(gr_line
		(start 36.11499 -280.43124)
		(end 36.11499 -281.54884)
		(stroke
			(width 0.2)
			(type default)
		)
		(layer "In3.Cu")
	)
	(gr_arc
		(start 36.11499 -276.748748)
		(mid 36.72713 -277.360888)
		(end 37.33927 -276.748748)
		(stroke
			(width 0.2)
			(type default)
		)
		(layer "In3.Cu")
	)
	(gr_line
		(start 36.11499 -275.631148)
		(end 36.11499 -276.748748)
		(stroke
			(width 0.2)
			(type default)
		)
		(layer "In3.Cu")
	)
	(gr_arc
		(start 36.11499 -263.948926)
		(mid 36.72713 -264.561066)
		(end 37.33927 -263.948926)
		(stroke
			(width 0.2)
			(type default)
		)
		(layer "In3.Cu")
	)
	(gr_line
		(start 36.11499 -262.831326)
		(end 36.11499 -263.948926)
		(stroke
			(width 0.2)
			(type default)
		)
		(layer "In3.Cu")
	)
	(gr_arc
		(start 36.11499 -183.348884)
		(mid 36.72713 -183.961024)
		(end 37.33927 -183.348884)
		(stroke
			(width 0.2)
			(type default)
		)
		(layer "In3.Cu")
	)
	(gr_line
		(start 36.11499 -182.231284)
		(end 36.11499 -183.348884)
		(stroke
			(width 0.2)
			(type default)
		)
		(layer "In3.Cu")
	)
	(gr_arc
		(start 36.11499 -178.548792)
		(mid 36.72713 -179.160932)
		(end 37.33927 -178.548792)
		(stroke
			(width 0.2)
			(type default)
		)
		(layer "In3.Cu")
	)
	(gr_line
		(start 36.11499 -177.431192)
		(end 36.11499 -178.548792)
		(stroke
			(width 0.2)
			(type default)
		)
		(layer "In3.Cu")
	)
	(gr_arc
		(start 36.11499 -173.7487)
		(mid 36.72713 -174.36084)
		(end 37.33927 -173.7487)
		(stroke
			(width 0.2)
			(type default)
		)
		(layer "In3.Cu")
	)
	(gr_line
		(start 36.11499 -172.6311)
		(end 36.11499 -173.7487)
		(stroke
			(width 0.2)
			(type default)
		)
		(layer "In3.Cu")
	)
	(gr_arc
		(start 36.11499 -160.948878)
		(mid 36.72713 -161.561018)
		(end 37.33927 -160.948878)
		(stroke
			(width 0.2)
			(type default)
		)
		(layer "In3.Cu")
	)
	(gr_line
		(start 36.11499 -159.831278)
		(end 36.11499 -160.948878)
		(stroke
			(width 0.2)
			(type default)
		)
		(layer "In3.Cu")
	)
	(gr_arc
		(start 36.11499 -80.348836)
		(mid 36.72713 -80.960976)
		(end 37.33927 -80.348836)
		(stroke
			(width 0.2)
			(type default)
		)
		(layer "In3.Cu")
	)
	(gr_line
		(start 36.11499 -79.231236)
		(end 36.11499 -80.348836)
		(stroke
			(width 0.2)
			(type default)
		)
		(layer "In3.Cu")
	)
	(gr_arc
		(start 36.11499 -75.548744)
		(mid 36.72713 -76.160884)
		(end 37.33927 -75.548744)
		(stroke
			(width 0.2)
			(type default)
		)
		(layer "In3.Cu")
	)
	(gr_line
		(start 36.11499 -74.431144)
		(end 36.11499 -75.548744)
		(stroke
			(width 0.2)
			(type default)
		)
		(layer "In3.Cu")
	)
	(gr_arc
		(start 36.11499 -70.748652)
		(mid 36.72713 -71.360792)
		(end 37.33927 -70.748652)
		(stroke
			(width 0.2)
			(type default)
		)
		(layer "In3.Cu")
	)
	(gr_line
		(start 36.11499 -69.631052)
		(end 36.11499 -70.748652)
		(stroke
			(width 0.2)
			(type default)
		)
		(layer "In3.Cu")
	)
	(gr_arc
		(start 36.11499 -57.94883)
		(mid 36.72713 -58.56097)
		(end 37.33927 -57.94883)
		(stroke
			(width 0.2)
			(type default)
		)
		(layer "In3.Cu")
	)
	(gr_line
		(start 36.11499 -56.83123)
		(end 36.11499 -57.94883)
		(stroke
			(width 0.2)
			(type default)
		)
		(layer "In3.Cu")
	)
	(gr_line
		(start 37.200078 0)
		(end 262.50011 0)
		(stroke
			(width 1.524)
			(type default)
		)
		(layer "In3.Cu")
	)
	(gr_line
		(start 37.33927 -492.349028)
		(end 37.33927 -491.231428)
		(stroke
			(width 0.2)
			(type default)
		)
		(layer "In3.Cu")
	)
	(gr_arc
		(start 37.33927 -491.231428)
		(mid 36.72713 -490.619288)
		(end 36.11499 -491.231428)
		(stroke
			(width 0.2)
			(type default)
		)
		(layer "In3.Cu")
	)
	(gr_line
		(start 37.33927 -487.548936)
		(end 37.33927 -486.43159)
		(stroke
			(width 0.2)
			(type default)
		)
		(layer "In3.Cu")
	)
	(gr_arc
		(start 37.33927 -486.43159)
		(mid 36.727257 -485.819196)
		(end 36.11499 -486.431336)
		(stroke
			(width 0.2)
			(type default)
		)
		(layer "In3.Cu")
	)
	(gr_line
		(start 37.33927 -482.748844)
		(end 37.33927 -481.631244)
		(stroke
			(width 0.2)
			(type default)
		)
		(layer "In3.Cu")
	)
	(gr_arc
		(start 37.33927 -481.631244)
		(mid 36.72713 -481.019104)
		(end 36.11499 -481.631244)
		(stroke
			(width 0.2)
			(type default)
		)
		(layer "In3.Cu")
	)
	(gr_line
		(start 37.33927 -469.949022)
		(end 37.33927 -468.831422)
		(stroke
			(width 0.2)
			(type default)
		)
		(layer "In3.Cu")
	)
	(gr_arc
		(start 37.33927 -468.831422)
		(mid 36.72713 -468.219282)
		(end 36.11499 -468.831422)
		(stroke
			(width 0.2)
			(type default)
		)
		(layer "In3.Cu")
	)
	(gr_line
		(start 37.33927 -389.34898)
		(end 37.33927 -388.231634)
		(stroke
			(width 0.2)
			(type default)
		)
		(layer "In3.Cu")
	)
	(gr_arc
		(start 37.33927 -388.231634)
		(mid 36.727257 -387.61924)
		(end 36.11499 -388.23138)
		(stroke
			(width 0.2)
			(type default)
		)
		(layer "In3.Cu")
	)
	(gr_line
		(start 37.33927 -384.548888)
		(end 37.33927 -383.431542)
		(stroke
			(width 0.2)
			(type default)
		)
		(layer "In3.Cu")
	)
	(gr_arc
		(start 37.33927 -383.431542)
		(mid 36.727257 -382.819148)
		(end 36.11499 -383.431288)
		(stroke
			(width 0.2)
			(type default)
		)
		(layer "In3.Cu")
	)
	(gr_line
		(start 37.33927 -379.748796)
		(end 37.33927 -378.63145)
		(stroke
			(width 0.2)
			(type default)
		)
		(layer "In3.Cu")
	)
	(gr_arc
		(start 37.33927 -378.63145)
		(mid 36.727257 -378.019056)
		(end 36.11499 -378.631196)
		(stroke
			(width 0.2)
			(type default)
		)
		(layer "In3.Cu")
	)
	(gr_line
		(start 37.33927 -366.948974)
		(end 37.33927 -365.831628)
		(stroke
			(width 0.2)
			(type default)
		)
		(layer "In3.Cu")
	)
	(gr_arc
		(start 37.33927 -365.831628)
		(mid 36.727257 -365.219234)
		(end 36.11499 -365.831374)
		(stroke
			(width 0.2)
			(type default)
		)
		(layer "In3.Cu")
	)
	(gr_line
		(start 37.33927 -286.348932)
		(end 37.33927 -285.231586)
		(stroke
			(width 0.2)
			(type default)
		)
		(layer "In3.Cu")
	)
	(gr_arc
		(start 37.33927 -285.231586)
		(mid 36.727257 -284.619192)
		(end 36.11499 -285.231332)
		(stroke
			(width 0.2)
			(type default)
		)
		(layer "In3.Cu")
	)
	(gr_line
		(start 37.33927 -281.54884)
		(end 37.33927 -280.431494)
		(stroke
			(width 0.2)
			(type default)
		)
		(layer "In3.Cu")
	)
	(gr_arc
		(start 37.33927 -280.431494)
		(mid 36.727257 -279.8191)
		(end 36.11499 -280.43124)
		(stroke
			(width 0.2)
			(type default)
		)
		(layer "In3.Cu")
	)
	(gr_line
		(start 37.33927 -276.748748)
		(end 37.33927 -275.631402)
		(stroke
			(width 0.2)
			(type default)
		)
		(layer "In3.Cu")
	)
	(gr_arc
		(start 37.33927 -275.631402)
		(mid 36.727257 -275.019008)
		(end 36.11499 -275.631148)
		(stroke
			(width 0.2)
			(type default)
		)
		(layer "In3.Cu")
	)
	(gr_line
		(start 37.33927 -263.948926)
		(end 37.33927 -262.83158)
		(stroke
			(width 0.2)
			(type default)
		)
		(layer "In3.Cu")
	)
	(gr_arc
		(start 37.33927 -262.83158)
		(mid 36.727257 -262.219186)
		(end 36.11499 -262.831326)
		(stroke
			(width 0.2)
			(type default)
		)
		(layer "In3.Cu")
	)
	(gr_line
		(start 37.33927 -183.348884)
		(end 37.33927 -182.231538)
		(stroke
			(width 0.2)
			(type default)
		)
		(layer "In3.Cu")
	)
	(gr_arc
		(start 37.33927 -182.231538)
		(mid 36.727257 -181.619144)
		(end 36.11499 -182.231284)
		(stroke
			(width 0.2)
			(type default)
		)
		(layer "In3.Cu")
	)
	(gr_line
		(start 37.33927 -178.548792)
		(end 37.33927 -177.431446)
		(stroke
			(width 0.2)
			(type default)
		)
		(layer "In3.Cu")
	)
	(gr_arc
		(start 37.33927 -177.431446)
		(mid 36.727257 -176.819052)
		(end 36.11499 -177.431192)
		(stroke
			(width 0.2)
			(type default)
		)
		(layer "In3.Cu")
	)
	(gr_line
		(start 37.33927 -173.7487)
		(end 37.33927 -172.631354)
		(stroke
			(width 0.2)
			(type default)
		)
		(layer "In3.Cu")
	)
	(gr_arc
		(start 37.33927 -172.631354)
		(mid 36.727257 -172.01896)
		(end 36.11499 -172.6311)
		(stroke
			(width 0.2)
			(type default)
		)
		(layer "In3.Cu")
	)
	(gr_line
		(start 37.33927 -160.948878)
		(end 37.33927 -159.831532)
		(stroke
			(width 0.2)
			(type default)
		)
		(layer "In3.Cu")
	)
	(gr_arc
		(start 37.33927 -159.831532)
		(mid 36.727257 -159.219138)
		(end 36.11499 -159.831278)
		(stroke
			(width 0.2)
			(type default)
		)
		(layer "In3.Cu")
	)
	(gr_line
		(start 37.33927 -80.348836)
		(end 37.33927 -79.23149)
		(stroke
			(width 0.2)
			(type default)
		)
		(layer "In3.Cu")
	)
	(gr_arc
		(start 37.33927 -79.23149)
		(mid 36.727257 -78.619096)
		(end 36.11499 -79.231236)
		(stroke
			(width 0.2)
			(type default)
		)
		(layer "In3.Cu")
	)
	(gr_line
		(start 37.33927 -75.548744)
		(end 37.33927 -74.431398)
		(stroke
			(width 0.2)
			(type default)
		)
		(layer "In3.Cu")
	)
	(gr_arc
		(start 37.33927 -74.431398)
		(mid 36.727257 -73.819004)
		(end 36.11499 -74.431144)
		(stroke
			(width 0.2)
			(type default)
		)
		(layer "In3.Cu")
	)
	(gr_line
		(start 37.33927 -70.748652)
		(end 37.33927 -69.631306)
		(stroke
			(width 0.2)
			(type default)
		)
		(layer "In3.Cu")
	)
	(gr_arc
		(start 37.33927 -69.631306)
		(mid 36.727257 -69.018912)
		(end 36.11499 -69.631052)
		(stroke
			(width 0.2)
			(type default)
		)
		(layer "In3.Cu")
	)
	(gr_line
		(start 37.33927 -57.94883)
		(end 37.33927 -56.831484)
		(stroke
			(width 0.2)
			(type default)
		)
		(layer "In3.Cu")
	)
	(gr_arc
		(start 37.33927 -56.831484)
		(mid 36.727257 -56.21909)
		(end 36.11499 -56.83123)
		(stroke
			(width 0.2)
			(type default)
		)
		(layer "In3.Cu")
	)
	(gr_arc
		(start 41.90746 -239.397286)
		(mid 42.418 -239.907826)
		(end 42.92854 -239.397286)
		(stroke
			(width 0.2)
			(type default)
		)
		(layer "In3.Cu")
	)
	(gr_line
		(start 41.90746 -238.584486)
		(end 41.90746 -239.397286)
		(stroke
			(width 0.2)
			(type default)
		)
		(layer "In3.Cu")
	)
	(gr_line
		(start 42.92854 -239.397286)
		(end 42.92854 -238.58474)
		(stroke
			(width 0.2)
			(type default)
		)
		(layer "In3.Cu")
	)
	(gr_arc
		(start 42.92854 -238.58474)
		(mid 42.418127 -238.073946)
		(end 41.90746 -238.584486)
		(stroke
			(width 0.2)
			(type default)
		)
		(layer "In3.Cu")
	)
	(gr_line
		(start 44.9072 -472.300808)
		(end 45.719746 -472.300808)
		(stroke
			(width 0.2)
			(type default)
		)
		(layer "In3.Cu")
	)
	(gr_arc
		(start 44.9072 -471.279728)
		(mid 44.39666 -471.790268)
		(end 44.9072 -472.300808)
		(stroke
			(width 0.2)
			(type default)
		)
		(layer "In3.Cu")
	)
	(gr_line
		(start 44.9072 -369.30076)
		(end 45.72 -369.30076)
		(stroke
			(width 0.2)
			(type default)
		)
		(layer "In3.Cu")
	)
	(gr_line
		(start 44.9072 -266.300712)
		(end 45.72 -266.300712)
		(stroke
			(width 0.2)
			(type default)
		)
		(layer "In3.Cu")
	)
	(gr_line
		(start 44.9072 -163.300664)
		(end 45.72 -163.300664)
		(stroke
			(width 0.2)
			(type default)
		)
		(layer "In3.Cu")
	)
	(gr_line
		(start 44.9072 -60.300616)
		(end 45.72 -60.300616)
		(stroke
			(width 0.2)
			(type default)
		)
		(layer "In3.Cu")
	)
	(gr_arc
		(start 44.907454 -368.27968)
		(mid 44.39666 -368.790093)
		(end 44.9072 -369.30076)
		(stroke
			(width 0.2)
			(type default)
		)
		(layer "In3.Cu")
	)
	(gr_arc
		(start 44.907454 -265.279632)
		(mid 44.39666 -265.790045)
		(end 44.9072 -266.300712)
		(stroke
			(width 0.2)
			(type default)
		)
		(layer "In3.Cu")
	)
	(gr_arc
		(start 44.907454 -162.279584)
		(mid 44.39666 -162.789997)
		(end 44.9072 -163.300664)
		(stroke
			(width 0.2)
			(type default)
		)
		(layer "In3.Cu")
	)
	(gr_arc
		(start 44.907454 -59.279536)
		(mid 44.39666 -59.789949)
		(end 44.9072 -60.300616)
		(stroke
			(width 0.2)
			(type default)
		)
		(layer "In3.Cu")
	)
	(gr_arc
		(start 45.719746 -472.300808)
		(mid 46.23054 -471.790395)
		(end 45.72 -471.279728)
		(stroke
			(width 0.2)
			(type default)
		)
		(layer "In3.Cu")
	)
	(gr_line
		(start 45.72 -471.279728)
		(end 44.9072 -471.279728)
		(stroke
			(width 0.2)
			(type default)
		)
		(layer "In3.Cu")
	)
	(gr_arc
		(start 45.72 -369.30076)
		(mid 46.23054 -368.79022)
		(end 45.72 -368.27968)
		(stroke
			(width 0.2)
			(type default)
		)
		(layer "In3.Cu")
	)
	(gr_line
		(start 45.72 -368.27968)
		(end 44.907454 -368.27968)
		(stroke
			(width 0.2)
			(type default)
		)
		(layer "In3.Cu")
	)
	(gr_arc
		(start 45.72 -266.300712)
		(mid 46.23054 -265.790172)
		(end 45.72 -265.279632)
		(stroke
			(width 0.2)
			(type default)
		)
		(layer "In3.Cu")
	)
	(gr_line
		(start 45.72 -265.279632)
		(end 44.907454 -265.279632)
		(stroke
			(width 0.2)
			(type default)
		)
		(layer "In3.Cu")
	)
	(gr_arc
		(start 45.72 -163.300664)
		(mid 46.23054 -162.790124)
		(end 45.72 -162.279584)
		(stroke
			(width 0.2)
			(type default)
		)
		(layer "In3.Cu")
	)
	(gr_line
		(start 45.72 -162.279584)
		(end 44.907454 -162.279584)
		(stroke
			(width 0.2)
			(type default)
		)
		(layer "In3.Cu")
	)
	(gr_arc
		(start 45.72 -60.300616)
		(mid 46.23054 -59.790076)
		(end 45.72 -59.279536)
		(stroke
			(width 0.2)
			(type default)
		)
		(layer "In3.Cu")
	)
	(gr_line
		(start 45.72 -59.279536)
		(end 44.907454 -59.279536)
		(stroke
			(width 0.2)
			(type default)
		)
		(layer "In3.Cu")
	)
	(gr_arc
		(start 47.87646 -473.392246)
		(mid 48.387 -473.902786)
		(end 48.89754 -473.392246)
		(stroke
			(width 0.2)
			(type default)
		)
		(layer "In3.Cu")
	)
	(gr_line
		(start 47.87646 -472.579446)
		(end 47.87646 -473.392246)
		(stroke
			(width 0.2)
			(type default)
		)
		(layer "In3.Cu")
	)
	(gr_arc
		(start 47.87646 -370.392198)
		(mid 48.387 -370.902738)
		(end 48.89754 -370.392198)
		(stroke
			(width 0.2)
			(type default)
		)
		(layer "In3.Cu")
	)
	(gr_line
		(start 47.87646 -369.579398)
		(end 47.87646 -370.392198)
		(stroke
			(width 0.2)
			(type default)
		)
		(layer "In3.Cu")
	)
	(gr_arc
		(start 47.87646 -267.39215)
		(mid 48.387 -267.90269)
		(end 48.89754 -267.39215)
		(stroke
			(width 0.2)
			(type default)
		)
		(layer "In3.Cu")
	)
	(gr_line
		(start 47.87646 -266.57935)
		(end 47.87646 -267.39215)
		(stroke
			(width 0.2)
			(type default)
		)
		(layer "In3.Cu")
	)
	(gr_arc
		(start 47.87646 -164.392102)
		(mid 48.387 -164.902642)
		(end 48.89754 -164.392102)
		(stroke
			(width 0.2)
			(type default)
		)
		(layer "In3.Cu")
	)
	(gr_line
		(start 47.87646 -163.579302)
		(end 47.87646 -164.392102)
		(stroke
			(width 0.2)
			(type default)
		)
		(layer "In3.Cu")
	)
	(gr_arc
		(start 47.87646 -61.392054)
		(mid 48.387 -61.902594)
		(end 48.89754 -61.392054)
		(stroke
			(width 0.2)
			(type default)
		)
		(layer "In3.Cu")
	)
	(gr_line
		(start 47.87646 -60.579254)
		(end 47.87646 -61.392054)
		(stroke
			(width 0.2)
			(type default)
		)
		(layer "In3.Cu")
	)
	(gr_line
		(start 48.89754 -473.392246)
		(end 48.89754 -472.5797)
		(stroke
			(width 0.2)
			(type default)
		)
		(layer "In3.Cu")
	)
	(gr_arc
		(start 48.89754 -472.5797)
		(mid 48.387127 -472.068906)
		(end 47.87646 -472.579446)
		(stroke
			(width 0.2)
			(type default)
		)
		(layer "In3.Cu")
	)
	(gr_line
		(start 48.89754 -370.392198)
		(end 48.89754 -369.579652)
		(stroke
			(width 0.2)
			(type default)
		)
		(layer "In3.Cu")
	)
	(gr_arc
		(start 48.89754 -369.579652)
		(mid 48.387127 -369.068858)
		(end 47.87646 -369.579398)
		(stroke
			(width 0.2)
			(type default)
		)
		(layer "In3.Cu")
	)
	(gr_line
		(start 48.89754 -267.39215)
		(end 48.89754 -266.579604)
		(stroke
			(width 0.2)
			(type default)
		)
		(layer "In3.Cu")
	)
	(gr_arc
		(start 48.89754 -266.579604)
		(mid 48.387127 -266.06881)
		(end 47.87646 -266.57935)
		(stroke
			(width 0.2)
			(type default)
		)
		(layer "In3.Cu")
	)
	(gr_line
		(start 48.89754 -164.392102)
		(end 48.89754 -163.579556)
		(stroke
			(width 0.2)
			(type default)
		)
		(layer "In3.Cu")
	)
	(gr_arc
		(start 48.89754 -163.579556)
		(mid 48.387127 -163.068762)
		(end 47.87646 -163.579302)
		(stroke
			(width 0.2)
			(type default)
		)
		(layer "In3.Cu")
	)
	(gr_line
		(start 48.89754 -61.392054)
		(end 48.89754 -60.579508)
		(stroke
			(width 0.2)
			(type default)
		)
		(layer "In3.Cu")
	)
	(gr_arc
		(start 48.89754 -60.579508)
		(mid 48.387127 -60.068714)
		(end 47.87646 -60.579254)
		(stroke
			(width 0.2)
			(type default)
		)
		(layer "In3.Cu")
	)
	(gr_arc
		(start 71.87946 -431.9524)
		(mid 72.39 -432.46294)
		(end 72.90054 -431.9524)
		(stroke
			(width 0.2)
			(type default)
		)
		(layer "In3.Cu")
	)
	(gr_line
		(start 71.87946 -431.1396)
		(end 71.87946 -431.9524)
		(stroke
			(width 0.2)
			(type default)
		)
		(layer "In3.Cu")
	)
	(gr_line
		(start 72.90054 -431.9524)
		(end 72.90054 -431.139854)
		(stroke
			(width 0.2)
			(type default)
		)
		(layer "In3.Cu")
	)
	(gr_arc
		(start 72.90054 -431.139854)
		(mid 72.390127 -430.62906)
		(end 71.87946 -431.1396)
		(stroke
			(width 0.2)
			(type default)
		)
		(layer "In3.Cu")
	)
	(gr_line
		(start 74.2696 -430.63414)
		(end 75.0824 -430.63414)
		(stroke
			(width 0.2)
			(type default)
		)
		(layer "In3.Cu")
	)
	(gr_arc
		(start 74.269854 -429.61306)
		(mid 73.75906 -430.123473)
		(end 74.2696 -430.63414)
		(stroke
			(width 0.2)
			(type default)
		)
		(layer "In3.Cu")
	)
	(gr_arc
		(start 75.0824 -430.63414)
		(mid 75.59294 -430.1236)
		(end 75.0824 -429.61306)
		(stroke
			(width 0.2)
			(type default)
		)
		(layer "In3.Cu")
	)
	(gr_line
		(start 75.0824 -429.61306)
		(end 74.269854 -429.61306)
		(stroke
			(width 0.2)
			(type default)
		)
		(layer "In3.Cu")
	)
	(gr_arc
		(start 219.819474 -489.796582)
		(mid 220.330014 -490.307122)
		(end 220.840554 -489.796582)
		(stroke
			(width 0.2)
			(type default)
		)
		(layer "In3.Cu")
	)
	(gr_line
		(start 219.819474 -488.983782)
		(end 219.819474 -489.796582)
		(stroke
			(width 0.2)
			(type default)
		)
		(layer "In3.Cu")
	)
	(gr_arc
		(start 219.819474 -484.99649)
		(mid 220.330014 -485.50703)
		(end 220.840554 -484.99649)
		(stroke
			(width 0.2)
			(type default)
		)
		(layer "In3.Cu")
	)
	(gr_line
		(start 219.819474 -484.18369)
		(end 219.819474 -484.99649)
		(stroke
			(width 0.2)
			(type default)
		)
		(layer "In3.Cu")
	)
	(gr_arc
		(start 219.819474 -480.196652)
		(mid 220.330014 -480.707192)
		(end 220.840554 -480.196652)
		(stroke
			(width 0.2)
			(type default)
		)
		(layer "In3.Cu")
	)
	(gr_line
		(start 219.819474 -479.383852)
		(end 219.819474 -480.196652)
		(stroke
			(width 0.2)
			(type default)
		)
		(layer "In3.Cu")
	)
	(gr_arc
		(start 219.819474 -467.396576)
		(mid 220.330014 -467.907116)
		(end 220.840554 -467.396576)
		(stroke
			(width 0.2)
			(type default)
		)
		(layer "In3.Cu")
	)
	(gr_line
		(start 219.819474 -466.583776)
		(end 219.819474 -467.396576)
		(stroke
			(width 0.2)
			(type default)
		)
		(layer "In3.Cu")
	)
	(gr_arc
		(start 219.819474 -386.796534)
		(mid 220.330014 -387.307074)
		(end 220.840554 -386.796534)
		(stroke
			(width 0.2)
			(type default)
		)
		(layer "In3.Cu")
	)
	(gr_line
		(start 219.819474 -385.983734)
		(end 219.819474 -386.796534)
		(stroke
			(width 0.2)
			(type default)
		)
		(layer "In3.Cu")
	)
	(gr_arc
		(start 219.819474 -381.996442)
		(mid 220.330014 -382.506982)
		(end 220.840554 -381.996442)
		(stroke
			(width 0.2)
			(type default)
		)
		(layer "In3.Cu")
	)
	(gr_line
		(start 219.819474 -381.183642)
		(end 219.819474 -381.996442)
		(stroke
			(width 0.2)
			(type default)
		)
		(layer "In3.Cu")
	)
	(gr_arc
		(start 219.819474 -377.196604)
		(mid 220.330014 -377.707144)
		(end 220.840554 -377.196604)
		(stroke
			(width 0.2)
			(type default)
		)
		(layer "In3.Cu")
	)
	(gr_line
		(start 219.819474 -376.383804)
		(end 219.819474 -377.196604)
		(stroke
			(width 0.2)
			(type default)
		)
		(layer "In3.Cu")
	)
	(gr_arc
		(start 219.819474 -364.396528)
		(mid 220.330014 -364.907068)
		(end 220.840554 -364.396528)
		(stroke
			(width 0.2)
			(type default)
		)
		(layer "In3.Cu")
	)
	(gr_line
		(start 219.819474 -363.583728)
		(end 219.819474 -364.396528)
		(stroke
			(width 0.2)
			(type default)
		)
		(layer "In3.Cu")
	)
	(gr_arc
		(start 219.819474 -283.796486)
		(mid 220.330014 -284.307026)
		(end 220.840554 -283.796486)
		(stroke
			(width 0.2)
			(type default)
		)
		(layer "In3.Cu")
	)
	(gr_line
		(start 219.819474 -282.983686)
		(end 219.819474 -283.796486)
		(stroke
			(width 0.2)
			(type default)
		)
		(layer "In3.Cu")
	)
	(gr_arc
		(start 219.819474 -278.996394)
		(mid 220.330014 -279.506934)
		(end 220.840554 -278.996394)
		(stroke
			(width 0.2)
			(type default)
		)
		(layer "In3.Cu")
	)
	(gr_line
		(start 219.819474 -278.183594)
		(end 219.819474 -278.996394)
		(stroke
			(width 0.2)
			(type default)
		)
		(layer "In3.Cu")
	)
	(gr_arc
		(start 219.819474 -274.196556)
		(mid 220.330014 -274.707096)
		(end 220.840554 -274.196556)
		(stroke
			(width 0.2)
			(type default)
		)
		(layer "In3.Cu")
	)
	(gr_line
		(start 219.819474 -273.383756)
		(end 219.819474 -274.196556)
		(stroke
			(width 0.2)
			(type default)
		)
		(layer "In3.Cu")
	)
	(gr_arc
		(start 219.819474 -261.39648)
		(mid 220.330014 -261.90702)
		(end 220.840554 -261.39648)
		(stroke
			(width 0.2)
			(type default)
		)
		(layer "In3.Cu")
	)
	(gr_line
		(start 219.819474 -260.58368)
		(end 219.819474 -261.39648)
		(stroke
			(width 0.2)
			(type default)
		)
		(layer "In3.Cu")
	)
	(gr_arc
		(start 219.819474 -180.796438)
		(mid 220.330014 -181.306978)
		(end 220.840554 -180.796438)
		(stroke
			(width 0.2)
			(type default)
		)
		(layer "In3.Cu")
	)
	(gr_line
		(start 219.819474 -179.983638)
		(end 219.819474 -180.796438)
		(stroke
			(width 0.2)
			(type default)
		)
		(layer "In3.Cu")
	)
	(gr_arc
		(start 219.819474 -175.996346)
		(mid 220.330014 -176.506886)
		(end 220.840554 -175.996346)
		(stroke
			(width 0.2)
			(type default)
		)
		(layer "In3.Cu")
	)
	(gr_line
		(start 219.819474 -175.183546)
		(end 219.819474 -175.996346)
		(stroke
			(width 0.2)
			(type default)
		)
		(layer "In3.Cu")
	)
	(gr_arc
		(start 219.819474 -171.196508)
		(mid 220.330014 -171.707048)
		(end 220.840554 -171.196508)
		(stroke
			(width 0.2)
			(type default)
		)
		(layer "In3.Cu")
	)
	(gr_line
		(start 219.819474 -170.383708)
		(end 219.819474 -171.196508)
		(stroke
			(width 0.2)
			(type default)
		)
		(layer "In3.Cu")
	)
	(gr_arc
		(start 219.819474 -158.396432)
		(mid 220.330014 -158.906972)
		(end 220.840554 -158.396432)
		(stroke
			(width 0.2)
			(type default)
		)
		(layer "In3.Cu")
	)
	(gr_line
		(start 219.819474 -157.583632)
		(end 219.819474 -158.396432)
		(stroke
			(width 0.2)
			(type default)
		)
		(layer "In3.Cu")
	)
	(gr_arc
		(start 219.819474 -77.79639)
		(mid 220.330014 -78.30693)
		(end 220.840554 -77.79639)
		(stroke
			(width 0.2)
			(type default)
		)
		(layer "In3.Cu")
	)
	(gr_line
		(start 219.819474 -76.98359)
		(end 219.819474 -77.79639)
		(stroke
			(width 0.2)
			(type default)
		)
		(layer "In3.Cu")
	)
	(gr_arc
		(start 219.819474 -72.996298)
		(mid 220.330014 -73.506838)
		(end 220.840554 -72.996298)
		(stroke
			(width 0.2)
			(type default)
		)
		(layer "In3.Cu")
	)
	(gr_line
		(start 219.819474 -72.183498)
		(end 219.819474 -72.996298)
		(stroke
			(width 0.2)
			(type default)
		)
		(layer "In3.Cu")
	)
	(gr_arc
		(start 219.819474 -68.19646)
		(mid 220.330014 -68.707)
		(end 220.840554 -68.19646)
		(stroke
			(width 0.2)
			(type default)
		)
		(layer "In3.Cu")
	)
	(gr_line
		(start 219.819474 -67.38366)
		(end 219.819474 -68.19646)
		(stroke
			(width 0.2)
			(type default)
		)
		(layer "In3.Cu")
	)
	(gr_arc
		(start 219.819474 -55.396384)
		(mid 220.330014 -55.906924)
		(end 220.840554 -55.396384)
		(stroke
			(width 0.2)
			(type default)
		)
		(layer "In3.Cu")
	)
	(gr_line
		(start 219.819474 -54.583584)
		(end 219.819474 -55.396384)
		(stroke
			(width 0.2)
			(type default)
		)
		(layer "In3.Cu")
	)
	(gr_line
		(start 220.840554 -489.796582)
		(end 220.840554 -488.984036)
		(stroke
			(width 0.2)
			(type default)
		)
		(layer "In3.Cu")
	)
	(gr_arc
		(start 220.840554 -488.984036)
		(mid 220.330141 -488.473242)
		(end 219.819474 -488.983782)
		(stroke
			(width 0.2)
			(type default)
		)
		(layer "In3.Cu")
	)
	(gr_line
		(start 220.840554 -484.99649)
		(end 220.840554 -484.183944)
		(stroke
			(width 0.2)
			(type default)
		)
		(layer "In3.Cu")
	)
	(gr_arc
		(start 220.840554 -484.183944)
		(mid 220.330141 -483.67315)
		(end 219.819474 -484.18369)
		(stroke
			(width 0.2)
			(type default)
		)
		(layer "In3.Cu")
	)
	(gr_line
		(start 220.840554 -480.196652)
		(end 220.840554 -479.384106)
		(stroke
			(width 0.2)
			(type default)
		)
		(layer "In3.Cu")
	)
	(gr_arc
		(start 220.840554 -479.384106)
		(mid 220.330141 -478.873312)
		(end 219.819474 -479.383852)
		(stroke
			(width 0.2)
			(type default)
		)
		(layer "In3.Cu")
	)
	(gr_line
		(start 220.840554 -467.396576)
		(end 220.840554 -466.58403)
		(stroke
			(width 0.2)
			(type default)
		)
		(layer "In3.Cu")
	)
	(gr_arc
		(start 220.840554 -466.58403)
		(mid 220.330141 -466.073236)
		(end 219.819474 -466.583776)
		(stroke
			(width 0.2)
			(type default)
		)
		(layer "In3.Cu")
	)
	(gr_line
		(start 220.840554 -386.796534)
		(end 220.840554 -385.983988)
		(stroke
			(width 0.2)
			(type default)
		)
		(layer "In3.Cu")
	)
	(gr_arc
		(start 220.840554 -385.983988)
		(mid 220.330141 -385.473194)
		(end 219.819474 -385.983734)
		(stroke
			(width 0.2)
			(type default)
		)
		(layer "In3.Cu")
	)
	(gr_line
		(start 220.840554 -381.996442)
		(end 220.840554 -381.183896)
		(stroke
			(width 0.2)
			(type default)
		)
		(layer "In3.Cu")
	)
	(gr_arc
		(start 220.840554 -381.183896)
		(mid 220.330141 -380.673102)
		(end 219.819474 -381.183642)
		(stroke
			(width 0.2)
			(type default)
		)
		(layer "In3.Cu")
	)
	(gr_line
		(start 220.840554 -377.196604)
		(end 220.840554 -376.384058)
		(stroke
			(width 0.2)
			(type default)
		)
		(layer "In3.Cu")
	)
	(gr_arc
		(start 220.840554 -376.384058)
		(mid 220.330141 -375.873264)
		(end 219.819474 -376.383804)
		(stroke
			(width 0.2)
			(type default)
		)
		(layer "In3.Cu")
	)
	(gr_line
		(start 220.840554 -364.396528)
		(end 220.840554 -363.583982)
		(stroke
			(width 0.2)
			(type default)
		)
		(layer "In3.Cu")
	)
	(gr_arc
		(start 220.840554 -363.583982)
		(mid 220.330141 -363.073188)
		(end 219.819474 -363.583728)
		(stroke
			(width 0.2)
			(type default)
		)
		(layer "In3.Cu")
	)
	(gr_line
		(start 220.840554 -283.796486)
		(end 220.840554 -282.98394)
		(stroke
			(width 0.2)
			(type default)
		)
		(layer "In3.Cu")
	)
	(gr_arc
		(start 220.840554 -282.98394)
		(mid 220.330141 -282.473146)
		(end 219.819474 -282.983686)
		(stroke
			(width 0.2)
			(type default)
		)
		(layer "In3.Cu")
	)
	(gr_line
		(start 220.840554 -278.996394)
		(end 220.840554 -278.183848)
		(stroke
			(width 0.2)
			(type default)
		)
		(layer "In3.Cu")
	)
	(gr_arc
		(start 220.840554 -278.183848)
		(mid 220.330141 -277.673054)
		(end 219.819474 -278.183594)
		(stroke
			(width 0.2)
			(type default)
		)
		(layer "In3.Cu")
	)
	(gr_line
		(start 220.840554 -274.196556)
		(end 220.840554 -273.38401)
		(stroke
			(width 0.2)
			(type default)
		)
		(layer "In3.Cu")
	)
	(gr_arc
		(start 220.840554 -273.38401)
		(mid 220.330141 -272.873216)
		(end 219.819474 -273.383756)
		(stroke
			(width 0.2)
			(type default)
		)
		(layer "In3.Cu")
	)
	(gr_line
		(start 220.840554 -261.39648)
		(end 220.840554 -260.583934)
		(stroke
			(width 0.2)
			(type default)
		)
		(layer "In3.Cu")
	)
	(gr_arc
		(start 220.840554 -260.583934)
		(mid 220.330141 -260.07314)
		(end 219.819474 -260.58368)
		(stroke
			(width 0.2)
			(type default)
		)
		(layer "In3.Cu")
	)
	(gr_line
		(start 220.840554 -180.796438)
		(end 220.840554 -179.983892)
		(stroke
			(width 0.2)
			(type default)
		)
		(layer "In3.Cu")
	)
	(gr_arc
		(start 220.840554 -179.983892)
		(mid 220.330141 -179.473098)
		(end 219.819474 -179.983638)
		(stroke
			(width 0.2)
			(type default)
		)
		(layer "In3.Cu")
	)
	(gr_line
		(start 220.840554 -175.996346)
		(end 220.840554 -175.1838)
		(stroke
			(width 0.2)
			(type default)
		)
		(layer "In3.Cu")
	)
	(gr_arc
		(start 220.840554 -175.1838)
		(mid 220.330141 -174.673006)
		(end 219.819474 -175.183546)
		(stroke
			(width 0.2)
			(type default)
		)
		(layer "In3.Cu")
	)
	(gr_line
		(start 220.840554 -171.196508)
		(end 220.840554 -170.383962)
		(stroke
			(width 0.2)
			(type default)
		)
		(layer "In3.Cu")
	)
	(gr_arc
		(start 220.840554 -170.383962)
		(mid 220.330141 -169.873168)
		(end 219.819474 -170.383708)
		(stroke
			(width 0.2)
			(type default)
		)
		(layer "In3.Cu")
	)
	(gr_line
		(start 220.840554 -158.396432)
		(end 220.840554 -157.583886)
		(stroke
			(width 0.2)
			(type default)
		)
		(layer "In3.Cu")
	)
	(gr_arc
		(start 220.840554 -157.583886)
		(mid 220.330141 -157.073092)
		(end 219.819474 -157.583632)
		(stroke
			(width 0.2)
			(type default)
		)
		(layer "In3.Cu")
	)
	(gr_line
		(start 220.840554 -77.79639)
		(end 220.840554 -76.983844)
		(stroke
			(width 0.2)
			(type default)
		)
		(layer "In3.Cu")
	)
	(gr_arc
		(start 220.840554 -76.983844)
		(mid 220.330141 -76.47305)
		(end 219.819474 -76.98359)
		(stroke
			(width 0.2)
			(type default)
		)
		(layer "In3.Cu")
	)
	(gr_line
		(start 220.840554 -72.996298)
		(end 220.840554 -72.183752)
		(stroke
			(width 0.2)
			(type default)
		)
		(layer "In3.Cu")
	)
	(gr_arc
		(start 220.840554 -72.183752)
		(mid 220.330141 -71.672958)
		(end 219.819474 -72.183498)
		(stroke
			(width 0.2)
			(type default)
		)
		(layer "In3.Cu")
	)
	(gr_line
		(start 220.840554 -68.19646)
		(end 220.840554 -67.383914)
		(stroke
			(width 0.2)
			(type default)
		)
		(layer "In3.Cu")
	)
	(gr_arc
		(start 220.840554 -67.383914)
		(mid 220.330141 -66.87312)
		(end 219.819474 -67.38366)
		(stroke
			(width 0.2)
			(type default)
		)
		(layer "In3.Cu")
	)
	(gr_line
		(start 220.840554 -55.396384)
		(end 220.840554 -54.583838)
		(stroke
			(width 0.2)
			(type default)
		)
		(layer "In3.Cu")
	)
	(gr_arc
		(start 220.840554 -54.583838)
		(mid 220.330141 -54.073044)
		(end 219.819474 -54.583584)
		(stroke
			(width 0.2)
			(type default)
		)
		(layer "In3.Cu")
	)
	(gr_arc
		(start 221.114874 -492.349028)
		(mid 221.727014 -492.961168)
		(end 222.339154 -492.349028)
		(stroke
			(width 0.2)
			(type default)
		)
		(layer "In3.Cu")
	)
	(gr_line
		(start 221.114874 -491.231428)
		(end 221.114874 -492.349028)
		(stroke
			(width 0.2)
			(type default)
		)
		(layer "In3.Cu")
	)
	(gr_arc
		(start 221.114874 -487.548936)
		(mid 221.727014 -488.161076)
		(end 222.339154 -487.548936)
		(stroke
			(width 0.2)
			(type default)
		)
		(layer "In3.Cu")
	)
	(gr_line
		(start 221.114874 -486.431336)
		(end 221.114874 -487.548936)
		(stroke
			(width 0.2)
			(type default)
		)
		(layer "In3.Cu")
	)
	(gr_arc
		(start 221.114874 -482.748844)
		(mid 221.727014 -483.360984)
		(end 222.339154 -482.748844)
		(stroke
			(width 0.2)
			(type default)
		)
		(layer "In3.Cu")
	)
	(gr_line
		(start 221.114874 -481.631244)
		(end 221.114874 -482.748844)
		(stroke
			(width 0.2)
			(type default)
		)
		(layer "In3.Cu")
	)
	(gr_arc
		(start 221.114874 -469.949022)
		(mid 221.727014 -470.561162)
		(end 222.339154 -469.949022)
		(stroke
			(width 0.2)
			(type default)
		)
		(layer "In3.Cu")
	)
	(gr_line
		(start 221.114874 -468.831422)
		(end 221.114874 -469.949022)
		(stroke
			(width 0.2)
			(type default)
		)
		(layer "In3.Cu")
	)
	(gr_arc
		(start 221.114874 -389.34898)
		(mid 221.727014 -389.96112)
		(end 222.339154 -389.34898)
		(stroke
			(width 0.2)
			(type default)
		)
		(layer "In3.Cu")
	)
	(gr_line
		(start 221.114874 -388.23138)
		(end 221.114874 -389.34898)
		(stroke
			(width 0.2)
			(type default)
		)
		(layer "In3.Cu")
	)
	(gr_arc
		(start 221.114874 -384.548888)
		(mid 221.727014 -385.161028)
		(end 222.339154 -384.548888)
		(stroke
			(width 0.2)
			(type default)
		)
		(layer "In3.Cu")
	)
	(gr_line
		(start 221.114874 -383.431288)
		(end 221.114874 -384.548888)
		(stroke
			(width 0.2)
			(type default)
		)
		(layer "In3.Cu")
	)
	(gr_arc
		(start 221.114874 -379.748796)
		(mid 221.727014 -380.360936)
		(end 222.339154 -379.748796)
		(stroke
			(width 0.2)
			(type default)
		)
		(layer "In3.Cu")
	)
	(gr_line
		(start 221.114874 -378.631196)
		(end 221.114874 -379.748796)
		(stroke
			(width 0.2)
			(type default)
		)
		(layer "In3.Cu")
	)
	(gr_arc
		(start 221.114874 -366.948974)
		(mid 221.727014 -367.561114)
		(end 222.339154 -366.948974)
		(stroke
			(width 0.2)
			(type default)
		)
		(layer "In3.Cu")
	)
	(gr_line
		(start 221.114874 -365.831374)
		(end 221.114874 -366.948974)
		(stroke
			(width 0.2)
			(type default)
		)
		(layer "In3.Cu")
	)
	(gr_arc
		(start 221.114874 -286.348932)
		(mid 221.727014 -286.961072)
		(end 222.339154 -286.348932)
		(stroke
			(width 0.2)
			(type default)
		)
		(layer "In3.Cu")
	)
	(gr_line
		(start 221.114874 -285.231332)
		(end 221.114874 -286.348932)
		(stroke
			(width 0.2)
			(type default)
		)
		(layer "In3.Cu")
	)
	(gr_arc
		(start 221.114874 -281.54884)
		(mid 221.727014 -282.16098)
		(end 222.339154 -281.54884)
		(stroke
			(width 0.2)
			(type default)
		)
		(layer "In3.Cu")
	)
	(gr_line
		(start 221.114874 -280.43124)
		(end 221.114874 -281.54884)
		(stroke
			(width 0.2)
			(type default)
		)
		(layer "In3.Cu")
	)
	(gr_arc
		(start 221.114874 -276.748748)
		(mid 221.727014 -277.360888)
		(end 222.339154 -276.748748)
		(stroke
			(width 0.2)
			(type default)
		)
		(layer "In3.Cu")
	)
	(gr_line
		(start 221.114874 -275.631148)
		(end 221.114874 -276.748748)
		(stroke
			(width 0.2)
			(type default)
		)
		(layer "In3.Cu")
	)
	(gr_arc
		(start 221.114874 -263.948926)
		(mid 221.727014 -264.561066)
		(end 222.339154 -263.948926)
		(stroke
			(width 0.2)
			(type default)
		)
		(layer "In3.Cu")
	)
	(gr_line
		(start 221.114874 -262.831326)
		(end 221.114874 -263.948926)
		(stroke
			(width 0.2)
			(type default)
		)
		(layer "In3.Cu")
	)
	(gr_arc
		(start 221.114874 -183.348884)
		(mid 221.727014 -183.961024)
		(end 222.339154 -183.348884)
		(stroke
			(width 0.2)
			(type default)
		)
		(layer "In3.Cu")
	)
	(gr_line
		(start 221.114874 -182.231284)
		(end 221.114874 -183.348884)
		(stroke
			(width 0.2)
			(type default)
		)
		(layer "In3.Cu")
	)
	(gr_arc
		(start 221.114874 -178.548792)
		(mid 221.727014 -179.160932)
		(end 222.339154 -178.548792)
		(stroke
			(width 0.2)
			(type default)
		)
		(layer "In3.Cu")
	)
	(gr_line
		(start 221.114874 -177.431192)
		(end 221.114874 -178.548792)
		(stroke
			(width 0.2)
			(type default)
		)
		(layer "In3.Cu")
	)
	(gr_arc
		(start 221.114874 -173.7487)
		(mid 221.727014 -174.36084)
		(end 222.339154 -173.7487)
		(stroke
			(width 0.2)
			(type default)
		)
		(layer "In3.Cu")
	)
	(gr_line
		(start 221.114874 -172.6311)
		(end 221.114874 -173.7487)
		(stroke
			(width 0.2)
			(type default)
		)
		(layer "In3.Cu")
	)
	(gr_arc
		(start 221.114874 -160.948878)
		(mid 221.727014 -161.561018)
		(end 222.339154 -160.948878)
		(stroke
			(width 0.2)
			(type default)
		)
		(layer "In3.Cu")
	)
	(gr_line
		(start 221.114874 -159.831278)
		(end 221.114874 -160.948878)
		(stroke
			(width 0.2)
			(type default)
		)
		(layer "In3.Cu")
	)
	(gr_arc
		(start 221.114874 -80.348836)
		(mid 221.727014 -80.960976)
		(end 222.339154 -80.348836)
		(stroke
			(width 0.2)
			(type default)
		)
		(layer "In3.Cu")
	)
	(gr_line
		(start 221.114874 -79.231236)
		(end 221.114874 -80.348836)
		(stroke
			(width 0.2)
			(type default)
		)
		(layer "In3.Cu")
	)
	(gr_arc
		(start 221.114874 -75.548744)
		(mid 221.727014 -76.160884)
		(end 222.339154 -75.548744)
		(stroke
			(width 0.2)
			(type default)
		)
		(layer "In3.Cu")
	)
	(gr_line
		(start 221.114874 -74.431144)
		(end 221.114874 -75.548744)
		(stroke
			(width 0.2)
			(type default)
		)
		(layer "In3.Cu")
	)
	(gr_arc
		(start 221.114874 -70.748652)
		(mid 221.727014 -71.360792)
		(end 222.339154 -70.748652)
		(stroke
			(width 0.2)
			(type default)
		)
		(layer "In3.Cu")
	)
	(gr_line
		(start 221.114874 -69.631052)
		(end 221.114874 -70.748652)
		(stroke
			(width 0.2)
			(type default)
		)
		(layer "In3.Cu")
	)
	(gr_arc
		(start 221.114874 -57.94883)
		(mid 221.727014 -58.56097)
		(end 222.339154 -57.94883)
		(stroke
			(width 0.2)
			(type default)
		)
		(layer "In3.Cu")
	)
	(gr_line
		(start 221.114874 -56.83123)
		(end 221.114874 -57.94883)
		(stroke
			(width 0.2)
			(type default)
		)
		(layer "In3.Cu")
	)
	(gr_line
		(start 222.339154 -492.349028)
		(end 222.339154 -491.231682)
		(stroke
			(width 0.2)
			(type default)
		)
		(layer "In3.Cu")
	)
	(gr_arc
		(start 222.339154 -491.231682)
		(mid 221.727141 -490.619288)
		(end 221.114874 -491.231428)
		(stroke
			(width 0.2)
			(type default)
		)
		(layer "In3.Cu")
	)
	(gr_line
		(start 222.339154 -487.548936)
		(end 222.339154 -486.43159)
		(stroke
			(width 0.2)
			(type default)
		)
		(layer "In3.Cu")
	)
	(gr_arc
		(start 222.339154 -486.43159)
		(mid 221.727141 -485.819196)
		(end 221.114874 -486.431336)
		(stroke
			(width 0.2)
			(type default)
		)
		(layer "In3.Cu")
	)
	(gr_line
		(start 222.339154 -482.748844)
		(end 222.339154 -481.631498)
		(stroke
			(width 0.2)
			(type default)
		)
		(layer "In3.Cu")
	)
	(gr_arc
		(start 222.339154 -481.631498)
		(mid 221.727141 -481.019104)
		(end 221.114874 -481.631244)
		(stroke
			(width 0.2)
			(type default)
		)
		(layer "In3.Cu")
	)
	(gr_line
		(start 222.339154 -469.949022)
		(end 222.339154 -468.831676)
		(stroke
			(width 0.2)
			(type default)
		)
		(layer "In3.Cu")
	)
	(gr_arc
		(start 222.339154 -468.831676)
		(mid 221.727141 -468.219282)
		(end 221.114874 -468.831422)
		(stroke
			(width 0.2)
			(type default)
		)
		(layer "In3.Cu")
	)
	(gr_line
		(start 222.339154 -389.34898)
		(end 222.339154 -388.231634)
		(stroke
			(width 0.2)
			(type default)
		)
		(layer "In3.Cu")
	)
	(gr_arc
		(start 222.339154 -388.231634)
		(mid 221.727141 -387.61924)
		(end 221.114874 -388.23138)
		(stroke
			(width 0.2)
			(type default)
		)
		(layer "In3.Cu")
	)
	(gr_line
		(start 222.339154 -384.548888)
		(end 222.339154 -383.431542)
		(stroke
			(width 0.2)
			(type default)
		)
		(layer "In3.Cu")
	)
	(gr_arc
		(start 222.339154 -383.431542)
		(mid 221.727141 -382.819148)
		(end 221.114874 -383.431288)
		(stroke
			(width 0.2)
			(type default)
		)
		(layer "In3.Cu")
	)
	(gr_line
		(start 222.339154 -379.748796)
		(end 222.339154 -378.63145)
		(stroke
			(width 0.2)
			(type default)
		)
		(layer "In3.Cu")
	)
	(gr_arc
		(start 222.339154 -378.63145)
		(mid 221.727141 -378.019056)
		(end 221.114874 -378.631196)
		(stroke
			(width 0.2)
			(type default)
		)
		(layer "In3.Cu")
	)
	(gr_line
		(start 222.339154 -366.948974)
		(end 222.339154 -365.831628)
		(stroke
			(width 0.2)
			(type default)
		)
		(layer "In3.Cu")
	)
	(gr_arc
		(start 222.339154 -365.831628)
		(mid 221.727141 -365.219234)
		(end 221.114874 -365.831374)
		(stroke
			(width 0.2)
			(type default)
		)
		(layer "In3.Cu")
	)
	(gr_line
		(start 222.339154 -286.348932)
		(end 222.339154 -285.231586)
		(stroke
			(width 0.2)
			(type default)
		)
		(layer "In3.Cu")
	)
	(gr_arc
		(start 222.339154 -285.231586)
		(mid 221.727141 -284.619192)
		(end 221.114874 -285.231332)
		(stroke
			(width 0.2)
			(type default)
		)
		(layer "In3.Cu")
	)
	(gr_line
		(start 222.339154 -281.54884)
		(end 222.339154 -280.431494)
		(stroke
			(width 0.2)
			(type default)
		)
		(layer "In3.Cu")
	)
	(gr_arc
		(start 222.339154 -280.431494)
		(mid 221.727141 -279.8191)
		(end 221.114874 -280.43124)
		(stroke
			(width 0.2)
			(type default)
		)
		(layer "In3.Cu")
	)
	(gr_line
		(start 222.339154 -276.748748)
		(end 222.339154 -275.631402)
		(stroke
			(width 0.2)
			(type default)
		)
		(layer "In3.Cu")
	)
	(gr_arc
		(start 222.339154 -275.631402)
		(mid 221.727141 -275.019008)
		(end 221.114874 -275.631148)
		(stroke
			(width 0.2)
			(type default)
		)
		(layer "In3.Cu")
	)
	(gr_line
		(start 222.339154 -263.948926)
		(end 222.339154 -262.83158)
		(stroke
			(width 0.2)
			(type default)
		)
		(layer "In3.Cu")
	)
	(gr_arc
		(start 222.339154 -262.83158)
		(mid 221.727141 -262.219186)
		(end 221.114874 -262.831326)
		(stroke
			(width 0.2)
			(type default)
		)
		(layer "In3.Cu")
	)
	(gr_line
		(start 222.339154 -183.348884)
		(end 222.339154 -182.231538)
		(stroke
			(width 0.2)
			(type default)
		)
		(layer "In3.Cu")
	)
	(gr_arc
		(start 222.339154 -182.231538)
		(mid 221.727141 -181.619144)
		(end 221.114874 -182.231284)
		(stroke
			(width 0.2)
			(type default)
		)
		(layer "In3.Cu")
	)
	(gr_line
		(start 222.339154 -178.548792)
		(end 222.339154 -177.431446)
		(stroke
			(width 0.2)
			(type default)
		)
		(layer "In3.Cu")
	)
	(gr_arc
		(start 222.339154 -177.431446)
		(mid 221.727141 -176.819052)
		(end 221.114874 -177.431192)
		(stroke
			(width 0.2)
			(type default)
		)
		(layer "In3.Cu")
	)
	(gr_line
		(start 222.339154 -173.7487)
		(end 222.339154 -172.631354)
		(stroke
			(width 0.2)
			(type default)
		)
		(layer "In3.Cu")
	)
	(gr_arc
		(start 222.339154 -172.631354)
		(mid 221.727141 -172.01896)
		(end 221.114874 -172.6311)
		(stroke
			(width 0.2)
			(type default)
		)
		(layer "In3.Cu")
	)
	(gr_line
		(start 222.339154 -160.948878)
		(end 222.339154 -159.831532)
		(stroke
			(width 0.2)
			(type default)
		)
		(layer "In3.Cu")
	)
	(gr_arc
		(start 222.339154 -159.831532)
		(mid 221.727141 -159.219138)
		(end 221.114874 -159.831278)
		(stroke
			(width 0.2)
			(type default)
		)
		(layer "In3.Cu")
	)
	(gr_line
		(start 222.339154 -80.348836)
		(end 222.339154 -79.23149)
		(stroke
			(width 0.2)
			(type default)
		)
		(layer "In3.Cu")
	)
	(gr_arc
		(start 222.339154 -79.23149)
		(mid 221.727141 -78.619096)
		(end 221.114874 -79.231236)
		(stroke
			(width 0.2)
			(type default)
		)
		(layer "In3.Cu")
	)
	(gr_line
		(start 222.339154 -75.548744)
		(end 222.339154 -74.431398)
		(stroke
			(width 0.2)
			(type default)
		)
		(layer "In3.Cu")
	)
	(gr_arc
		(start 222.339154 -74.431398)
		(mid 221.727141 -73.819004)
		(end 221.114874 -74.431144)
		(stroke
			(width 0.2)
			(type default)
		)
		(layer "In3.Cu")
	)
	(gr_line
		(start 222.339154 -70.748652)
		(end 222.339154 -69.631306)
		(stroke
			(width 0.2)
			(type default)
		)
		(layer "In3.Cu")
	)
	(gr_arc
		(start 222.339154 -69.631306)
		(mid 221.727141 -69.018912)
		(end 221.114874 -69.631052)
		(stroke
			(width 0.2)
			(type default)
		)
		(layer "In3.Cu")
	)
	(gr_line
		(start 222.339154 -57.94883)
		(end 222.339154 -56.831484)
		(stroke
			(width 0.2)
			(type default)
		)
		(layer "In3.Cu")
	)
	(gr_arc
		(start 222.339154 -56.831484)
		(mid 221.727141 -56.21909)
		(end 221.114874 -56.83123)
		(stroke
			(width 0.2)
			(type default)
		)
		(layer "In3.Cu")
	)
	(gr_line
		(start 229.907084 -472.300808)
		(end 230.71963 -472.300808)
		(stroke
			(width 0.2)
			(type default)
		)
		(layer "In3.Cu")
	)
	(gr_arc
		(start 229.907084 -471.279728)
		(mid 229.396544 -471.790268)
		(end 229.907084 -472.300808)
		(stroke
			(width 0.2)
			(type default)
		)
		(layer "In3.Cu")
	)
	(gr_line
		(start 229.907084 -369.30076)
		(end 230.71963 -369.30076)
		(stroke
			(width 0.2)
			(type default)
		)
		(layer "In3.Cu")
	)
	(gr_arc
		(start 229.907084 -368.27968)
		(mid 229.396544 -368.79022)
		(end 229.907084 -369.30076)
		(stroke
			(width 0.2)
			(type default)
		)
		(layer "In3.Cu")
	)
	(gr_line
		(start 229.907084 -266.300712)
		(end 230.71963 -266.300712)
		(stroke
			(width 0.2)
			(type default)
		)
		(layer "In3.Cu")
	)
	(gr_arc
		(start 229.907084 -265.279632)
		(mid 229.396544 -265.790172)
		(end 229.907084 -266.300712)
		(stroke
			(width 0.2)
			(type default)
		)
		(layer "In3.Cu")
	)
	(gr_line
		(start 229.907084 -163.300664)
		(end 230.71963 -163.300664)
		(stroke
			(width 0.2)
			(type default)
		)
		(layer "In3.Cu")
	)
	(gr_arc
		(start 229.907084 -162.279584)
		(mid 229.396544 -162.790124)
		(end 229.907084 -163.300664)
		(stroke
			(width 0.2)
			(type default)
		)
		(layer "In3.Cu")
	)
	(gr_line
		(start 229.907084 -60.300616)
		(end 230.71963 -60.300616)
		(stroke
			(width 0.2)
			(type default)
		)
		(layer "In3.Cu")
	)
	(gr_arc
		(start 229.907084 -59.279536)
		(mid 229.396544 -59.790076)
		(end 229.907084 -60.300616)
		(stroke
			(width 0.2)
			(type default)
		)
		(layer "In3.Cu")
	)
	(gr_arc
		(start 230.71963 -472.300808)
		(mid 231.230424 -471.790395)
		(end 230.719884 -471.279728)
		(stroke
			(width 0.2)
			(type default)
		)
		(layer "In3.Cu")
	)
	(gr_arc
		(start 230.71963 -369.30076)
		(mid 231.230424 -368.790347)
		(end 230.719884 -368.27968)
		(stroke
			(width 0.2)
			(type default)
		)
		(layer "In3.Cu")
	)
	(gr_arc
		(start 230.71963 -266.300712)
		(mid 231.230424 -265.790299)
		(end 230.719884 -265.279632)
		(stroke
			(width 0.2)
			(type default)
		)
		(layer "In3.Cu")
	)
	(gr_arc
		(start 230.71963 -163.300664)
		(mid 231.230424 -162.790251)
		(end 230.719884 -162.279584)
		(stroke
			(width 0.2)
			(type default)
		)
		(layer "In3.Cu")
	)
	(gr_arc
		(start 230.71963 -60.300616)
		(mid 231.230424 -59.790203)
		(end 230.719884 -59.279536)
		(stroke
			(width 0.2)
			(type default)
		)
		(layer "In3.Cu")
	)
	(gr_line
		(start 230.719884 -471.279728)
		(end 229.907084 -471.279728)
		(stroke
			(width 0.2)
			(type default)
		)
		(layer "In3.Cu")
	)
	(gr_line
		(start 230.719884 -368.27968)
		(end 229.907084 -368.27968)
		(stroke
			(width 0.2)
			(type default)
		)
		(layer "In3.Cu")
	)
	(gr_line
		(start 230.719884 -265.279632)
		(end 229.907084 -265.279632)
		(stroke
			(width 0.2)
			(type default)
		)
		(layer "In3.Cu")
	)
	(gr_line
		(start 230.719884 -162.279584)
		(end 229.907084 -162.279584)
		(stroke
			(width 0.2)
			(type default)
		)
		(layer "In3.Cu")
	)
	(gr_line
		(start 230.719884 -59.279536)
		(end 229.907084 -59.279536)
		(stroke
			(width 0.2)
			(type default)
		)
		(layer "In3.Cu")
	)
	(gr_arc
		(start 232.876344 -473.391992)
		(mid 233.386757 -473.902786)
		(end 233.897424 -473.392246)
		(stroke
			(width 0.2)
			(type default)
		)
		(layer "In3.Cu")
	)
	(gr_line
		(start 232.876344 -472.579446)
		(end 232.876344 -473.391992)
		(stroke
			(width 0.2)
			(type default)
		)
		(layer "In3.Cu")
	)
	(gr_arc
		(start 232.876344 -370.391944)
		(mid 233.386757 -370.902738)
		(end 233.897424 -370.392198)
		(stroke
			(width 0.2)
			(type default)
		)
		(layer "In3.Cu")
	)
	(gr_line
		(start 232.876344 -369.579398)
		(end 232.876344 -370.391944)
		(stroke
			(width 0.2)
			(type default)
		)
		(layer "In3.Cu")
	)
	(gr_arc
		(start 232.876344 -267.391896)
		(mid 233.386757 -267.90269)
		(end 233.897424 -267.39215)
		(stroke
			(width 0.2)
			(type default)
		)
		(layer "In3.Cu")
	)
	(gr_line
		(start 232.876344 -266.57935)
		(end 232.876344 -267.391896)
		(stroke
			(width 0.2)
			(type default)
		)
		(layer "In3.Cu")
	)
	(gr_arc
		(start 232.876344 -164.391848)
		(mid 233.386757 -164.902642)
		(end 233.897424 -164.392102)
		(stroke
			(width 0.2)
			(type default)
		)
		(layer "In3.Cu")
	)
	(gr_line
		(start 232.876344 -163.579302)
		(end 232.876344 -164.391848)
		(stroke
			(width 0.2)
			(type default)
		)
		(layer "In3.Cu")
	)
	(gr_arc
		(start 232.876344 -61.3918)
		(mid 233.386757 -61.902594)
		(end 233.897424 -61.392054)
		(stroke
			(width 0.2)
			(type default)
		)
		(layer "In3.Cu")
	)
	(gr_line
		(start 232.876344 -60.579254)
		(end 232.876344 -61.3918)
		(stroke
			(width 0.2)
			(type default)
		)
		(layer "In3.Cu")
	)
	(gr_line
		(start 233.897424 -473.392246)
		(end 233.897424 -472.579446)
		(stroke
			(width 0.2)
			(type default)
		)
		(layer "In3.Cu")
	)
	(gr_arc
		(start 233.897424 -472.579446)
		(mid 233.386884 -472.068906)
		(end 232.876344 -472.579446)
		(stroke
			(width 0.2)
			(type default)
		)
		(layer "In3.Cu")
	)
	(gr_line
		(start 233.897424 -370.392198)
		(end 233.897424 -369.579398)
		(stroke
			(width 0.2)
			(type default)
		)
		(layer "In3.Cu")
	)
	(gr_arc
		(start 233.897424 -369.579398)
		(mid 233.386884 -369.068858)
		(end 232.876344 -369.579398)
		(stroke
			(width 0.2)
			(type default)
		)
		(layer "In3.Cu")
	)
	(gr_line
		(start 233.897424 -267.39215)
		(end 233.897424 -266.57935)
		(stroke
			(width 0.2)
			(type default)
		)
		(layer "In3.Cu")
	)
	(gr_arc
		(start 233.897424 -266.57935)
		(mid 233.386884 -266.06881)
		(end 232.876344 -266.57935)
		(stroke
			(width 0.2)
			(type default)
		)
		(layer "In3.Cu")
	)
	(gr_line
		(start 233.897424 -164.392102)
		(end 233.897424 -163.579302)
		(stroke
			(width 0.2)
			(type default)
		)
		(layer "In3.Cu")
	)
	(gr_arc
		(start 233.897424 -163.579302)
		(mid 233.386884 -163.068762)
		(end 232.876344 -163.579302)
		(stroke
			(width 0.2)
			(type default)
		)
		(layer "In3.Cu")
	)
	(gr_line
		(start 233.897424 -61.392054)
		(end 233.897424 -60.579254)
		(stroke
			(width 0.2)
			(type default)
		)
		(layer "In3.Cu")
	)
	(gr_arc
		(start 233.897424 -60.579254)
		(mid 233.386884 -60.068714)
		(end 232.876344 -60.579254)
		(stroke
			(width 0.2)
			(type default)
		)
		(layer "In3.Cu")
	)
	(gr_line
		(start 252.394974 -410.485082)
		(end 258.899914 -410.485082)
		(stroke
			(width 1.524)
			(type default)
		)
		(layer "In3.Cu")
	)
	(gr_arc
		(start 252.394974 -409.41498)
		(mid 251.859796 -409.950158)
		(end 252.394974 -410.485082)
		(stroke
			(width 1.524)
			(type default)
		)
		(layer "In3.Cu")
	)
	(gr_line
		(start 258.899914 -410.485082)
		(end 259.899912 -411.48508)
		(stroke
			(width 1.524)
			(type default)
		)
		(layer "In3.Cu")
	)
	(gr_line
		(start 258.899914 -409.41498)
		(end 252.394974 -409.41498)
		(stroke
			(width 1.524)
			(type default)
		)
		(layer "In3.Cu")
	)
	(gr_arc
		(start 259.899912 -425.69003)
		(mid 260.307091 -426.672919)
		(end 261.290054 -427.079918)
		(stroke
			(width 1.524)
			(type default)
		)
		(layer "In3.Cu")
	)
	(gr_line
		(start 259.899912 -411.48508)
		(end 259.899912 -425.69003)
		(stroke
			(width 1.524)
			(type default)
		)
		(layer "In3.Cu")
	)
	(gr_line
		(start 259.899912 -408.414982)
		(end 258.899914 -409.41498)
		(stroke
			(width 1.524)
			(type default)
		)
		(layer "In3.Cu")
	)
	(gr_line
		(start 259.899912 -364.309914)
		(end 259.899912 -408.414982)
		(stroke
			(width 1.524)
			(type default)
		)
		(layer "In3.Cu")
	)
	(gr_line
		(start 261.290054 -427.079918)
		(end 262.50011 -427.079918)
		(stroke
			(width 1.524)
			(type default)
		)
		(layer "In3.Cu")
	)
	(gr_arc
		(start 261.290054 -362.920026)
		(mid 260.307165 -363.327099)
		(end 259.899912 -364.309914)
		(stroke
			(width 1.524)
			(type default)
		)
		(layer "In3.Cu")
	)
	(gr_line
		(start 262.50011 -506.000004)
		(end 0.999998 -506.000004)
		(stroke
			(width 1.524)
			(type default)
		)
		(layer "In3.Cu")
	)
	(gr_arc
		(start 262.50011 -506.000004)
		(mid 263.207211 -505.707108)
		(end 263.500108 -505.000006)
		(stroke
			(width 1.524)
			(type default)
		)
		(layer "In3.Cu")
	)
	(gr_line
		(start 262.50011 -427.079918)
		(end 263.500108 -428.079916)
		(stroke
			(width 1.524)
			(type default)
		)
		(layer "In3.Cu")
	)
	(gr_line
		(start 262.50011 -362.920026)
		(end 261.290054 -362.920026)
		(stroke
			(width 1.524)
			(type default)
		)
		(layer "In3.Cu")
	)
	(gr_line
		(start 263.500108 -428.079916)
		(end 263.500108 -505.000006)
		(stroke
			(width 1.524)
			(type default)
		)
		(layer "In3.Cu")
	)
	(gr_line
		(start 263.500108 -361.920028)
		(end 262.50011 -362.920026)
		(stroke
			(width 1.524)
			(type default)
		)
		(layer "In3.Cu")
	)
	(gr_arc
		(start 263.500108 -0.999998)
		(mid 263.207215 -0.29289)
		(end 262.50011 0)
		(stroke
			(width 1.524)
			(type default)
		)
		(layer "In3.Cu")
	)
	(gr_line
		(start 263.500108 -0.999998)
		(end 263.500108 -361.920028)
		(stroke
			(width 1.524)
			(type default)
		)
		(layer "In3.Cu")
	)
	(gr_line
		(start 0 -505.000006)
		(end 0 -421.942006)
		(stroke
			(width 2.54)
			(type default)
		)
		(layer "In4.Cu")
	)
	(gr_arc
		(start 0 -505.000006)
		(mid 0.292895 -505.707108)
		(end 0.999998 -506.000004)
		(stroke
			(width 2.54)
			(type default)
		)
		(layer "In4.Cu")
	)
	(gr_line
		(start 0 -421.942006)
		(end 0.500126 -421.44188)
		(stroke
			(width 2.54)
			(type default)
		)
		(layer "In4.Cu")
	)
	(gr_line
		(start 0 -418.742114)
		(end 0 -315.941964)
		(stroke
			(width 2.54)
			(type default)
		)
		(layer "In4.Cu")
	)
	(gr_line
		(start 0 -315.941964)
		(end 0.500126 -315.442092)
		(stroke
			(width 2.54)
			(type default)
		)
		(layer "In4.Cu")
	)
	(gr_line
		(start 0 -312.742072)
		(end 0 -189.941962)
		(stroke
			(width 2.54)
			(type default)
		)
		(layer "In4.Cu")
	)
	(gr_line
		(start 0 -189.941962)
		(end 0.500126 -189.44209)
		(stroke
			(width 2.54)
			(type default)
		)
		(layer "In4.Cu")
	)
	(gr_line
		(start 0 -186.74207)
		(end 0 -0.999998)
		(stroke
			(width 2.54)
			(type default)
		)
		(layer "In4.Cu")
	)
	(gr_line
		(start 0.500126 -421.44188)
		(end 4.400042 -421.44188)
		(stroke
			(width 2.54)
			(type default)
		)
		(layer "In4.Cu")
	)
	(gr_line
		(start 0.500126 -419.241986)
		(end 0 -418.742114)
		(stroke
			(width 2.54)
			(type default)
		)
		(layer "In4.Cu")
	)
	(gr_line
		(start 0.500126 -315.442092)
		(end 4.400042 -315.442092)
		(stroke
			(width 2.54)
			(type default)
		)
		(layer "In4.Cu")
	)
	(gr_line
		(start 0.500126 -313.241944)
		(end 0 -312.742072)
		(stroke
			(width 2.54)
			(type default)
		)
		(layer "In4.Cu")
	)
	(gr_line
		(start 0.500126 -189.44209)
		(end 4.400042 -189.44209)
		(stroke
			(width 2.54)
			(type default)
		)
		(layer "In4.Cu")
	)
	(gr_line
		(start 0.500126 -187.241942)
		(end 0 -186.74207)
		(stroke
			(width 2.54)
			(type default)
		)
		(layer "In4.Cu")
	)
	(gr_arc
		(start 0.999998 0)
		(mid 0.292893 -0.292893)
		(end 0 -0.999998)
		(stroke
			(width 2.54)
			(type default)
		)
		(layer "In4.Cu")
	)
	(gr_line
		(start 0.999998 0)
		(end 30.80004 0)
		(stroke
			(width 2.54)
			(type default)
		)
		(layer "In4.Cu")
	)
	(gr_arc
		(start 4.400042 -421.44188)
		(mid 5.499862 -420.34206)
		(end 4.400042 -419.241986)
		(stroke
			(width 2.54)
			(type default)
		)
		(layer "In4.Cu")
	)
	(gr_line
		(start 4.400042 -419.241986)
		(end 0.500126 -419.241986)
		(stroke
			(width 2.54)
			(type default)
		)
		(layer "In4.Cu")
	)
	(gr_arc
		(start 4.400042 -315.442092)
		(mid 5.500116 -314.342018)
		(end 4.400042 -313.241944)
		(stroke
			(width 2.54)
			(type default)
		)
		(layer "In4.Cu")
	)
	(gr_line
		(start 4.400042 -313.241944)
		(end 0.500126 -313.241944)
		(stroke
			(width 2.54)
			(type default)
		)
		(layer "In4.Cu")
	)
	(gr_arc
		(start 4.400042 -189.44209)
		(mid 5.500116 -188.342016)
		(end 4.400042 -187.241942)
		(stroke
			(width 2.54)
			(type default)
		)
		(layer "In4.Cu")
	)
	(gr_line
		(start 4.400042 -187.241942)
		(end 0.500126 -187.241942)
		(stroke
			(width 2.54)
			(type default)
		)
		(layer "In4.Cu")
	)
	(gr_arc
		(start 4.56946 -445.54775)
		(mid 5.079873 -446.058544)
		(end 5.59054 -445.548004)
		(stroke
			(width 0.2)
			(type default)
		)
		(layer "In4.Cu")
	)
	(gr_line
		(start 4.56946 -444.735204)
		(end 4.56946 -445.54775)
		(stroke
			(width 0.2)
			(type default)
		)
		(layer "In4.Cu")
	)
	(gr_arc
		(start 4.56946 -442.347858)
		(mid 5.079873 -442.858652)
		(end 5.59054 -442.348112)
		(stroke
			(width 0.2)
			(type default)
		)
		(layer "In4.Cu")
	)
	(gr_line
		(start 4.56946 -441.535312)
		(end 4.56946 -442.347858)
		(stroke
			(width 0.2)
			(type default)
		)
		(layer "In4.Cu")
	)
	(gr_arc
		(start 4.56946 -439.147712)
		(mid 5.079873 -439.658506)
		(end 5.59054 -439.147966)
		(stroke
			(width 0.2)
			(type default)
		)
		(layer "In4.Cu")
	)
	(gr_line
		(start 4.56946 -438.335166)
		(end 4.56946 -439.147712)
		(stroke
			(width 0.2)
			(type default)
		)
		(layer "In4.Cu")
	)
	(gr_arc
		(start 4.56946 -435.94782)
		(mid 5.079873 -436.458614)
		(end 5.59054 -435.948074)
		(stroke
			(width 0.2)
			(type default)
		)
		(layer "In4.Cu")
	)
	(gr_line
		(start 4.56946 -435.135274)
		(end 4.56946 -435.94782)
		(stroke
			(width 0.2)
			(type default)
		)
		(layer "In4.Cu")
	)
	(gr_arc
		(start 4.56946 -430.347882)
		(mid 5.08 -430.858422)
		(end 5.59054 -430.347882)
		(stroke
			(width 0.2)
			(type default)
		)
		(layer "In4.Cu")
	)
	(gr_line
		(start 4.56946 -429.535082)
		(end 4.56946 -430.347882)
		(stroke
			(width 0.2)
			(type default)
		)
		(layer "In4.Cu")
	)
	(gr_arc
		(start 4.56946 -427.14799)
		(mid 5.08 -427.65853)
		(end 5.59054 -427.14799)
		(stroke
			(width 0.2)
			(type default)
		)
		(layer "In4.Cu")
	)
	(gr_line
		(start 4.56946 -426.33519)
		(end 4.56946 -427.14799)
		(stroke
			(width 0.2)
			(type default)
		)
		(layer "In4.Cu")
	)
	(gr_arc
		(start 4.56946 -423.948098)
		(mid 5.08 -424.458638)
		(end 5.59054 -423.948098)
		(stroke
			(width 0.2)
			(type default)
		)
		(layer "In4.Cu")
	)
	(gr_line
		(start 4.56946 -423.135298)
		(end 4.56946 -423.948098)
		(stroke
			(width 0.2)
			(type default)
		)
		(layer "In4.Cu")
	)
	(gr_arc
		(start 4.56946 -417.54806)
		(mid 5.08 -418.0586)
		(end 5.59054 -417.54806)
		(stroke
			(width 0.2)
			(type default)
		)
		(layer "In4.Cu")
	)
	(gr_line
		(start 4.56946 -416.73526)
		(end 4.56946 -417.54806)
		(stroke
			(width 0.2)
			(type default)
		)
		(layer "In4.Cu")
	)
	(gr_arc
		(start 4.56946 -414.34766)
		(mid 5.079873 -414.858454)
		(end 5.59054 -414.347914)
		(stroke
			(width 0.2)
			(type default)
		)
		(layer "In4.Cu")
	)
	(gr_line
		(start 4.56946 -413.535114)
		(end 4.56946 -414.34766)
		(stroke
			(width 0.2)
			(type default)
		)
		(layer "In4.Cu")
	)
	(gr_arc
		(start 4.56946 -411.147768)
		(mid 5.079873 -411.658562)
		(end 5.59054 -411.148022)
		(stroke
			(width 0.2)
			(type default)
		)
		(layer "In4.Cu")
	)
	(gr_line
		(start 4.56946 -410.335222)
		(end 4.56946 -411.147768)
		(stroke
			(width 0.2)
			(type default)
		)
		(layer "In4.Cu")
	)
	(gr_arc
		(start 4.56946 -407.947622)
		(mid 5.079873 -408.458416)
		(end 5.59054 -407.947876)
		(stroke
			(width 0.2)
			(type default)
		)
		(layer "In4.Cu")
	)
	(gr_line
		(start 4.56946 -407.135076)
		(end 4.56946 -407.947622)
		(stroke
			(width 0.2)
			(type default)
		)
		(layer "In4.Cu")
	)
	(gr_arc
		(start 4.56946 -404.74773)
		(mid 5.079873 -405.258524)
		(end 5.59054 -404.747984)
		(stroke
			(width 0.2)
			(type default)
		)
		(layer "In4.Cu")
	)
	(gr_line
		(start 4.56946 -403.935184)
		(end 4.56946 -404.74773)
		(stroke
			(width 0.2)
			(type default)
		)
		(layer "In4.Cu")
	)
	(gr_arc
		(start 4.56946 -399.148046)
		(mid 5.08 -399.658586)
		(end 5.59054 -399.148046)
		(stroke
			(width 0.2)
			(type default)
		)
		(layer "In4.Cu")
	)
	(gr_line
		(start 4.56946 -398.335246)
		(end 4.56946 -399.148046)
		(stroke
			(width 0.2)
			(type default)
		)
		(layer "In4.Cu")
	)
	(gr_arc
		(start 4.56946 -395.9479)
		(mid 5.08 -396.45844)
		(end 5.59054 -395.9479)
		(stroke
			(width 0.2)
			(type default)
		)
		(layer "In4.Cu")
	)
	(gr_line
		(start 4.56946 -395.1351)
		(end 4.56946 -395.9479)
		(stroke
			(width 0.2)
			(type default)
		)
		(layer "In4.Cu")
	)
	(gr_arc
		(start 4.56946 -392.748008)
		(mid 5.08 -393.258548)
		(end 5.59054 -392.748008)
		(stroke
			(width 0.2)
			(type default)
		)
		(layer "In4.Cu")
	)
	(gr_line
		(start 4.56946 -391.935208)
		(end 4.56946 -392.748008)
		(stroke
			(width 0.2)
			(type default)
		)
		(layer "In4.Cu")
	)
	(gr_arc
		(start 4.56946 -389.548116)
		(mid 5.08 -390.058656)
		(end 5.59054 -389.548116)
		(stroke
			(width 0.2)
			(type default)
		)
		(layer "In4.Cu")
	)
	(gr_line
		(start 4.56946 -388.735316)
		(end 4.56946 -389.548116)
		(stroke
			(width 0.2)
			(type default)
		)
		(layer "In4.Cu")
	)
	(gr_arc
		(start 4.56946 -358.74833)
		(mid 5.08 -359.25887)
		(end 5.59054 -358.74833)
		(stroke
			(width 0.2)
			(type default)
		)
		(layer "In4.Cu")
	)
	(gr_line
		(start 4.56946 -357.93553)
		(end 4.56946 -358.74833)
		(stroke
			(width 0.2)
			(type default)
		)
		(layer "In4.Cu")
	)
	(gr_arc
		(start 4.56946 -355.548184)
		(mid 5.08 -356.058724)
		(end 5.59054 -355.548184)
		(stroke
			(width 0.2)
			(type default)
		)
		(layer "In4.Cu")
	)
	(gr_line
		(start 4.56946 -354.735384)
		(end 4.56946 -355.548184)
		(stroke
			(width 0.2)
			(type default)
		)
		(layer "In4.Cu")
	)
	(gr_arc
		(start 4.56946 -352.348292)
		(mid 5.08 -352.858832)
		(end 5.59054 -352.348292)
		(stroke
			(width 0.2)
			(type default)
		)
		(layer "In4.Cu")
	)
	(gr_line
		(start 4.56946 -351.535492)
		(end 4.56946 -352.348292)
		(stroke
			(width 0.2)
			(type default)
		)
		(layer "In4.Cu")
	)
	(gr_arc
		(start 4.56946 -349.148146)
		(mid 5.08 -349.658686)
		(end 5.59054 -349.148146)
		(stroke
			(width 0.2)
			(type default)
		)
		(layer "In4.Cu")
	)
	(gr_line
		(start 4.56946 -348.335346)
		(end 4.56946 -349.148146)
		(stroke
			(width 0.2)
			(type default)
		)
		(layer "In4.Cu")
	)
	(gr_arc
		(start 4.56946 -345.948254)
		(mid 5.08 -346.458794)
		(end 5.59054 -345.948254)
		(stroke
			(width 0.2)
			(type default)
		)
		(layer "In4.Cu")
	)
	(gr_line
		(start 4.56946 -345.135454)
		(end 4.56946 -345.948254)
		(stroke
			(width 0.2)
			(type default)
		)
		(layer "In4.Cu")
	)
	(gr_arc
		(start 4.56946 -342.748108)
		(mid 5.08 -343.258648)
		(end 5.59054 -342.748108)
		(stroke
			(width 0.2)
			(type default)
		)
		(layer "In4.Cu")
	)
	(gr_line
		(start 4.56946 -341.935308)
		(end 4.56946 -342.748108)
		(stroke
			(width 0.2)
			(type default)
		)
		(layer "In4.Cu")
	)
	(gr_arc
		(start 4.56946 -339.548216)
		(mid 5.08 -340.058756)
		(end 5.59054 -339.548216)
		(stroke
			(width 0.2)
			(type default)
		)
		(layer "In4.Cu")
	)
	(gr_line
		(start 4.56946 -338.735416)
		(end 4.56946 -339.548216)
		(stroke
			(width 0.2)
			(type default)
		)
		(layer "In4.Cu")
	)
	(gr_arc
		(start 4.56946 -336.348324)
		(mid 5.08 -336.858864)
		(end 5.59054 -336.348324)
		(stroke
			(width 0.2)
			(type default)
		)
		(layer "In4.Cu")
	)
	(gr_line
		(start 4.56946 -335.535524)
		(end 4.56946 -336.348324)
		(stroke
			(width 0.2)
			(type default)
		)
		(layer "In4.Cu")
	)
	(gr_arc
		(start 4.56946 -330.748132)
		(mid 5.08 -331.258672)
		(end 5.59054 -330.748132)
		(stroke
			(width 0.2)
			(type default)
		)
		(layer "In4.Cu")
	)
	(gr_line
		(start 4.56946 -329.935332)
		(end 4.56946 -330.748132)
		(stroke
			(width 0.2)
			(type default)
		)
		(layer "In4.Cu")
	)
	(gr_arc
		(start 4.56946 -327.54824)
		(mid 5.08 -328.05878)
		(end 5.59054 -327.54824)
		(stroke
			(width 0.2)
			(type default)
		)
		(layer "In4.Cu")
	)
	(gr_line
		(start 4.56946 -326.73544)
		(end 4.56946 -327.54824)
		(stroke
			(width 0.2)
			(type default)
		)
		(layer "In4.Cu")
	)
	(gr_arc
		(start 4.56946 -324.348094)
		(mid 5.08 -324.858634)
		(end 5.59054 -324.348094)
		(stroke
			(width 0.2)
			(type default)
		)
		(layer "In4.Cu")
	)
	(gr_line
		(start 4.56946 -323.535294)
		(end 4.56946 -324.348094)
		(stroke
			(width 0.2)
			(type default)
		)
		(layer "In4.Cu")
	)
	(gr_arc
		(start 4.56946 -321.148202)
		(mid 5.08 -321.658742)
		(end 5.59054 -321.148202)
		(stroke
			(width 0.2)
			(type default)
		)
		(layer "In4.Cu")
	)
	(gr_line
		(start 4.56946 -320.335402)
		(end 4.56946 -321.148202)
		(stroke
			(width 0.2)
			(type default)
		)
		(layer "In4.Cu")
	)
	(gr_arc
		(start 4.56946 -317.94831)
		(mid 5.08 -318.45885)
		(end 5.59054 -317.94831)
		(stroke
			(width 0.2)
			(type default)
		)
		(layer "In4.Cu")
	)
	(gr_line
		(start 4.56946 -317.13551)
		(end 4.56946 -317.94831)
		(stroke
			(width 0.2)
			(type default)
		)
		(layer "In4.Cu")
	)
	(gr_arc
		(start 4.56946 -309.948326)
		(mid 5.08 -310.458866)
		(end 5.59054 -309.948326)
		(stroke
			(width 0.2)
			(type default)
		)
		(layer "In4.Cu")
	)
	(gr_line
		(start 4.56946 -309.135526)
		(end 4.56946 -309.948326)
		(stroke
			(width 0.2)
			(type default)
		)
		(layer "In4.Cu")
	)
	(gr_arc
		(start 4.56946 -306.74818)
		(mid 5.08 -307.25872)
		(end 5.59054 -306.74818)
		(stroke
			(width 0.2)
			(type default)
		)
		(layer "In4.Cu")
	)
	(gr_line
		(start 4.56946 -305.93538)
		(end 4.56946 -306.74818)
		(stroke
			(width 0.2)
			(type default)
		)
		(layer "In4.Cu")
	)
	(gr_arc
		(start 4.56946 -303.548288)
		(mid 5.08 -304.058828)
		(end 5.59054 -303.548288)
		(stroke
			(width 0.2)
			(type default)
		)
		(layer "In4.Cu")
	)
	(gr_line
		(start 4.56946 -302.735488)
		(end 4.56946 -303.548288)
		(stroke
			(width 0.2)
			(type default)
		)
		(layer "In4.Cu")
	)
	(gr_arc
		(start 4.56946 -300.348142)
		(mid 5.08 -300.858682)
		(end 5.59054 -300.348142)
		(stroke
			(width 0.2)
			(type default)
		)
		(layer "In4.Cu")
	)
	(gr_line
		(start 4.56946 -299.535342)
		(end 4.56946 -300.348142)
		(stroke
			(width 0.2)
			(type default)
		)
		(layer "In4.Cu")
	)
	(gr_arc
		(start 4.56946 -297.14825)
		(mid 5.08 -297.65879)
		(end 5.59054 -297.14825)
		(stroke
			(width 0.2)
			(type default)
		)
		(layer "In4.Cu")
	)
	(gr_line
		(start 4.56946 -296.33545)
		(end 4.56946 -297.14825)
		(stroke
			(width 0.2)
			(type default)
		)
		(layer "In4.Cu")
	)
	(gr_arc
		(start 4.56946 -293.948104)
		(mid 5.08 -294.458644)
		(end 5.59054 -293.948104)
		(stroke
			(width 0.2)
			(type default)
		)
		(layer "In4.Cu")
	)
	(gr_line
		(start 4.56946 -293.135304)
		(end 4.56946 -293.948104)
		(stroke
			(width 0.2)
			(type default)
		)
		(layer "In4.Cu")
	)
	(gr_arc
		(start 4.56946 -290.748212)
		(mid 5.08 -291.258752)
		(end 5.59054 -290.748212)
		(stroke
			(width 0.2)
			(type default)
		)
		(layer "In4.Cu")
	)
	(gr_line
		(start 4.56946 -289.935412)
		(end 4.56946 -290.748212)
		(stroke
			(width 0.2)
			(type default)
		)
		(layer "In4.Cu")
	)
	(gr_arc
		(start 4.56946 -284.348174)
		(mid 5.08 -284.858714)
		(end 5.59054 -284.348174)
		(stroke
			(width 0.2)
			(type default)
		)
		(layer "In4.Cu")
	)
	(gr_line
		(start 4.56946 -283.535374)
		(end 4.56946 -284.348174)
		(stroke
			(width 0.2)
			(type default)
		)
		(layer "In4.Cu")
	)
	(gr_arc
		(start 4.56946 -281.148282)
		(mid 5.08 -281.658822)
		(end 5.59054 -281.148282)
		(stroke
			(width 0.2)
			(type default)
		)
		(layer "In4.Cu")
	)
	(gr_line
		(start 4.56946 -280.335482)
		(end 4.56946 -281.148282)
		(stroke
			(width 0.2)
			(type default)
		)
		(layer "In4.Cu")
	)
	(gr_arc
		(start 4.56946 -232.748328)
		(mid 5.08 -233.258868)
		(end 5.59054 -232.748328)
		(stroke
			(width 0.2)
			(type default)
		)
		(layer "In4.Cu")
	)
	(gr_line
		(start 4.56946 -231.935528)
		(end 4.56946 -232.748328)
		(stroke
			(width 0.2)
			(type default)
		)
		(layer "In4.Cu")
	)
	(gr_arc
		(start 4.56946 -229.548182)
		(mid 5.08 -230.058722)
		(end 5.59054 -229.548182)
		(stroke
			(width 0.2)
			(type default)
		)
		(layer "In4.Cu")
	)
	(gr_line
		(start 4.56946 -228.735382)
		(end 4.56946 -229.548182)
		(stroke
			(width 0.2)
			(type default)
		)
		(layer "In4.Cu")
	)
	(gr_arc
		(start 4.56946 -223.148144)
		(mid 5.08 -223.658684)
		(end 5.59054 -223.148144)
		(stroke
			(width 0.2)
			(type default)
		)
		(layer "In4.Cu")
	)
	(gr_line
		(start 4.56946 -222.335344)
		(end 4.56946 -223.148144)
		(stroke
			(width 0.2)
			(type default)
		)
		(layer "In4.Cu")
	)
	(gr_arc
		(start 4.56946 -219.948252)
		(mid 5.08 -220.458792)
		(end 5.59054 -219.948252)
		(stroke
			(width 0.2)
			(type default)
		)
		(layer "In4.Cu")
	)
	(gr_line
		(start 4.56946 -219.135452)
		(end 4.56946 -219.948252)
		(stroke
			(width 0.2)
			(type default)
		)
		(layer "In4.Cu")
	)
	(gr_arc
		(start 4.56946 -216.748106)
		(mid 5.08 -217.258646)
		(end 5.59054 -216.748106)
		(stroke
			(width 0.2)
			(type default)
		)
		(layer "In4.Cu")
	)
	(gr_line
		(start 4.56946 -215.935306)
		(end 4.56946 -216.748106)
		(stroke
			(width 0.2)
			(type default)
		)
		(layer "In4.Cu")
	)
	(gr_arc
		(start 4.56946 -213.548214)
		(mid 5.08 -214.058754)
		(end 5.59054 -213.548214)
		(stroke
			(width 0.2)
			(type default)
		)
		(layer "In4.Cu")
	)
	(gr_line
		(start 4.56946 -212.735414)
		(end 4.56946 -213.548214)
		(stroke
			(width 0.2)
			(type default)
		)
		(layer "In4.Cu")
	)
	(gr_arc
		(start 4.56946 -210.348322)
		(mid 5.08 -210.858862)
		(end 5.59054 -210.348322)
		(stroke
			(width 0.2)
			(type default)
		)
		(layer "In4.Cu")
	)
	(gr_line
		(start 4.56946 -209.535522)
		(end 4.56946 -210.348322)
		(stroke
			(width 0.2)
			(type default)
		)
		(layer "In4.Cu")
	)
	(gr_arc
		(start 4.56946 -207.148176)
		(mid 5.08 -207.658716)
		(end 5.59054 -207.148176)
		(stroke
			(width 0.2)
			(type default)
		)
		(layer "In4.Cu")
	)
	(gr_line
		(start 4.56946 -206.335376)
		(end 4.56946 -207.148176)
		(stroke
			(width 0.2)
			(type default)
		)
		(layer "In4.Cu")
	)
	(gr_arc
		(start 4.56946 -203.948284)
		(mid 5.08 -204.458824)
		(end 5.59054 -203.948284)
		(stroke
			(width 0.2)
			(type default)
		)
		(layer "In4.Cu")
	)
	(gr_line
		(start 4.56946 -203.135484)
		(end 4.56946 -203.948284)
		(stroke
			(width 0.2)
			(type default)
		)
		(layer "In4.Cu")
	)
	(gr_arc
		(start 4.56946 -200.748138)
		(mid 5.08 -201.258678)
		(end 5.59054 -200.748138)
		(stroke
			(width 0.2)
			(type default)
		)
		(layer "In4.Cu")
	)
	(gr_line
		(start 4.56946 -199.935338)
		(end 4.56946 -200.748138)
		(stroke
			(width 0.2)
			(type default)
		)
		(layer "In4.Cu")
	)
	(gr_arc
		(start 4.56946 -195.1482)
		(mid 5.08 -195.65874)
		(end 5.59054 -195.1482)
		(stroke
			(width 0.2)
			(type default)
		)
		(layer "In4.Cu")
	)
	(gr_line
		(start 4.56946 -194.3354)
		(end 4.56946 -195.1482)
		(stroke
			(width 0.2)
			(type default)
		)
		(layer "In4.Cu")
	)
	(gr_arc
		(start 4.56946 -191.948308)
		(mid 5.08 -192.458848)
		(end 5.59054 -191.948308)
		(stroke
			(width 0.2)
			(type default)
		)
		(layer "In4.Cu")
	)
	(gr_line
		(start 4.56946 -191.135508)
		(end 4.56946 -191.948308)
		(stroke
			(width 0.2)
			(type default)
		)
		(layer "In4.Cu")
	)
	(gr_arc
		(start 4.56946 -183.948324)
		(mid 5.08 -184.458864)
		(end 5.59054 -183.948324)
		(stroke
			(width 0.2)
			(type default)
		)
		(layer "In4.Cu")
	)
	(gr_line
		(start 4.56946 -183.135524)
		(end 4.56946 -183.948324)
		(stroke
			(width 0.2)
			(type default)
		)
		(layer "In4.Cu")
	)
	(gr_arc
		(start 4.56946 -180.748178)
		(mid 5.08 -181.258718)
		(end 5.59054 -180.748178)
		(stroke
			(width 0.2)
			(type default)
		)
		(layer "In4.Cu")
	)
	(gr_line
		(start 4.56946 -179.935378)
		(end 4.56946 -180.748178)
		(stroke
			(width 0.2)
			(type default)
		)
		(layer "In4.Cu")
	)
	(gr_arc
		(start 4.56946 -177.548286)
		(mid 5.08 -178.058826)
		(end 5.59054 -177.548286)
		(stroke
			(width 0.2)
			(type default)
		)
		(layer "In4.Cu")
	)
	(gr_line
		(start 4.56946 -176.735486)
		(end 4.56946 -177.548286)
		(stroke
			(width 0.2)
			(type default)
		)
		(layer "In4.Cu")
	)
	(gr_arc
		(start 4.56946 -174.34814)
		(mid 5.08 -174.85868)
		(end 5.59054 -174.34814)
		(stroke
			(width 0.2)
			(type default)
		)
		(layer "In4.Cu")
	)
	(gr_line
		(start 4.56946 -173.53534)
		(end 4.56946 -174.34814)
		(stroke
			(width 0.2)
			(type default)
		)
		(layer "In4.Cu")
	)
	(gr_arc
		(start 4.56946 -171.148248)
		(mid 5.08 -171.658788)
		(end 5.59054 -171.148248)
		(stroke
			(width 0.2)
			(type default)
		)
		(layer "In4.Cu")
	)
	(gr_line
		(start 4.56946 -170.335448)
		(end 4.56946 -171.148248)
		(stroke
			(width 0.2)
			(type default)
		)
		(layer "In4.Cu")
	)
	(gr_arc
		(start 4.56946 -167.948102)
		(mid 5.08 -168.458642)
		(end 5.59054 -167.948102)
		(stroke
			(width 0.2)
			(type default)
		)
		(layer "In4.Cu")
	)
	(gr_line
		(start 4.56946 -167.135302)
		(end 4.56946 -167.948102)
		(stroke
			(width 0.2)
			(type default)
		)
		(layer "In4.Cu")
	)
	(gr_arc
		(start 4.56946 -164.74821)
		(mid 5.08 -165.25875)
		(end 5.59054 -164.74821)
		(stroke
			(width 0.2)
			(type default)
		)
		(layer "In4.Cu")
	)
	(gr_line
		(start 4.56946 -163.93541)
		(end 4.56946 -164.74821)
		(stroke
			(width 0.2)
			(type default)
		)
		(layer "In4.Cu")
	)
	(gr_arc
		(start 4.56946 -161.548318)
		(mid 5.08 -162.058858)
		(end 5.59054 -161.548318)
		(stroke
			(width 0.2)
			(type default)
		)
		(layer "In4.Cu")
	)
	(gr_line
		(start 4.56946 -160.735518)
		(end 4.56946 -161.548318)
		(stroke
			(width 0.2)
			(type default)
		)
		(layer "In4.Cu")
	)
	(gr_arc
		(start 4.56946 -158.348172)
		(mid 5.08 -158.858712)
		(end 5.59054 -158.348172)
		(stroke
			(width 0.2)
			(type default)
		)
		(layer "In4.Cu")
	)
	(gr_line
		(start 4.56946 -157.535372)
		(end 4.56946 -158.348172)
		(stroke
			(width 0.2)
			(type default)
		)
		(layer "In4.Cu")
	)
	(gr_arc
		(start 4.56946 -155.14828)
		(mid 5.08 -155.65882)
		(end 5.59054 -155.14828)
		(stroke
			(width 0.2)
			(type default)
		)
		(layer "In4.Cu")
	)
	(gr_line
		(start 4.56946 -154.33548)
		(end 4.56946 -155.14828)
		(stroke
			(width 0.2)
			(type default)
		)
		(layer "In4.Cu")
	)
	(gr_line
		(start 5.59054 -445.548004)
		(end 5.59054 -444.735204)
		(stroke
			(width 0.2)
			(type default)
		)
		(layer "In4.Cu")
	)
	(gr_arc
		(start 5.59054 -444.735204)
		(mid 5.08 -444.224664)
		(end 4.56946 -444.735204)
		(stroke
			(width 0.2)
			(type default)
		)
		(layer "In4.Cu")
	)
	(gr_line
		(start 5.59054 -442.348112)
		(end 5.59054 -441.535312)
		(stroke
			(width 0.2)
			(type default)
		)
		(layer "In4.Cu")
	)
	(gr_arc
		(start 5.59054 -441.535312)
		(mid 5.08 -441.024772)
		(end 4.56946 -441.535312)
		(stroke
			(width 0.2)
			(type default)
		)
		(layer "In4.Cu")
	)
	(gr_line
		(start 5.59054 -439.147966)
		(end 5.59054 -438.335166)
		(stroke
			(width 0.2)
			(type default)
		)
		(layer "In4.Cu")
	)
	(gr_arc
		(start 5.59054 -438.335166)
		(mid 5.08 -437.824626)
		(end 4.56946 -438.335166)
		(stroke
			(width 0.2)
			(type default)
		)
		(layer "In4.Cu")
	)
	(gr_line
		(start 5.59054 -435.948074)
		(end 5.59054 -435.135274)
		(stroke
			(width 0.2)
			(type default)
		)
		(layer "In4.Cu")
	)
	(gr_arc
		(start 5.59054 -435.135274)
		(mid 5.08 -434.624734)
		(end 4.56946 -435.135274)
		(stroke
			(width 0.2)
			(type default)
		)
		(layer "In4.Cu")
	)
	(gr_line
		(start 5.59054 -430.347882)
		(end 5.59054 -429.535336)
		(stroke
			(width 0.2)
			(type default)
		)
		(layer "In4.Cu")
	)
	(gr_arc
		(start 5.59054 -429.535336)
		(mid 5.080127 -429.024542)
		(end 4.56946 -429.535082)
		(stroke
			(width 0.2)
			(type default)
		)
		(layer "In4.Cu")
	)
	(gr_line
		(start 5.59054 -427.14799)
		(end 5.59054 -426.335444)
		(stroke
			(width 0.2)
			(type default)
		)
		(layer "In4.Cu")
	)
	(gr_arc
		(start 5.59054 -426.335444)
		(mid 5.080127 -425.82465)
		(end 4.56946 -426.33519)
		(stroke
			(width 0.2)
			(type default)
		)
		(layer "In4.Cu")
	)
	(gr_line
		(start 5.59054 -423.948098)
		(end 5.59054 -423.135552)
		(stroke
			(width 0.2)
			(type default)
		)
		(layer "In4.Cu")
	)
	(gr_arc
		(start 5.59054 -423.135552)
		(mid 5.080127 -422.624758)
		(end 4.56946 -423.135298)
		(stroke
			(width 0.2)
			(type default)
		)
		(layer "In4.Cu")
	)
	(gr_line
		(start 5.59054 -417.54806)
		(end 5.59054 -416.735514)
		(stroke
			(width 0.2)
			(type default)
		)
		(layer "In4.Cu")
	)
	(gr_arc
		(start 5.59054 -416.735514)
		(mid 5.080127 -416.22472)
		(end 4.56946 -416.73526)
		(stroke
			(width 0.2)
			(type default)
		)
		(layer "In4.Cu")
	)
	(gr_line
		(start 5.59054 -414.347914)
		(end 5.59054 -413.535114)
		(stroke
			(width 0.2)
			(type default)
		)
		(layer "In4.Cu")
	)
	(gr_arc
		(start 5.59054 -413.535114)
		(mid 5.08 -413.024574)
		(end 4.56946 -413.535114)
		(stroke
			(width 0.2)
			(type default)
		)
		(layer "In4.Cu")
	)
	(gr_line
		(start 5.59054 -411.148022)
		(end 5.59054 -410.335222)
		(stroke
			(width 0.2)
			(type default)
		)
		(layer "In4.Cu")
	)
	(gr_arc
		(start 5.59054 -410.335222)
		(mid 5.08 -409.824682)
		(end 4.56946 -410.335222)
		(stroke
			(width 0.2)
			(type default)
		)
		(layer "In4.Cu")
	)
	(gr_line
		(start 5.59054 -407.947876)
		(end 5.59054 -407.135076)
		(stroke
			(width 0.2)
			(type default)
		)
		(layer "In4.Cu")
	)
	(gr_arc
		(start 5.59054 -407.135076)
		(mid 5.08 -406.624536)
		(end 4.56946 -407.135076)
		(stroke
			(width 0.2)
			(type default)
		)
		(layer "In4.Cu")
	)
	(gr_line
		(start 5.59054 -404.747984)
		(end 5.59054 -403.935184)
		(stroke
			(width 0.2)
			(type default)
		)
		(layer "In4.Cu")
	)
	(gr_arc
		(start 5.59054 -403.935184)
		(mid 5.08 -403.424644)
		(end 4.56946 -403.935184)
		(stroke
			(width 0.2)
			(type default)
		)
		(layer "In4.Cu")
	)
	(gr_line
		(start 5.59054 -399.148046)
		(end 5.59054 -398.3355)
		(stroke
			(width 0.2)
			(type default)
		)
		(layer "In4.Cu")
	)
	(gr_arc
		(start 5.59054 -398.3355)
		(mid 5.080127 -397.824706)
		(end 4.56946 -398.335246)
		(stroke
			(width 0.2)
			(type default)
		)
		(layer "In4.Cu")
	)
	(gr_line
		(start 5.59054 -395.9479)
		(end 5.59054 -395.135354)
		(stroke
			(width 0.2)
			(type default)
		)
		(layer "In4.Cu")
	)
	(gr_arc
		(start 5.59054 -395.135354)
		(mid 5.080127 -394.62456)
		(end 4.56946 -395.1351)
		(stroke
			(width 0.2)
			(type default)
		)
		(layer "In4.Cu")
	)
	(gr_line
		(start 5.59054 -392.748008)
		(end 5.59054 -391.935462)
		(stroke
			(width 0.2)
			(type default)
		)
		(layer "In4.Cu")
	)
	(gr_arc
		(start 5.59054 -391.935462)
		(mid 5.080127 -391.424668)
		(end 4.56946 -391.935208)
		(stroke
			(width 0.2)
			(type default)
		)
		(layer "In4.Cu")
	)
	(gr_line
		(start 5.59054 -389.548116)
		(end 5.59054 -388.73557)
		(stroke
			(width 0.2)
			(type default)
		)
		(layer "In4.Cu")
	)
	(gr_arc
		(start 5.59054 -388.73557)
		(mid 5.080127 -388.224776)
		(end 4.56946 -388.735316)
		(stroke
			(width 0.2)
			(type default)
		)
		(layer "In4.Cu")
	)
	(gr_line
		(start 5.59054 -358.74833)
		(end 5.59054 -357.935784)
		(stroke
			(width 0.2)
			(type default)
		)
		(layer "In4.Cu")
	)
	(gr_arc
		(start 5.59054 -357.935784)
		(mid 5.080127 -357.42499)
		(end 4.56946 -357.93553)
		(stroke
			(width 0.2)
			(type default)
		)
		(layer "In4.Cu")
	)
	(gr_line
		(start 5.59054 -355.548184)
		(end 5.59054 -354.735638)
		(stroke
			(width 0.2)
			(type default)
		)
		(layer "In4.Cu")
	)
	(gr_arc
		(start 5.59054 -354.735638)
		(mid 5.080127 -354.224844)
		(end 4.56946 -354.735384)
		(stroke
			(width 0.2)
			(type default)
		)
		(layer "In4.Cu")
	)
	(gr_line
		(start 5.59054 -352.348292)
		(end 5.59054 -351.535746)
		(stroke
			(width 0.2)
			(type default)
		)
		(layer "In4.Cu")
	)
	(gr_arc
		(start 5.59054 -351.535746)
		(mid 5.080127 -351.024952)
		(end 4.56946 -351.535492)
		(stroke
			(width 0.2)
			(type default)
		)
		(layer "In4.Cu")
	)
	(gr_line
		(start 5.59054 -349.148146)
		(end 5.59054 -348.3356)
		(stroke
			(width 0.2)
			(type default)
		)
		(layer "In4.Cu")
	)
	(gr_arc
		(start 5.59054 -348.3356)
		(mid 5.080127 -347.824806)
		(end 4.56946 -348.335346)
		(stroke
			(width 0.2)
			(type default)
		)
		(layer "In4.Cu")
	)
	(gr_line
		(start 5.59054 -345.948254)
		(end 5.59054 -345.135708)
		(stroke
			(width 0.2)
			(type default)
		)
		(layer "In4.Cu")
	)
	(gr_arc
		(start 5.59054 -345.135708)
		(mid 5.080127 -344.624914)
		(end 4.56946 -345.135454)
		(stroke
			(width 0.2)
			(type default)
		)
		(layer "In4.Cu")
	)
	(gr_line
		(start 5.59054 -342.748108)
		(end 5.59054 -341.935562)
		(stroke
			(width 0.2)
			(type default)
		)
		(layer "In4.Cu")
	)
	(gr_arc
		(start 5.59054 -341.935562)
		(mid 5.080127 -341.424768)
		(end 4.56946 -341.935308)
		(stroke
			(width 0.2)
			(type default)
		)
		(layer "In4.Cu")
	)
	(gr_line
		(start 5.59054 -339.548216)
		(end 5.59054 -338.73567)
		(stroke
			(width 0.2)
			(type default)
		)
		(layer "In4.Cu")
	)
	(gr_arc
		(start 5.59054 -338.73567)
		(mid 5.080127 -338.224876)
		(end 4.56946 -338.735416)
		(stroke
			(width 0.2)
			(type default)
		)
		(layer "In4.Cu")
	)
	(gr_line
		(start 5.59054 -336.348324)
		(end 5.59054 -335.535778)
		(stroke
			(width 0.2)
			(type default)
		)
		(layer "In4.Cu")
	)
	(gr_arc
		(start 5.59054 -335.535778)
		(mid 5.080127 -335.024984)
		(end 4.56946 -335.535524)
		(stroke
			(width 0.2)
			(type default)
		)
		(layer "In4.Cu")
	)
	(gr_line
		(start 5.59054 -330.748132)
		(end 5.59054 -329.935586)
		(stroke
			(width 0.2)
			(type default)
		)
		(layer "In4.Cu")
	)
	(gr_arc
		(start 5.59054 -329.935586)
		(mid 5.080127 -329.424792)
		(end 4.56946 -329.935332)
		(stroke
			(width 0.2)
			(type default)
		)
		(layer "In4.Cu")
	)
	(gr_line
		(start 5.59054 -327.54824)
		(end 5.59054 -326.735694)
		(stroke
			(width 0.2)
			(type default)
		)
		(layer "In4.Cu")
	)
	(gr_arc
		(start 5.59054 -326.735694)
		(mid 5.080127 -326.2249)
		(end 4.56946 -326.73544)
		(stroke
			(width 0.2)
			(type default)
		)
		(layer "In4.Cu")
	)
	(gr_line
		(start 5.59054 -324.348094)
		(end 5.59054 -323.535548)
		(stroke
			(width 0.2)
			(type default)
		)
		(layer "In4.Cu")
	)
	(gr_arc
		(start 5.59054 -323.535548)
		(mid 5.080127 -323.024754)
		(end 4.56946 -323.535294)
		(stroke
			(width 0.2)
			(type default)
		)
		(layer "In4.Cu")
	)
	(gr_line
		(start 5.59054 -321.148202)
		(end 5.59054 -320.335656)
		(stroke
			(width 0.2)
			(type default)
		)
		(layer "In4.Cu")
	)
	(gr_arc
		(start 5.59054 -320.335656)
		(mid 5.080127 -319.824862)
		(end 4.56946 -320.335402)
		(stroke
			(width 0.2)
			(type default)
		)
		(layer "In4.Cu")
	)
	(gr_line
		(start 5.59054 -317.94831)
		(end 5.59054 -317.135764)
		(stroke
			(width 0.2)
			(type default)
		)
		(layer "In4.Cu")
	)
	(gr_arc
		(start 5.59054 -317.135764)
		(mid 5.080127 -316.62497)
		(end 4.56946 -317.13551)
		(stroke
			(width 0.2)
			(type default)
		)
		(layer "In4.Cu")
	)
	(gr_line
		(start 5.59054 -309.948326)
		(end 5.59054 -309.13578)
		(stroke
			(width 0.2)
			(type default)
		)
		(layer "In4.Cu")
	)
	(gr_arc
		(start 5.59054 -309.13578)
		(mid 5.080127 -308.624986)
		(end 4.56946 -309.135526)
		(stroke
			(width 0.2)
			(type default)
		)
		(layer "In4.Cu")
	)
	(gr_line
		(start 5.59054 -306.74818)
		(end 5.59054 -305.935634)
		(stroke
			(width 0.2)
			(type default)
		)
		(layer "In4.Cu")
	)
	(gr_arc
		(start 5.59054 -305.935634)
		(mid 5.080127 -305.42484)
		(end 4.56946 -305.93538)
		(stroke
			(width 0.2)
			(type default)
		)
		(layer "In4.Cu")
	)
	(gr_line
		(start 5.59054 -303.548288)
		(end 5.59054 -302.735742)
		(stroke
			(width 0.2)
			(type default)
		)
		(layer "In4.Cu")
	)
	(gr_arc
		(start 5.59054 -302.735742)
		(mid 5.080127 -302.224948)
		(end 4.56946 -302.735488)
		(stroke
			(width 0.2)
			(type default)
		)
		(layer "In4.Cu")
	)
	(gr_line
		(start 5.59054 -300.348142)
		(end 5.59054 -299.535596)
		(stroke
			(width 0.2)
			(type default)
		)
		(layer "In4.Cu")
	)
	(gr_arc
		(start 5.59054 -299.535596)
		(mid 5.080127 -299.024802)
		(end 4.56946 -299.535342)
		(stroke
			(width 0.2)
			(type default)
		)
		(layer "In4.Cu")
	)
	(gr_line
		(start 5.59054 -297.14825)
		(end 5.59054 -296.335704)
		(stroke
			(width 0.2)
			(type default)
		)
		(layer "In4.Cu")
	)
	(gr_arc
		(start 5.59054 -296.335704)
		(mid 5.080127 -295.82491)
		(end 4.56946 -296.33545)
		(stroke
			(width 0.2)
			(type default)
		)
		(layer "In4.Cu")
	)
	(gr_line
		(start 5.59054 -293.948104)
		(end 5.59054 -293.135558)
		(stroke
			(width 0.2)
			(type default)
		)
		(layer "In4.Cu")
	)
	(gr_arc
		(start 5.59054 -293.135558)
		(mid 5.080127 -292.624764)
		(end 4.56946 -293.135304)
		(stroke
			(width 0.2)
			(type default)
		)
		(layer "In4.Cu")
	)
	(gr_line
		(start 5.59054 -290.748212)
		(end 5.59054 -289.935666)
		(stroke
			(width 0.2)
			(type default)
		)
		(layer "In4.Cu")
	)
	(gr_arc
		(start 5.59054 -289.935666)
		(mid 5.080127 -289.424872)
		(end 4.56946 -289.935412)
		(stroke
			(width 0.2)
			(type default)
		)
		(layer "In4.Cu")
	)
	(gr_line
		(start 5.59054 -284.348174)
		(end 5.59054 -283.535628)
		(stroke
			(width 0.2)
			(type default)
		)
		(layer "In4.Cu")
	)
	(gr_arc
		(start 5.59054 -283.535628)
		(mid 5.080127 -283.024834)
		(end 4.56946 -283.535374)
		(stroke
			(width 0.2)
			(type default)
		)
		(layer "In4.Cu")
	)
	(gr_line
		(start 5.59054 -281.148282)
		(end 5.59054 -280.335736)
		(stroke
			(width 0.2)
			(type default)
		)
		(layer "In4.Cu")
	)
	(gr_arc
		(start 5.59054 -280.335736)
		(mid 5.080127 -279.824942)
		(end 4.56946 -280.335482)
		(stroke
			(width 0.2)
			(type default)
		)
		(layer "In4.Cu")
	)
	(gr_line
		(start 5.59054 -232.748328)
		(end 5.59054 -231.935782)
		(stroke
			(width 0.2)
			(type default)
		)
		(layer "In4.Cu")
	)
	(gr_arc
		(start 5.59054 -231.935782)
		(mid 5.080127 -231.424988)
		(end 4.56946 -231.935528)
		(stroke
			(width 0.2)
			(type default)
		)
		(layer "In4.Cu")
	)
	(gr_line
		(start 5.59054 -229.548182)
		(end 5.59054 -228.735636)
		(stroke
			(width 0.2)
			(type default)
		)
		(layer "In4.Cu")
	)
	(gr_arc
		(start 5.59054 -228.735636)
		(mid 5.080127 -228.224842)
		(end 4.56946 -228.735382)
		(stroke
			(width 0.2)
			(type default)
		)
		(layer "In4.Cu")
	)
	(gr_line
		(start 5.59054 -223.148144)
		(end 5.59054 -222.335598)
		(stroke
			(width 0.2)
			(type default)
		)
		(layer "In4.Cu")
	)
	(gr_arc
		(start 5.59054 -222.335598)
		(mid 5.080127 -221.824804)
		(end 4.56946 -222.335344)
		(stroke
			(width 0.2)
			(type default)
		)
		(layer "In4.Cu")
	)
	(gr_line
		(start 5.59054 -219.948252)
		(end 5.59054 -219.135706)
		(stroke
			(width 0.2)
			(type default)
		)
		(layer "In4.Cu")
	)
	(gr_arc
		(start 5.59054 -219.135706)
		(mid 5.080127 -218.624912)
		(end 4.56946 -219.135452)
		(stroke
			(width 0.2)
			(type default)
		)
		(layer "In4.Cu")
	)
	(gr_line
		(start 5.59054 -216.748106)
		(end 5.59054 -215.93556)
		(stroke
			(width 0.2)
			(type default)
		)
		(layer "In4.Cu")
	)
	(gr_arc
		(start 5.59054 -215.93556)
		(mid 5.080127 -215.424766)
		(end 4.56946 -215.935306)
		(stroke
			(width 0.2)
			(type default)
		)
		(layer "In4.Cu")
	)
	(gr_line
		(start 5.59054 -213.548214)
		(end 5.59054 -212.735668)
		(stroke
			(width 0.2)
			(type default)
		)
		(layer "In4.Cu")
	)
	(gr_arc
		(start 5.59054 -212.735668)
		(mid 5.080127 -212.224874)
		(end 4.56946 -212.735414)
		(stroke
			(width 0.2)
			(type default)
		)
		(layer "In4.Cu")
	)
	(gr_line
		(start 5.59054 -210.348322)
		(end 5.59054 -209.535776)
		(stroke
			(width 0.2)
			(type default)
		)
		(layer "In4.Cu")
	)
	(gr_arc
		(start 5.59054 -209.535776)
		(mid 5.080127 -209.024982)
		(end 4.56946 -209.535522)
		(stroke
			(width 0.2)
			(type default)
		)
		(layer "In4.Cu")
	)
	(gr_line
		(start 5.59054 -207.148176)
		(end 5.59054 -206.33563)
		(stroke
			(width 0.2)
			(type default)
		)
		(layer "In4.Cu")
	)
	(gr_arc
		(start 5.59054 -206.33563)
		(mid 5.080127 -205.824836)
		(end 4.56946 -206.335376)
		(stroke
			(width 0.2)
			(type default)
		)
		(layer "In4.Cu")
	)
	(gr_line
		(start 5.59054 -203.948284)
		(end 5.59054 -203.135738)
		(stroke
			(width 0.2)
			(type default)
		)
		(layer "In4.Cu")
	)
	(gr_arc
		(start 5.59054 -203.135738)
		(mid 5.080127 -202.624944)
		(end 4.56946 -203.135484)
		(stroke
			(width 0.2)
			(type default)
		)
		(layer "In4.Cu")
	)
	(gr_line
		(start 5.59054 -200.748138)
		(end 5.59054 -199.935592)
		(stroke
			(width 0.2)
			(type default)
		)
		(layer "In4.Cu")
	)
	(gr_arc
		(start 5.59054 -199.935592)
		(mid 5.080127 -199.424798)
		(end 4.56946 -199.935338)
		(stroke
			(width 0.2)
			(type default)
		)
		(layer "In4.Cu")
	)
	(gr_line
		(start 5.59054 -195.1482)
		(end 5.59054 -194.335654)
		(stroke
			(width 0.2)
			(type default)
		)
		(layer "In4.Cu")
	)
	(gr_arc
		(start 5.59054 -194.335654)
		(mid 5.080127 -193.82486)
		(end 4.56946 -194.3354)
		(stroke
			(width 0.2)
			(type default)
		)
		(layer "In4.Cu")
	)
	(gr_line
		(start 5.59054 -191.948308)
		(end 5.59054 -191.135762)
		(stroke
			(width 0.2)
			(type default)
		)
		(layer "In4.Cu")
	)
	(gr_arc
		(start 5.59054 -191.135762)
		(mid 5.080127 -190.624968)
		(end 4.56946 -191.135508)
		(stroke
			(width 0.2)
			(type default)
		)
		(layer "In4.Cu")
	)
	(gr_line
		(start 5.59054 -183.948324)
		(end 5.59054 -183.135778)
		(stroke
			(width 0.2)
			(type default)
		)
		(layer "In4.Cu")
	)
	(gr_arc
		(start 5.59054 -183.135778)
		(mid 5.080127 -182.624984)
		(end 4.56946 -183.135524)
		(stroke
			(width 0.2)
			(type default)
		)
		(layer "In4.Cu")
	)
	(gr_line
		(start 5.59054 -180.748178)
		(end 5.59054 -179.935632)
		(stroke
			(width 0.2)
			(type default)
		)
		(layer "In4.Cu")
	)
	(gr_arc
		(start 5.59054 -179.935632)
		(mid 5.080127 -179.424838)
		(end 4.56946 -179.935378)
		(stroke
			(width 0.2)
			(type default)
		)
		(layer "In4.Cu")
	)
	(gr_line
		(start 5.59054 -177.548286)
		(end 5.59054 -176.73574)
		(stroke
			(width 0.2)
			(type default)
		)
		(layer "In4.Cu")
	)
	(gr_arc
		(start 5.59054 -176.73574)
		(mid 5.080127 -176.224946)
		(end 4.56946 -176.735486)
		(stroke
			(width 0.2)
			(type default)
		)
		(layer "In4.Cu")
	)
	(gr_line
		(start 5.59054 -174.34814)
		(end 5.59054 -173.535594)
		(stroke
			(width 0.2)
			(type default)
		)
		(layer "In4.Cu")
	)
	(gr_arc
		(start 5.59054 -173.535594)
		(mid 5.080127 -173.0248)
		(end 4.56946 -173.53534)
		(stroke
			(width 0.2)
			(type default)
		)
		(layer "In4.Cu")
	)
	(gr_line
		(start 5.59054 -171.148248)
		(end 5.59054 -170.335702)
		(stroke
			(width 0.2)
			(type default)
		)
		(layer "In4.Cu")
	)
	(gr_arc
		(start 5.59054 -170.335702)
		(mid 5.080127 -169.824908)
		(end 4.56946 -170.335448)
		(stroke
			(width 0.2)
			(type default)
		)
		(layer "In4.Cu")
	)
	(gr_line
		(start 5.59054 -167.948102)
		(end 5.59054 -167.135556)
		(stroke
			(width 0.2)
			(type default)
		)
		(layer "In4.Cu")
	)
	(gr_arc
		(start 5.59054 -167.135556)
		(mid 5.080127 -166.624762)
		(end 4.56946 -167.135302)
		(stroke
			(width 0.2)
			(type default)
		)
		(layer "In4.Cu")
	)
	(gr_line
		(start 5.59054 -164.74821)
		(end 5.59054 -163.935664)
		(stroke
			(width 0.2)
			(type default)
		)
		(layer "In4.Cu")
	)
	(gr_arc
		(start 5.59054 -163.935664)
		(mid 5.080127 -163.42487)
		(end 4.56946 -163.93541)
		(stroke
			(width 0.2)
			(type default)
		)
		(layer "In4.Cu")
	)
	(gr_line
		(start 5.59054 -161.548318)
		(end 5.59054 -160.735772)
		(stroke
			(width 0.2)
			(type default)
		)
		(layer "In4.Cu")
	)
	(gr_arc
		(start 5.59054 -160.735772)
		(mid 5.080127 -160.224978)
		(end 4.56946 -160.735518)
		(stroke
			(width 0.2)
			(type default)
		)
		(layer "In4.Cu")
	)
	(gr_line
		(start 5.59054 -158.348172)
		(end 5.59054 -157.535626)
		(stroke
			(width 0.2)
			(type default)
		)
		(layer "In4.Cu")
	)
	(gr_arc
		(start 5.59054 -157.535626)
		(mid 5.080127 -157.024832)
		(end 4.56946 -157.535372)
		(stroke
			(width 0.2)
			(type default)
		)
		(layer "In4.Cu")
	)
	(gr_line
		(start 5.59054 -155.14828)
		(end 5.59054 -154.335734)
		(stroke
			(width 0.2)
			(type default)
		)
		(layer "In4.Cu")
	)
	(gr_arc
		(start 5.59054 -154.335734)
		(mid 5.080127 -153.82494)
		(end 4.56946 -154.33548)
		(stroke
			(width 0.2)
			(type default)
		)
		(layer "In4.Cu")
	)
	(gr_line
		(start 6.477 -449.978272)
		(end 7.2898 -449.978272)
		(stroke
			(width 0.2)
			(type default)
		)
		(layer "In4.Cu")
	)
	(gr_arc
		(start 6.477254 -448.957192)
		(mid 5.96646 -449.467605)
		(end 6.477 -449.978272)
		(stroke
			(width 0.2)
			(type default)
		)
		(layer "In4.Cu")
	)
	(gr_arc
		(start 6.481826 -447.196718)
		(mid 6.992239 -447.707512)
		(end 7.502906 -447.196972)
		(stroke
			(width 0.2)
			(type default)
		)
		(layer "In4.Cu")
	)
	(gr_line
		(start 6.481826 -446.384172)
		(end 6.481826 -447.196718)
		(stroke
			(width 0.2)
			(type default)
		)
		(layer "In4.Cu")
	)
	(gr_arc
		(start 6.481826 -443.996826)
		(mid 6.992239 -444.50762)
		(end 7.502906 -443.99708)
		(stroke
			(width 0.2)
			(type default)
		)
		(layer "In4.Cu")
	)
	(gr_line
		(start 6.481826 -443.18428)
		(end 6.481826 -443.996826)
		(stroke
			(width 0.2)
			(type default)
		)
		(layer "In4.Cu")
	)
	(gr_arc
		(start 6.481826 -440.79668)
		(mid 6.992239 -441.307474)
		(end 7.502906 -440.796934)
		(stroke
			(width 0.2)
			(type default)
		)
		(layer "In4.Cu")
	)
	(gr_line
		(start 6.481826 -439.984134)
		(end 6.481826 -440.79668)
		(stroke
			(width 0.2)
			(type default)
		)
		(layer "In4.Cu")
	)
	(gr_arc
		(start 6.481826 -437.596788)
		(mid 6.992239 -438.107582)
		(end 7.502906 -437.597042)
		(stroke
			(width 0.2)
			(type default)
		)
		(layer "In4.Cu")
	)
	(gr_line
		(start 6.481826 -436.784242)
		(end 6.481826 -437.596788)
		(stroke
			(width 0.2)
			(type default)
		)
		(layer "In4.Cu")
	)
	(gr_arc
		(start 6.481826 -431.997104)
		(mid 6.992366 -432.507644)
		(end 7.502906 -431.997104)
		(stroke
			(width 0.2)
			(type default)
		)
		(layer "In4.Cu")
	)
	(gr_line
		(start 6.481826 -431.184304)
		(end 6.481826 -431.997104)
		(stroke
			(width 0.2)
			(type default)
		)
		(layer "In4.Cu")
	)
	(gr_arc
		(start 6.481826 -428.796958)
		(mid 6.992366 -429.307498)
		(end 7.502906 -428.796958)
		(stroke
			(width 0.2)
			(type default)
		)
		(layer "In4.Cu")
	)
	(gr_line
		(start 6.481826 -427.984158)
		(end 6.481826 -428.796958)
		(stroke
			(width 0.2)
			(type default)
		)
		(layer "In4.Cu")
	)
	(gr_arc
		(start 6.481826 -425.597066)
		(mid 6.992366 -426.107606)
		(end 7.502906 -425.597066)
		(stroke
			(width 0.2)
			(type default)
		)
		(layer "In4.Cu")
	)
	(gr_line
		(start 6.481826 -424.784266)
		(end 6.481826 -425.597066)
		(stroke
			(width 0.2)
			(type default)
		)
		(layer "In4.Cu")
	)
	(gr_arc
		(start 6.481826 -415.948622)
		(mid 6.992366 -416.459162)
		(end 7.502906 -415.948622)
		(stroke
			(width 0.2)
			(type default)
		)
		(layer "In4.Cu")
	)
	(gr_line
		(start 6.481826 -415.135822)
		(end 6.481826 -415.948622)
		(stroke
			(width 0.2)
			(type default)
		)
		(layer "In4.Cu")
	)
	(gr_arc
		(start 6.481826 -412.748222)
		(mid 6.992239 -413.259016)
		(end 7.502906 -412.748476)
		(stroke
			(width 0.2)
			(type default)
		)
		(layer "In4.Cu")
	)
	(gr_line
		(start 6.481826 -411.935676)
		(end 6.481826 -412.748222)
		(stroke
			(width 0.2)
			(type default)
		)
		(layer "In4.Cu")
	)
	(gr_arc
		(start 6.481826 -409.54833)
		(mid 6.992239 -410.059124)
		(end 7.502906 -409.548584)
		(stroke
			(width 0.2)
			(type default)
		)
		(layer "In4.Cu")
	)
	(gr_line
		(start 6.481826 -408.735784)
		(end 6.481826 -409.54833)
		(stroke
			(width 0.2)
			(type default)
		)
		(layer "In4.Cu")
	)
	(gr_arc
		(start 6.481826 -406.348184)
		(mid 6.992239 -406.858978)
		(end 7.502906 -406.348438)
		(stroke
			(width 0.2)
			(type default)
		)
		(layer "In4.Cu")
	)
	(gr_line
		(start 6.481826 -405.535638)
		(end 6.481826 -406.348184)
		(stroke
			(width 0.2)
			(type default)
		)
		(layer "In4.Cu")
	)
	(gr_arc
		(start 6.481826 -403.148292)
		(mid 6.992239 -403.659086)
		(end 7.502906 -403.148546)
		(stroke
			(width 0.2)
			(type default)
		)
		(layer "In4.Cu")
	)
	(gr_line
		(start 6.481826 -402.335746)
		(end 6.481826 -403.148292)
		(stroke
			(width 0.2)
			(type default)
		)
		(layer "In4.Cu")
	)
	(gr_arc
		(start 6.481826 -397.548608)
		(mid 6.992366 -398.059148)
		(end 7.502906 -397.548608)
		(stroke
			(width 0.2)
			(type default)
		)
		(layer "In4.Cu")
	)
	(gr_line
		(start 6.481826 -396.735808)
		(end 6.481826 -397.548608)
		(stroke
			(width 0.2)
			(type default)
		)
		(layer "In4.Cu")
	)
	(gr_arc
		(start 6.481826 -394.348462)
		(mid 6.992366 -394.859002)
		(end 7.502906 -394.348462)
		(stroke
			(width 0.2)
			(type default)
		)
		(layer "In4.Cu")
	)
	(gr_line
		(start 6.481826 -393.535662)
		(end 6.481826 -394.348462)
		(stroke
			(width 0.2)
			(type default)
		)
		(layer "In4.Cu")
	)
	(gr_arc
		(start 6.481826 -391.14857)
		(mid 6.992366 -391.65911)
		(end 7.502906 -391.14857)
		(stroke
			(width 0.2)
			(type default)
		)
		(layer "In4.Cu")
	)
	(gr_line
		(start 6.481826 -390.33577)
		(end 6.481826 -391.14857)
		(stroke
			(width 0.2)
			(type default)
		)
		(layer "In4.Cu")
	)
	(gr_arc
		(start 6.481826 -387.948424)
		(mid 6.992366 -388.458964)
		(end 7.502906 -387.948424)
		(stroke
			(width 0.2)
			(type default)
		)
		(layer "In4.Cu")
	)
	(gr_line
		(start 6.481826 -387.135624)
		(end 6.481826 -387.948424)
		(stroke
			(width 0.2)
			(type default)
		)
		(layer "In4.Cu")
	)
	(gr_arc
		(start 6.481826 -357.148384)
		(mid 6.992239 -357.659178)
		(end 7.502906 -357.148638)
		(stroke
			(width 0.2)
			(type default)
		)
		(layer "In4.Cu")
	)
	(gr_line
		(start 6.481826 -356.335838)
		(end 6.481826 -357.148384)
		(stroke
			(width 0.2)
			(type default)
		)
		(layer "In4.Cu")
	)
	(gr_arc
		(start 6.481826 -353.948746)
		(mid 6.992366 -354.459286)
		(end 7.502906 -353.948746)
		(stroke
			(width 0.2)
			(type default)
		)
		(layer "In4.Cu")
	)
	(gr_line
		(start 6.481826 -353.135946)
		(end 6.481826 -353.948746)
		(stroke
			(width 0.2)
			(type default)
		)
		(layer "In4.Cu")
	)
	(gr_arc
		(start 6.481826 -350.748346)
		(mid 6.992239 -351.25914)
		(end 7.502906 -350.7486)
		(stroke
			(width 0.2)
			(type default)
		)
		(layer "In4.Cu")
	)
	(gr_line
		(start 6.481826 -349.9358)
		(end 6.481826 -350.748346)
		(stroke
			(width 0.2)
			(type default)
		)
		(layer "In4.Cu")
	)
	(gr_arc
		(start 6.481826 -347.548454)
		(mid 6.992239 -348.059248)
		(end 7.502906 -347.548708)
		(stroke
			(width 0.2)
			(type default)
		)
		(layer "In4.Cu")
	)
	(gr_line
		(start 6.481826 -346.735908)
		(end 6.481826 -347.548454)
		(stroke
			(width 0.2)
			(type default)
		)
		(layer "In4.Cu")
	)
	(gr_arc
		(start 6.481826 -344.399616)
		(mid 6.992366 -344.910156)
		(end 7.502906 -344.399616)
		(stroke
			(width 0.2)
			(type default)
		)
		(layer "In4.Cu")
	)
	(gr_line
		(start 6.481826 -343.586816)
		(end 6.481826 -344.399616)
		(stroke
			(width 0.2)
			(type default)
		)
		(layer "In4.Cu")
	)
	(gr_arc
		(start 6.481826 -341.19947)
		(mid 6.992366 -341.71001)
		(end 7.502906 -341.19947)
		(stroke
			(width 0.2)
			(type default)
		)
		(layer "In4.Cu")
	)
	(gr_line
		(start 6.481826 -340.38667)
		(end 6.481826 -341.19947)
		(stroke
			(width 0.2)
			(type default)
		)
		(layer "In4.Cu")
	)
	(gr_arc
		(start 6.481826 -337.999578)
		(mid 6.992366 -338.510118)
		(end 7.502906 -337.999578)
		(stroke
			(width 0.2)
			(type default)
		)
		(layer "In4.Cu")
	)
	(gr_line
		(start 6.481826 -337.186778)
		(end 6.481826 -337.999578)
		(stroke
			(width 0.2)
			(type default)
		)
		(layer "In4.Cu")
	)
	(gr_arc
		(start 6.481826 -334.799432)
		(mid 6.992366 -335.309972)
		(end 7.502906 -334.799432)
		(stroke
			(width 0.2)
			(type default)
		)
		(layer "In4.Cu")
	)
	(gr_line
		(start 6.481826 -333.986632)
		(end 6.481826 -334.799432)
		(stroke
			(width 0.2)
			(type default)
		)
		(layer "In4.Cu")
	)
	(gr_arc
		(start 6.481826 -329.14844)
		(mid 6.992239 -329.659234)
		(end 7.502906 -329.148694)
		(stroke
			(width 0.2)
			(type default)
		)
		(layer "In4.Cu")
	)
	(gr_line
		(start 6.481826 -328.335894)
		(end 6.481826 -329.14844)
		(stroke
			(width 0.2)
			(type default)
		)
		(layer "In4.Cu")
	)
	(gr_arc
		(start 6.481826 -325.948548)
		(mid 6.992239 -326.459342)
		(end 7.502906 -325.948802)
		(stroke
			(width 0.2)
			(type default)
		)
		(layer "In4.Cu")
	)
	(gr_line
		(start 6.481826 -325.136002)
		(end 6.481826 -325.948548)
		(stroke
			(width 0.2)
			(type default)
		)
		(layer "In4.Cu")
	)
	(gr_arc
		(start 6.481826 -322.748402)
		(mid 6.992239 -323.259196)
		(end 7.502906 -322.748656)
		(stroke
			(width 0.2)
			(type default)
		)
		(layer "In4.Cu")
	)
	(gr_line
		(start 6.481826 -321.935856)
		(end 6.481826 -322.748402)
		(stroke
			(width 0.2)
			(type default)
		)
		(layer "In4.Cu")
	)
	(gr_arc
		(start 6.481826 -319.54851)
		(mid 6.992239 -320.059304)
		(end 7.502906 -319.548764)
		(stroke
			(width 0.2)
			(type default)
		)
		(layer "In4.Cu")
	)
	(gr_line
		(start 6.481826 -318.735964)
		(end 6.481826 -319.54851)
		(stroke
			(width 0.2)
			(type default)
		)
		(layer "In4.Cu")
	)
	(gr_arc
		(start 6.481826 -311.548526)
		(mid 6.992239 -312.05932)
		(end 7.502906 -311.54878)
		(stroke
			(width 0.2)
			(type default)
		)
		(layer "In4.Cu")
	)
	(gr_line
		(start 6.481826 -310.73598)
		(end 6.481826 -311.548526)
		(stroke
			(width 0.2)
			(type default)
		)
		(layer "In4.Cu")
	)
	(gr_arc
		(start 6.481826 -308.34838)
		(mid 6.992239 -308.859174)
		(end 7.502906 -308.348634)
		(stroke
			(width 0.2)
			(type default)
		)
		(layer "In4.Cu")
	)
	(gr_line
		(start 6.481826 -307.535834)
		(end 6.481826 -308.34838)
		(stroke
			(width 0.2)
			(type default)
		)
		(layer "In4.Cu")
	)
	(gr_arc
		(start 6.481826 -305.148488)
		(mid 6.992239 -305.659282)
		(end 7.502906 -305.148742)
		(stroke
			(width 0.2)
			(type default)
		)
		(layer "In4.Cu")
	)
	(gr_line
		(start 6.481826 -304.335942)
		(end 6.481826 -305.148488)
		(stroke
			(width 0.2)
			(type default)
		)
		(layer "In4.Cu")
	)
	(gr_arc
		(start 6.481826 -301.948342)
		(mid 6.992239 -302.459136)
		(end 7.502906 -301.948596)
		(stroke
			(width 0.2)
			(type default)
		)
		(layer "In4.Cu")
	)
	(gr_line
		(start 6.481826 -301.135796)
		(end 6.481826 -301.948342)
		(stroke
			(width 0.2)
			(type default)
		)
		(layer "In4.Cu")
	)
	(gr_arc
		(start 6.481826 -298.74845)
		(mid 6.992239 -299.259244)
		(end 7.502906 -298.748704)
		(stroke
			(width 0.2)
			(type default)
		)
		(layer "In4.Cu")
	)
	(gr_line
		(start 6.481826 -297.935904)
		(end 6.481826 -298.74845)
		(stroke
			(width 0.2)
			(type default)
		)
		(layer "In4.Cu")
	)
	(gr_arc
		(start 6.481826 -295.548558)
		(mid 6.992239 -296.059352)
		(end 7.502906 -295.548812)
		(stroke
			(width 0.2)
			(type default)
		)
		(layer "In4.Cu")
	)
	(gr_line
		(start 6.481826 -294.736012)
		(end 6.481826 -295.548558)
		(stroke
			(width 0.2)
			(type default)
		)
		(layer "In4.Cu")
	)
	(gr_arc
		(start 6.481826 -292.348412)
		(mid 6.992239 -292.859206)
		(end 7.502906 -292.348666)
		(stroke
			(width 0.2)
			(type default)
		)
		(layer "In4.Cu")
	)
	(gr_line
		(start 6.481826 -291.535866)
		(end 6.481826 -292.348412)
		(stroke
			(width 0.2)
			(type default)
		)
		(layer "In4.Cu")
	)
	(gr_arc
		(start 6.481826 -289.148774)
		(mid 6.992366 -289.659314)
		(end 7.502906 -289.148774)
		(stroke
			(width 0.2)
			(type default)
		)
		(layer "In4.Cu")
	)
	(gr_line
		(start 6.481826 -288.335974)
		(end 6.481826 -289.148774)
		(stroke
			(width 0.2)
			(type default)
		)
		(layer "In4.Cu")
	)
	(gr_arc
		(start 6.481826 -282.799536)
		(mid 6.992366 -283.310076)
		(end 7.502906 -282.799536)
		(stroke
			(width 0.2)
			(type default)
		)
		(layer "In4.Cu")
	)
	(gr_line
		(start 6.481826 -281.986736)
		(end 6.481826 -282.799536)
		(stroke
			(width 0.2)
			(type default)
		)
		(layer "In4.Cu")
	)
	(gr_arc
		(start 6.481826 -279.59939)
		(mid 6.992366 -280.10993)
		(end 7.502906 -279.59939)
		(stroke
			(width 0.2)
			(type default)
		)
		(layer "In4.Cu")
	)
	(gr_line
		(start 6.481826 -278.78659)
		(end 6.481826 -279.59939)
		(stroke
			(width 0.2)
			(type default)
		)
		(layer "In4.Cu")
	)
	(gr_arc
		(start 6.481826 -231.148636)
		(mid 6.992366 -231.659176)
		(end 7.502906 -231.148636)
		(stroke
			(width 0.2)
			(type default)
		)
		(layer "In4.Cu")
	)
	(gr_line
		(start 6.481826 -230.335836)
		(end 6.481826 -231.148636)
		(stroke
			(width 0.2)
			(type default)
		)
		(layer "In4.Cu")
	)
	(gr_arc
		(start 6.481826 -227.948744)
		(mid 6.992366 -228.459284)
		(end 7.502906 -227.948744)
		(stroke
			(width 0.2)
			(type default)
		)
		(layer "In4.Cu")
	)
	(gr_line
		(start 6.481826 -227.135944)
		(end 6.481826 -227.948744)
		(stroke
			(width 0.2)
			(type default)
		)
		(layer "In4.Cu")
	)
	(gr_arc
		(start 6.481826 -224.710498)
		(mid 6.992366 -225.221038)
		(end 7.502906 -224.710498)
		(stroke
			(width 0.2)
			(type default)
		)
		(layer "In4.Cu")
	)
	(gr_line
		(start 6.481826 -223.897698)
		(end 6.481826 -224.710498)
		(stroke
			(width 0.2)
			(type default)
		)
		(layer "In4.Cu")
	)
	(gr_arc
		(start 6.481826 -221.497652)
		(mid 6.992239 -222.008446)
		(end 7.502906 -221.497906)
		(stroke
			(width 0.2)
			(type default)
		)
		(layer "In4.Cu")
	)
	(gr_line
		(start 6.481826 -220.685106)
		(end 6.481826 -221.497652)
		(stroke
			(width 0.2)
			(type default)
		)
		(layer "In4.Cu")
	)
	(gr_arc
		(start 6.481826 -218.298014)
		(mid 6.992366 -218.808554)
		(end 7.502906 -218.298014)
		(stroke
			(width 0.2)
			(type default)
		)
		(layer "In4.Cu")
	)
	(gr_line
		(start 6.481826 -217.485214)
		(end 6.481826 -218.298014)
		(stroke
			(width 0.2)
			(type default)
		)
		(layer "In4.Cu")
	)
	(gr_arc
		(start 6.481826 -215.097868)
		(mid 6.992366 -215.608408)
		(end 7.502906 -215.097868)
		(stroke
			(width 0.2)
			(type default)
		)
		(layer "In4.Cu")
	)
	(gr_line
		(start 6.481826 -214.285068)
		(end 6.481826 -215.097868)
		(stroke
			(width 0.2)
			(type default)
		)
		(layer "In4.Cu")
	)
	(gr_arc
		(start 6.481826 -211.948776)
		(mid 6.992366 -212.459316)
		(end 7.502906 -211.948776)
		(stroke
			(width 0.2)
			(type default)
		)
		(layer "In4.Cu")
	)
	(gr_line
		(start 6.481826 -211.135976)
		(end 6.481826 -211.948776)
		(stroke
			(width 0.2)
			(type default)
		)
		(layer "In4.Cu")
	)
	(gr_arc
		(start 6.481826 -208.74863)
		(mid 6.992366 -209.25917)
		(end 7.502906 -208.74863)
		(stroke
			(width 0.2)
			(type default)
		)
		(layer "In4.Cu")
	)
	(gr_line
		(start 6.481826 -207.93583)
		(end 6.481826 -208.74863)
		(stroke
			(width 0.2)
			(type default)
		)
		(layer "In4.Cu")
	)
	(gr_arc
		(start 6.481826 -205.548738)
		(mid 6.992366 -206.059278)
		(end 7.502906 -205.548738)
		(stroke
			(width 0.2)
			(type default)
		)
		(layer "In4.Cu")
	)
	(gr_line
		(start 6.481826 -204.735938)
		(end 6.481826 -205.548738)
		(stroke
			(width 0.2)
			(type default)
		)
		(layer "In4.Cu")
	)
	(gr_arc
		(start 6.481826 -202.348592)
		(mid 6.992366 -202.859132)
		(end 7.502906 -202.348592)
		(stroke
			(width 0.2)
			(type default)
		)
		(layer "In4.Cu")
	)
	(gr_line
		(start 6.481826 -201.535792)
		(end 6.481826 -202.348592)
		(stroke
			(width 0.2)
			(type default)
		)
		(layer "In4.Cu")
	)
	(gr_arc
		(start 6.481826 -196.748654)
		(mid 6.992366 -197.259194)
		(end 7.502906 -196.748654)
		(stroke
			(width 0.2)
			(type default)
		)
		(layer "In4.Cu")
	)
	(gr_line
		(start 6.481826 -195.935854)
		(end 6.481826 -196.748654)
		(stroke
			(width 0.2)
			(type default)
		)
		(layer "In4.Cu")
	)
	(gr_arc
		(start 6.481826 -193.548762)
		(mid 6.992366 -194.059302)
		(end 7.502906 -193.548762)
		(stroke
			(width 0.2)
			(type default)
		)
		(layer "In4.Cu")
	)
	(gr_line
		(start 6.481826 -192.735962)
		(end 6.481826 -193.548762)
		(stroke
			(width 0.2)
			(type default)
		)
		(layer "In4.Cu")
	)
	(gr_arc
		(start 6.481826 -185.548778)
		(mid 6.992366 -186.059318)
		(end 7.502906 -185.548778)
		(stroke
			(width 0.2)
			(type default)
		)
		(layer "In4.Cu")
	)
	(gr_line
		(start 6.481826 -184.735978)
		(end 6.481826 -185.548778)
		(stroke
			(width 0.2)
			(type default)
		)
		(layer "In4.Cu")
	)
	(gr_arc
		(start 6.481826 -182.348632)
		(mid 6.992366 -182.859172)
		(end 7.502906 -182.348632)
		(stroke
			(width 0.2)
			(type default)
		)
		(layer "In4.Cu")
	)
	(gr_line
		(start 6.481826 -181.535832)
		(end 6.481826 -182.348632)
		(stroke
			(width 0.2)
			(type default)
		)
		(layer "In4.Cu")
	)
	(gr_arc
		(start 6.481826 -179.19954)
		(mid 6.992366 -179.71008)
		(end 7.502906 -179.19954)
		(stroke
			(width 0.2)
			(type default)
		)
		(layer "In4.Cu")
	)
	(gr_line
		(start 6.481826 -178.38674)
		(end 6.481826 -179.19954)
		(stroke
			(width 0.2)
			(type default)
		)
		(layer "In4.Cu")
	)
	(gr_arc
		(start 6.481826 -175.999394)
		(mid 6.992366 -176.509934)
		(end 7.502906 -175.999394)
		(stroke
			(width 0.2)
			(type default)
		)
		(layer "In4.Cu")
	)
	(gr_line
		(start 6.481826 -175.186594)
		(end 6.481826 -175.999394)
		(stroke
			(width 0.2)
			(type default)
		)
		(layer "In4.Cu")
	)
	(gr_arc
		(start 6.481826 -172.799502)
		(mid 6.992366 -173.310042)
		(end 7.502906 -172.799502)
		(stroke
			(width 0.2)
			(type default)
		)
		(layer "In4.Cu")
	)
	(gr_line
		(start 6.481826 -171.986702)
		(end 6.481826 -172.799502)
		(stroke
			(width 0.2)
			(type default)
		)
		(layer "In4.Cu")
	)
	(gr_arc
		(start 6.481826 -169.59961)
		(mid 6.992366 -170.11015)
		(end 7.502906 -169.59961)
		(stroke
			(width 0.2)
			(type default)
		)
		(layer "In4.Cu")
	)
	(gr_line
		(start 6.481826 -168.78681)
		(end 6.481826 -169.59961)
		(stroke
			(width 0.2)
			(type default)
		)
		(layer "In4.Cu")
	)
	(gr_arc
		(start 6.481826 -163.199572)
		(mid 6.992366 -163.710112)
		(end 7.502906 -163.199572)
		(stroke
			(width 0.2)
			(type default)
		)
		(layer "In4.Cu")
	)
	(gr_line
		(start 6.481826 -162.386772)
		(end 6.481826 -163.199572)
		(stroke
			(width 0.2)
			(type default)
		)
		(layer "In4.Cu")
	)
	(gr_arc
		(start 6.481826 -159.999426)
		(mid 6.992366 -160.509966)
		(end 7.502906 -159.999426)
		(stroke
			(width 0.2)
			(type default)
		)
		(layer "In4.Cu")
	)
	(gr_line
		(start 6.481826 -159.186626)
		(end 6.481826 -159.999426)
		(stroke
			(width 0.2)
			(type default)
		)
		(layer "In4.Cu")
	)
	(gr_arc
		(start 6.481826 -156.786834)
		(mid 6.992366 -157.297374)
		(end 7.502906 -156.786834)
		(stroke
			(width 0.2)
			(type default)
		)
		(layer "In4.Cu")
	)
	(gr_line
		(start 6.481826 -155.974034)
		(end 6.481826 -156.786834)
		(stroke
			(width 0.2)
			(type default)
		)
		(layer "In4.Cu")
	)
	(gr_arc
		(start 6.481826 -153.599388)
		(mid 6.992366 -154.109928)
		(end 7.502906 -153.599388)
		(stroke
			(width 0.2)
			(type default)
		)
		(layer "In4.Cu")
	)
	(gr_line
		(start 6.481826 -152.786588)
		(end 6.481826 -153.599388)
		(stroke
			(width 0.2)
			(type default)
		)
		(layer "In4.Cu")
	)
	(gr_arc
		(start 7.2898 -449.978272)
		(mid 7.80034 -449.467732)
		(end 7.2898 -448.957192)
		(stroke
			(width 0.2)
			(type default)
		)
		(layer "In4.Cu")
	)
	(gr_line
		(start 7.2898 -448.957192)
		(end 6.477254 -448.957192)
		(stroke
			(width 0.2)
			(type default)
		)
		(layer "In4.Cu")
	)
	(gr_line
		(start 7.502906 -447.196972)
		(end 7.502906 -446.384172)
		(stroke
			(width 0.2)
			(type default)
		)
		(layer "In4.Cu")
	)
	(gr_arc
		(start 7.502906 -446.384172)
		(mid 6.992366 -445.873632)
		(end 6.481826 -446.384172)
		(stroke
			(width 0.2)
			(type default)
		)
		(layer "In4.Cu")
	)
	(gr_line
		(start 7.502906 -443.99708)
		(end 7.502906 -443.18428)
		(stroke
			(width 0.2)
			(type default)
		)
		(layer "In4.Cu")
	)
	(gr_arc
		(start 7.502906 -443.18428)
		(mid 6.992366 -442.67374)
		(end 6.481826 -443.18428)
		(stroke
			(width 0.2)
			(type default)
		)
		(layer "In4.Cu")
	)
	(gr_line
		(start 7.502906 -440.796934)
		(end 7.502906 -439.984134)
		(stroke
			(width 0.2)
			(type default)
		)
		(layer "In4.Cu")
	)
	(gr_arc
		(start 7.502906 -439.984134)
		(mid 6.992366 -439.473594)
		(end 6.481826 -439.984134)
		(stroke
			(width 0.2)
			(type default)
		)
		(layer "In4.Cu")
	)
	(gr_line
		(start 7.502906 -437.597042)
		(end 7.502906 -436.784242)
		(stroke
			(width 0.2)
			(type default)
		)
		(layer "In4.Cu")
	)
	(gr_arc
		(start 7.502906 -436.784242)
		(mid 6.992366 -436.273702)
		(end 6.481826 -436.784242)
		(stroke
			(width 0.2)
			(type default)
		)
		(layer "In4.Cu")
	)
	(gr_line
		(start 7.502906 -431.997104)
		(end 7.502906 -431.184558)
		(stroke
			(width 0.2)
			(type default)
		)
		(layer "In4.Cu")
	)
	(gr_arc
		(start 7.502906 -431.184558)
		(mid 6.992493 -430.673764)
		(end 6.481826 -431.184304)
		(stroke
			(width 0.2)
			(type default)
		)
		(layer "In4.Cu")
	)
	(gr_line
		(start 7.502906 -428.796958)
		(end 7.502906 -427.984412)
		(stroke
			(width 0.2)
			(type default)
		)
		(layer "In4.Cu")
	)
	(gr_arc
		(start 7.502906 -427.984412)
		(mid 6.992493 -427.473618)
		(end 6.481826 -427.984158)
		(stroke
			(width 0.2)
			(type default)
		)
		(layer "In4.Cu")
	)
	(gr_line
		(start 7.502906 -425.597066)
		(end 7.502906 -424.78452)
		(stroke
			(width 0.2)
			(type default)
		)
		(layer "In4.Cu")
	)
	(gr_arc
		(start 7.502906 -424.78452)
		(mid 6.992493 -424.273726)
		(end 6.481826 -424.784266)
		(stroke
			(width 0.2)
			(type default)
		)
		(layer "In4.Cu")
	)
	(gr_line
		(start 7.502906 -415.948622)
		(end 7.502906 -415.136076)
		(stroke
			(width 0.2)
			(type default)
		)
		(layer "In4.Cu")
	)
	(gr_arc
		(start 7.502906 -415.136076)
		(mid 6.992493 -414.625282)
		(end 6.481826 -415.135822)
		(stroke
			(width 0.2)
			(type default)
		)
		(layer "In4.Cu")
	)
	(gr_line
		(start 7.502906 -412.748476)
		(end 7.502906 -411.935676)
		(stroke
			(width 0.2)
			(type default)
		)
		(layer "In4.Cu")
	)
	(gr_arc
		(start 7.502906 -411.935676)
		(mid 6.992366 -411.425136)
		(end 6.481826 -411.935676)
		(stroke
			(width 0.2)
			(type default)
		)
		(layer "In4.Cu")
	)
	(gr_line
		(start 7.502906 -409.548584)
		(end 7.502906 -408.735784)
		(stroke
			(width 0.2)
			(type default)
		)
		(layer "In4.Cu")
	)
	(gr_arc
		(start 7.502906 -408.735784)
		(mid 6.992366 -408.225244)
		(end 6.481826 -408.735784)
		(stroke
			(width 0.2)
			(type default)
		)
		(layer "In4.Cu")
	)
	(gr_line
		(start 7.502906 -406.348438)
		(end 7.502906 -405.535638)
		(stroke
			(width 0.2)
			(type default)
		)
		(layer "In4.Cu")
	)
	(gr_arc
		(start 7.502906 -405.535638)
		(mid 6.992366 -405.025098)
		(end 6.481826 -405.535638)
		(stroke
			(width 0.2)
			(type default)
		)
		(layer "In4.Cu")
	)
	(gr_line
		(start 7.502906 -403.148546)
		(end 7.502906 -402.335746)
		(stroke
			(width 0.2)
			(type default)
		)
		(layer "In4.Cu")
	)
	(gr_arc
		(start 7.502906 -402.335746)
		(mid 6.992366 -401.825206)
		(end 6.481826 -402.335746)
		(stroke
			(width 0.2)
			(type default)
		)
		(layer "In4.Cu")
	)
	(gr_line
		(start 7.502906 -397.548608)
		(end 7.502906 -396.736062)
		(stroke
			(width 0.2)
			(type default)
		)
		(layer "In4.Cu")
	)
	(gr_arc
		(start 7.502906 -396.736062)
		(mid 6.992493 -396.225268)
		(end 6.481826 -396.735808)
		(stroke
			(width 0.2)
			(type default)
		)
		(layer "In4.Cu")
	)
	(gr_line
		(start 7.502906 -394.348462)
		(end 7.502906 -393.535916)
		(stroke
			(width 0.2)
			(type default)
		)
		(layer "In4.Cu")
	)
	(gr_arc
		(start 7.502906 -393.535916)
		(mid 6.992493 -393.025122)
		(end 6.481826 -393.535662)
		(stroke
			(width 0.2)
			(type default)
		)
		(layer "In4.Cu")
	)
	(gr_line
		(start 7.502906 -391.14857)
		(end 7.502906 -390.336024)
		(stroke
			(width 0.2)
			(type default)
		)
		(layer "In4.Cu")
	)
	(gr_arc
		(start 7.502906 -390.336024)
		(mid 6.992493 -389.82523)
		(end 6.481826 -390.33577)
		(stroke
			(width 0.2)
			(type default)
		)
		(layer "In4.Cu")
	)
	(gr_line
		(start 7.502906 -387.948424)
		(end 7.502906 -387.135878)
		(stroke
			(width 0.2)
			(type default)
		)
		(layer "In4.Cu")
	)
	(gr_arc
		(start 7.502906 -387.135878)
		(mid 6.992493 -386.625084)
		(end 6.481826 -387.135624)
		(stroke
			(width 0.2)
			(type default)
		)
		(layer "In4.Cu")
	)
	(gr_line
		(start 7.502906 -357.148638)
		(end 7.502906 -356.335838)
		(stroke
			(width 0.2)
			(type default)
		)
		(layer "In4.Cu")
	)
	(gr_arc
		(start 7.502906 -356.335838)
		(mid 6.992366 -355.825298)
		(end 6.481826 -356.335838)
		(stroke
			(width 0.2)
			(type default)
		)
		(layer "In4.Cu")
	)
	(gr_line
		(start 7.502906 -353.948746)
		(end 7.502906 -353.1362)
		(stroke
			(width 0.2)
			(type default)
		)
		(layer "In4.Cu")
	)
	(gr_arc
		(start 7.502906 -353.1362)
		(mid 6.992493 -352.625406)
		(end 6.481826 -353.135946)
		(stroke
			(width 0.2)
			(type default)
		)
		(layer "In4.Cu")
	)
	(gr_line
		(start 7.502906 -350.7486)
		(end 7.502906 -349.9358)
		(stroke
			(width 0.2)
			(type default)
		)
		(layer "In4.Cu")
	)
	(gr_arc
		(start 7.502906 -349.9358)
		(mid 6.992366 -349.42526)
		(end 6.481826 -349.9358)
		(stroke
			(width 0.2)
			(type default)
		)
		(layer "In4.Cu")
	)
	(gr_line
		(start 7.502906 -347.548708)
		(end 7.502906 -346.735908)
		(stroke
			(width 0.2)
			(type default)
		)
		(layer "In4.Cu")
	)
	(gr_arc
		(start 7.502906 -346.735908)
		(mid 6.992366 -346.225368)
		(end 6.481826 -346.735908)
		(stroke
			(width 0.2)
			(type default)
		)
		(layer "In4.Cu")
	)
	(gr_line
		(start 7.502906 -344.399616)
		(end 7.502906 -343.58707)
		(stroke
			(width 0.2)
			(type default)
		)
		(layer "In4.Cu")
	)
	(gr_arc
		(start 7.502906 -343.58707)
		(mid 6.992493 -343.076276)
		(end 6.481826 -343.586816)
		(stroke
			(width 0.2)
			(type default)
		)
		(layer "In4.Cu")
	)
	(gr_line
		(start 7.502906 -341.19947)
		(end 7.502906 -340.386924)
		(stroke
			(width 0.2)
			(type default)
		)
		(layer "In4.Cu")
	)
	(gr_arc
		(start 7.502906 -340.386924)
		(mid 6.992493 -339.87613)
		(end 6.481826 -340.38667)
		(stroke
			(width 0.2)
			(type default)
		)
		(layer "In4.Cu")
	)
	(gr_line
		(start 7.502906 -337.999578)
		(end 7.502906 -337.187032)
		(stroke
			(width 0.2)
			(type default)
		)
		(layer "In4.Cu")
	)
	(gr_arc
		(start 7.502906 -337.187032)
		(mid 6.992493 -336.676238)
		(end 6.481826 -337.186778)
		(stroke
			(width 0.2)
			(type default)
		)
		(layer "In4.Cu")
	)
	(gr_line
		(start 7.502906 -334.799432)
		(end 7.502906 -333.986886)
		(stroke
			(width 0.2)
			(type default)
		)
		(layer "In4.Cu")
	)
	(gr_arc
		(start 7.502906 -333.986886)
		(mid 6.992493 -333.476092)
		(end 6.481826 -333.986632)
		(stroke
			(width 0.2)
			(type default)
		)
		(layer "In4.Cu")
	)
	(gr_line
		(start 7.502906 -329.148694)
		(end 7.502906 -328.335894)
		(stroke
			(width 0.2)
			(type default)
		)
		(layer "In4.Cu")
	)
	(gr_arc
		(start 7.502906 -328.335894)
		(mid 6.992366 -327.825354)
		(end 6.481826 -328.335894)
		(stroke
			(width 0.2)
			(type default)
		)
		(layer "In4.Cu")
	)
	(gr_line
		(start 7.502906 -325.948802)
		(end 7.502906 -325.136002)
		(stroke
			(width 0.2)
			(type default)
		)
		(layer "In4.Cu")
	)
	(gr_arc
		(start 7.502906 -325.136002)
		(mid 6.992366 -324.625462)
		(end 6.481826 -325.136002)
		(stroke
			(width 0.2)
			(type default)
		)
		(layer "In4.Cu")
	)
	(gr_line
		(start 7.502906 -322.748656)
		(end 7.502906 -321.935856)
		(stroke
			(width 0.2)
			(type default)
		)
		(layer "In4.Cu")
	)
	(gr_arc
		(start 7.502906 -321.935856)
		(mid 6.992366 -321.425316)
		(end 6.481826 -321.935856)
		(stroke
			(width 0.2)
			(type default)
		)
		(layer "In4.Cu")
	)
	(gr_line
		(start 7.502906 -319.548764)
		(end 7.502906 -318.735964)
		(stroke
			(width 0.2)
			(type default)
		)
		(layer "In4.Cu")
	)
	(gr_arc
		(start 7.502906 -318.735964)
		(mid 6.992366 -318.225424)
		(end 6.481826 -318.735964)
		(stroke
			(width 0.2)
			(type default)
		)
		(layer "In4.Cu")
	)
	(gr_line
		(start 7.502906 -311.54878)
		(end 7.502906 -310.73598)
		(stroke
			(width 0.2)
			(type default)
		)
		(layer "In4.Cu")
	)
	(gr_arc
		(start 7.502906 -310.73598)
		(mid 6.992366 -310.22544)
		(end 6.481826 -310.73598)
		(stroke
			(width 0.2)
			(type default)
		)
		(layer "In4.Cu")
	)
	(gr_line
		(start 7.502906 -308.348634)
		(end 7.502906 -307.535834)
		(stroke
			(width 0.2)
			(type default)
		)
		(layer "In4.Cu")
	)
	(gr_arc
		(start 7.502906 -307.535834)
		(mid 6.992366 -307.025294)
		(end 6.481826 -307.535834)
		(stroke
			(width 0.2)
			(type default)
		)
		(layer "In4.Cu")
	)
	(gr_line
		(start 7.502906 -305.148742)
		(end 7.502906 -304.335942)
		(stroke
			(width 0.2)
			(type default)
		)
		(layer "In4.Cu")
	)
	(gr_arc
		(start 7.502906 -304.335942)
		(mid 6.992366 -303.825402)
		(end 6.481826 -304.335942)
		(stroke
			(width 0.2)
			(type default)
		)
		(layer "In4.Cu")
	)
	(gr_line
		(start 7.502906 -301.948596)
		(end 7.502906 -301.135796)
		(stroke
			(width 0.2)
			(type default)
		)
		(layer "In4.Cu")
	)
	(gr_arc
		(start 7.502906 -301.135796)
		(mid 6.992366 -300.625256)
		(end 6.481826 -301.135796)
		(stroke
			(width 0.2)
			(type default)
		)
		(layer "In4.Cu")
	)
	(gr_line
		(start 7.502906 -298.748704)
		(end 7.502906 -297.935904)
		(stroke
			(width 0.2)
			(type default)
		)
		(layer "In4.Cu")
	)
	(gr_arc
		(start 7.502906 -297.935904)
		(mid 6.992366 -297.425364)
		(end 6.481826 -297.935904)
		(stroke
			(width 0.2)
			(type default)
		)
		(layer "In4.Cu")
	)
	(gr_line
		(start 7.502906 -295.548812)
		(end 7.502906 -294.736012)
		(stroke
			(width 0.2)
			(type default)
		)
		(layer "In4.Cu")
	)
	(gr_arc
		(start 7.502906 -294.736012)
		(mid 6.992366 -294.225472)
		(end 6.481826 -294.736012)
		(stroke
			(width 0.2)
			(type default)
		)
		(layer "In4.Cu")
	)
	(gr_line
		(start 7.502906 -292.348666)
		(end 7.502906 -291.535866)
		(stroke
			(width 0.2)
			(type default)
		)
		(layer "In4.Cu")
	)
	(gr_arc
		(start 7.502906 -291.535866)
		(mid 6.992366 -291.025326)
		(end 6.481826 -291.535866)
		(stroke
			(width 0.2)
			(type default)
		)
		(layer "In4.Cu")
	)
	(gr_line
		(start 7.502906 -289.148774)
		(end 7.502906 -288.336228)
		(stroke
			(width 0.2)
			(type default)
		)
		(layer "In4.Cu")
	)
	(gr_arc
		(start 7.502906 -288.336228)
		(mid 6.992493 -287.825434)
		(end 6.481826 -288.335974)
		(stroke
			(width 0.2)
			(type default)
		)
		(layer "In4.Cu")
	)
	(gr_line
		(start 7.502906 -282.799536)
		(end 7.502906 -281.98699)
		(stroke
			(width 0.2)
			(type default)
		)
		(layer "In4.Cu")
	)
	(gr_arc
		(start 7.502906 -281.98699)
		(mid 6.992493 -281.476196)
		(end 6.481826 -281.986736)
		(stroke
			(width 0.2)
			(type default)
		)
		(layer "In4.Cu")
	)
	(gr_line
		(start 7.502906 -279.59939)
		(end 7.502906 -278.786844)
		(stroke
			(width 0.2)
			(type default)
		)
		(layer "In4.Cu")
	)
	(gr_arc
		(start 7.502906 -278.786844)
		(mid 6.992493 -278.27605)
		(end 6.481826 -278.78659)
		(stroke
			(width 0.2)
			(type default)
		)
		(layer "In4.Cu")
	)
	(gr_line
		(start 7.502906 -231.148636)
		(end 7.502906 -230.33609)
		(stroke
			(width 0.2)
			(type default)
		)
		(layer "In4.Cu")
	)
	(gr_arc
		(start 7.502906 -230.33609)
		(mid 6.992493 -229.825296)
		(end 6.481826 -230.335836)
		(stroke
			(width 0.2)
			(type default)
		)
		(layer "In4.Cu")
	)
	(gr_line
		(start 7.502906 -227.948744)
		(end 7.502906 -227.136198)
		(stroke
			(width 0.2)
			(type default)
		)
		(layer "In4.Cu")
	)
	(gr_arc
		(start 7.502906 -227.136198)
		(mid 6.992493 -226.625404)
		(end 6.481826 -227.135944)
		(stroke
			(width 0.2)
			(type default)
		)
		(layer "In4.Cu")
	)
	(gr_line
		(start 7.502906 -224.710498)
		(end 7.502906 -223.897952)
		(stroke
			(width 0.2)
			(type default)
		)
		(layer "In4.Cu")
	)
	(gr_arc
		(start 7.502906 -223.897952)
		(mid 6.992493 -223.387158)
		(end 6.481826 -223.897698)
		(stroke
			(width 0.2)
			(type default)
		)
		(layer "In4.Cu")
	)
	(gr_line
		(start 7.502906 -221.497906)
		(end 7.502906 -220.685106)
		(stroke
			(width 0.2)
			(type default)
		)
		(layer "In4.Cu")
	)
	(gr_arc
		(start 7.502906 -220.685106)
		(mid 6.992366 -220.174566)
		(end 6.481826 -220.685106)
		(stroke
			(width 0.2)
			(type default)
		)
		(layer "In4.Cu")
	)
	(gr_line
		(start 7.502906 -218.298014)
		(end 7.502906 -217.485468)
		(stroke
			(width 0.2)
			(type default)
		)
		(layer "In4.Cu")
	)
	(gr_arc
		(start 7.502906 -217.485468)
		(mid 6.992493 -216.974674)
		(end 6.481826 -217.485214)
		(stroke
			(width 0.2)
			(type default)
		)
		(layer "In4.Cu")
	)
	(gr_line
		(start 7.502906 -215.097868)
		(end 7.502906 -214.285322)
		(stroke
			(width 0.2)
			(type default)
		)
		(layer "In4.Cu")
	)
	(gr_arc
		(start 7.502906 -214.285322)
		(mid 6.992493 -213.774528)
		(end 6.481826 -214.285068)
		(stroke
			(width 0.2)
			(type default)
		)
		(layer "In4.Cu")
	)
	(gr_line
		(start 7.502906 -211.948776)
		(end 7.502906 -211.13623)
		(stroke
			(width 0.2)
			(type default)
		)
		(layer "In4.Cu")
	)
	(gr_arc
		(start 7.502906 -211.13623)
		(mid 6.992493 -210.625436)
		(end 6.481826 -211.135976)
		(stroke
			(width 0.2)
			(type default)
		)
		(layer "In4.Cu")
	)
	(gr_line
		(start 7.502906 -208.74863)
		(end 7.502906 -207.936084)
		(stroke
			(width 0.2)
			(type default)
		)
		(layer "In4.Cu")
	)
	(gr_arc
		(start 7.502906 -207.936084)
		(mid 6.992493 -207.42529)
		(end 6.481826 -207.93583)
		(stroke
			(width 0.2)
			(type default)
		)
		(layer "In4.Cu")
	)
	(gr_line
		(start 7.502906 -205.548738)
		(end 7.502906 -204.736192)
		(stroke
			(width 0.2)
			(type default)
		)
		(layer "In4.Cu")
	)
	(gr_arc
		(start 7.502906 -204.736192)
		(mid 6.992493 -204.225398)
		(end 6.481826 -204.735938)
		(stroke
			(width 0.2)
			(type default)
		)
		(layer "In4.Cu")
	)
	(gr_line
		(start 7.502906 -202.348592)
		(end 7.502906 -201.536046)
		(stroke
			(width 0.2)
			(type default)
		)
		(layer "In4.Cu")
	)
	(gr_arc
		(start 7.502906 -201.536046)
		(mid 6.992493 -201.025252)
		(end 6.481826 -201.535792)
		(stroke
			(width 0.2)
			(type default)
		)
		(layer "In4.Cu")
	)
	(gr_line
		(start 7.502906 -196.748654)
		(end 7.502906 -195.936108)
		(stroke
			(width 0.2)
			(type default)
		)
		(layer "In4.Cu")
	)
	(gr_arc
		(start 7.502906 -195.936108)
		(mid 6.992493 -195.425314)
		(end 6.481826 -195.935854)
		(stroke
			(width 0.2)
			(type default)
		)
		(layer "In4.Cu")
	)
	(gr_line
		(start 7.502906 -193.548762)
		(end 7.502906 -192.736216)
		(stroke
			(width 0.2)
			(type default)
		)
		(layer "In4.Cu")
	)
	(gr_arc
		(start 7.502906 -192.736216)
		(mid 6.992493 -192.225422)
		(end 6.481826 -192.735962)
		(stroke
			(width 0.2)
			(type default)
		)
		(layer "In4.Cu")
	)
	(gr_line
		(start 7.502906 -185.548778)
		(end 7.502906 -184.736232)
		(stroke
			(width 0.2)
			(type default)
		)
		(layer "In4.Cu")
	)
	(gr_arc
		(start 7.502906 -184.736232)
		(mid 6.992493 -184.225438)
		(end 6.481826 -184.735978)
		(stroke
			(width 0.2)
			(type default)
		)
		(layer "In4.Cu")
	)
	(gr_line
		(start 7.502906 -182.348632)
		(end 7.502906 -181.536086)
		(stroke
			(width 0.2)
			(type default)
		)
		(layer "In4.Cu")
	)
	(gr_arc
		(start 7.502906 -181.536086)
		(mid 6.992493 -181.025292)
		(end 6.481826 -181.535832)
		(stroke
			(width 0.2)
			(type default)
		)
		(layer "In4.Cu")
	)
	(gr_line
		(start 7.502906 -179.19954)
		(end 7.502906 -178.386994)
		(stroke
			(width 0.2)
			(type default)
		)
		(layer "In4.Cu")
	)
	(gr_arc
		(start 7.502906 -178.386994)
		(mid 6.992493 -177.8762)
		(end 6.481826 -178.38674)
		(stroke
			(width 0.2)
			(type default)
		)
		(layer "In4.Cu")
	)
	(gr_line
		(start 7.502906 -175.999394)
		(end 7.502906 -175.186848)
		(stroke
			(width 0.2)
			(type default)
		)
		(layer "In4.Cu")
	)
	(gr_arc
		(start 7.502906 -175.186848)
		(mid 6.992493 -174.676054)
		(end 6.481826 -175.186594)
		(stroke
			(width 0.2)
			(type default)
		)
		(layer "In4.Cu")
	)
	(gr_line
		(start 7.502906 -172.799502)
		(end 7.502906 -171.986956)
		(stroke
			(width 0.2)
			(type default)
		)
		(layer "In4.Cu")
	)
	(gr_arc
		(start 7.502906 -171.986956)
		(mid 6.992493 -171.476162)
		(end 6.481826 -171.986702)
		(stroke
			(width 0.2)
			(type default)
		)
		(layer "In4.Cu")
	)
	(gr_line
		(start 7.502906 -169.59961)
		(end 7.502906 -168.787064)
		(stroke
			(width 0.2)
			(type default)
		)
		(layer "In4.Cu")
	)
	(gr_arc
		(start 7.502906 -168.787064)
		(mid 6.992493 -168.27627)
		(end 6.481826 -168.78681)
		(stroke
			(width 0.2)
			(type default)
		)
		(layer "In4.Cu")
	)
	(gr_line
		(start 7.502906 -163.199572)
		(end 7.502906 -162.387026)
		(stroke
			(width 0.2)
			(type default)
		)
		(layer "In4.Cu")
	)
	(gr_arc
		(start 7.502906 -162.387026)
		(mid 6.992493 -161.876232)
		(end 6.481826 -162.386772)
		(stroke
			(width 0.2)
			(type default)
		)
		(layer "In4.Cu")
	)
	(gr_line
		(start 7.502906 -159.999426)
		(end 7.502906 -159.18688)
		(stroke
			(width 0.2)
			(type default)
		)
		(layer "In4.Cu")
	)
	(gr_arc
		(start 7.502906 -159.18688)
		(mid 6.992493 -158.676086)
		(end 6.481826 -159.186626)
		(stroke
			(width 0.2)
			(type default)
		)
		(layer "In4.Cu")
	)
	(gr_line
		(start 7.502906 -156.786834)
		(end 7.502906 -155.974288)
		(stroke
			(width 0.2)
			(type default)
		)
		(layer "In4.Cu")
	)
	(gr_arc
		(start 7.502906 -155.974288)
		(mid 6.992493 -155.463494)
		(end 6.481826 -155.974034)
		(stroke
			(width 0.2)
			(type default)
		)
		(layer "In4.Cu")
	)
	(gr_line
		(start 7.502906 -153.599388)
		(end 7.502906 -152.786842)
		(stroke
			(width 0.2)
			(type default)
		)
		(layer "In4.Cu")
	)
	(gr_arc
		(start 7.502906 -152.786842)
		(mid 6.992493 -152.276048)
		(end 6.481826 -152.786588)
		(stroke
			(width 0.2)
			(type default)
		)
		(layer "In4.Cu")
	)
	(gr_line
		(start 8.382254 -386.113782)
		(end 9.1948 -386.113782)
		(stroke
			(width 0.2)
			(type default)
		)
		(layer "In4.Cu")
	)
	(gr_arc
		(start 8.382254 -385.092702)
		(mid 7.871714 -385.603242)
		(end 8.382254 -386.113782)
		(stroke
			(width 0.2)
			(type default)
		)
		(layer "In4.Cu")
	)
	(gr_arc
		(start 9.1948 -386.113782)
		(mid 9.705594 -385.603369)
		(end 9.195054 -385.092702)
		(stroke
			(width 0.2)
			(type default)
		)
		(layer "In4.Cu")
	)
	(gr_line
		(start 9.195054 -385.092702)
		(end 8.382254 -385.092702)
		(stroke
			(width 0.2)
			(type default)
		)
		(layer "In4.Cu")
	)
	(gr_arc
		(start 16.76146 -445.415924)
		(mid 17.271873 -445.926718)
		(end 17.78254 -445.416178)
		(stroke
			(width 0.2)
			(type default)
		)
		(layer "In4.Cu")
	)
	(gr_line
		(start 16.76146 -444.603378)
		(end 16.76146 -445.415924)
		(stroke
			(width 0.2)
			(type default)
		)
		(layer "In4.Cu")
	)
	(gr_arc
		(start 16.76146 -342.415876)
		(mid 17.271873 -342.92667)
		(end 17.78254 -342.41613)
		(stroke
			(width 0.2)
			(type default)
		)
		(layer "In4.Cu")
	)
	(gr_line
		(start 16.76146 -341.60333)
		(end 16.76146 -342.415876)
		(stroke
			(width 0.2)
			(type default)
		)
		(layer "In4.Cu")
	)
	(gr_arc
		(start 16.76146 -239.415828)
		(mid 17.271873 -239.926622)
		(end 17.78254 -239.416082)
		(stroke
			(width 0.2)
			(type default)
		)
		(layer "In4.Cu")
	)
	(gr_line
		(start 16.76146 -238.603282)
		(end 16.76146 -239.415828)
		(stroke
			(width 0.2)
			(type default)
		)
		(layer "In4.Cu")
	)
	(gr_arc
		(start 16.76146 -136.41578)
		(mid 17.271873 -136.926574)
		(end 17.78254 -136.416034)
		(stroke
			(width 0.2)
			(type default)
		)
		(layer "In4.Cu")
	)
	(gr_line
		(start 16.76146 -135.603234)
		(end 16.76146 -136.41578)
		(stroke
			(width 0.2)
			(type default)
		)
		(layer "In4.Cu")
	)
	(gr_arc
		(start 16.76146 -33.415986)
		(mid 17.272 -33.926526)
		(end 17.78254 -33.415986)
		(stroke
			(width 0.2)
			(type default)
		)
		(layer "In4.Cu")
	)
	(gr_line
		(start 16.76146 -32.603186)
		(end 16.76146 -33.415986)
		(stroke
			(width 0.2)
			(type default)
		)
		(layer "In4.Cu")
	)
	(gr_line
		(start 17.78254 -445.416178)
		(end 17.78254 -444.603378)
		(stroke
			(width 0.2)
			(type default)
		)
		(layer "In4.Cu")
	)
	(gr_arc
		(start 17.78254 -444.603378)
		(mid 17.272 -444.092838)
		(end 16.76146 -444.603378)
		(stroke
			(width 0.2)
			(type default)
		)
		(layer "In4.Cu")
	)
	(gr_line
		(start 17.78254 -342.41613)
		(end 17.78254 -341.60333)
		(stroke
			(width 0.2)
			(type default)
		)
		(layer "In4.Cu")
	)
	(gr_arc
		(start 17.78254 -341.60333)
		(mid 17.272 -341.09279)
		(end 16.76146 -341.60333)
		(stroke
			(width 0.2)
			(type default)
		)
		(layer "In4.Cu")
	)
	(gr_line
		(start 17.78254 -239.416082)
		(end 17.78254 -238.603282)
		(stroke
			(width 0.2)
			(type default)
		)
		(layer "In4.Cu")
	)
	(gr_arc
		(start 17.78254 -238.603282)
		(mid 17.272 -238.092742)
		(end 16.76146 -238.603282)
		(stroke
			(width 0.2)
			(type default)
		)
		(layer "In4.Cu")
	)
	(gr_line
		(start 17.78254 -136.416034)
		(end 17.78254 -135.603234)
		(stroke
			(width 0.2)
			(type default)
		)
		(layer "In4.Cu")
	)
	(gr_arc
		(start 17.78254 -135.603234)
		(mid 17.272 -135.092694)
		(end 16.76146 -135.603234)
		(stroke
			(width 0.2)
			(type default)
		)
		(layer "In4.Cu")
	)
	(gr_line
		(start 17.78254 -33.415986)
		(end 17.78254 -32.60344)
		(stroke
			(width 0.2)
			(type default)
		)
		(layer "In4.Cu")
	)
	(gr_arc
		(start 17.78254 -32.60344)
		(mid 17.272127 -32.092646)
		(end 16.76146 -32.603186)
		(stroke
			(width 0.2)
			(type default)
		)
		(layer "In4.Cu")
	)
	(gr_arc
		(start 24.66086 -449.168774)
		(mid 25.273 -449.780914)
		(end 25.88514 -449.168774)
		(stroke
			(width 0.2)
			(type default)
		)
		(layer "In4.Cu")
	)
	(gr_line
		(start 24.66086 -448.051174)
		(end 24.66086 -449.168774)
		(stroke
			(width 0.2)
			(type default)
		)
		(layer "In4.Cu")
	)
	(gr_arc
		(start 24.66086 -436.368952)
		(mid 25.273 -436.981092)
		(end 25.88514 -436.368952)
		(stroke
			(width 0.2)
			(type default)
		)
		(layer "In4.Cu")
	)
	(gr_line
		(start 24.66086 -435.251352)
		(end 24.66086 -436.368952)
		(stroke
			(width 0.2)
			(type default)
		)
		(layer "In4.Cu")
	)
	(gr_arc
		(start 24.66086 -431.56886)
		(mid 25.273 -432.181)
		(end 25.88514 -431.56886)
		(stroke
			(width 0.2)
			(type default)
		)
		(layer "In4.Cu")
	)
	(gr_line
		(start 24.66086 -430.45126)
		(end 24.66086 -431.56886)
		(stroke
			(width 0.2)
			(type default)
		)
		(layer "In4.Cu")
	)
	(gr_arc
		(start 24.66086 -426.768768)
		(mid 25.273 -427.380908)
		(end 25.88514 -426.768768)
		(stroke
			(width 0.2)
			(type default)
		)
		(layer "In4.Cu")
	)
	(gr_line
		(start 24.66086 -425.651168)
		(end 24.66086 -426.768768)
		(stroke
			(width 0.2)
			(type default)
		)
		(layer "In4.Cu")
	)
	(gr_arc
		(start 24.66086 -346.168726)
		(mid 25.273 -346.780866)
		(end 25.88514 -346.168726)
		(stroke
			(width 0.2)
			(type default)
		)
		(layer "In4.Cu")
	)
	(gr_line
		(start 24.66086 -345.051126)
		(end 24.66086 -346.168726)
		(stroke
			(width 0.2)
			(type default)
		)
		(layer "In4.Cu")
	)
	(gr_arc
		(start 24.66086 -333.36865)
		(mid 25.272873 -333.981044)
		(end 25.88514 -333.368904)
		(stroke
			(width 0.2)
			(type default)
		)
		(layer "In4.Cu")
	)
	(gr_line
		(start 24.66086 -332.251304)
		(end 24.66086 -333.36865)
		(stroke
			(width 0.2)
			(type default)
		)
		(layer "In4.Cu")
	)
	(gr_arc
		(start 24.66086 -328.568558)
		(mid 25.272873 -329.180952)
		(end 25.88514 -328.568812)
		(stroke
			(width 0.2)
			(type default)
		)
		(layer "In4.Cu")
	)
	(gr_line
		(start 24.66086 -327.451212)
		(end 24.66086 -328.568558)
		(stroke
			(width 0.2)
			(type default)
		)
		(layer "In4.Cu")
	)
	(gr_arc
		(start 24.66086 -323.768466)
		(mid 25.272873 -324.38086)
		(end 25.88514 -323.76872)
		(stroke
			(width 0.2)
			(type default)
		)
		(layer "In4.Cu")
	)
	(gr_line
		(start 24.66086 -322.65112)
		(end 24.66086 -323.768466)
		(stroke
			(width 0.2)
			(type default)
		)
		(layer "In4.Cu")
	)
	(gr_arc
		(start 24.66086 -243.168424)
		(mid 25.272873 -243.780818)
		(end 25.88514 -243.168678)
		(stroke
			(width 0.2)
			(type default)
		)
		(layer "In4.Cu")
	)
	(gr_line
		(start 24.66086 -242.051078)
		(end 24.66086 -243.168424)
		(stroke
			(width 0.2)
			(type default)
		)
		(layer "In4.Cu")
	)
	(gr_arc
		(start 24.66086 -230.368602)
		(mid 25.272873 -230.980996)
		(end 25.88514 -230.368856)
		(stroke
			(width 0.2)
			(type default)
		)
		(layer "In4.Cu")
	)
	(gr_line
		(start 24.66086 -229.251256)
		(end 24.66086 -230.368602)
		(stroke
			(width 0.2)
			(type default)
		)
		(layer "In4.Cu")
	)
	(gr_arc
		(start 24.66086 -225.56851)
		(mid 25.272873 -226.180904)
		(end 25.88514 -225.568764)
		(stroke
			(width 0.2)
			(type default)
		)
		(layer "In4.Cu")
	)
	(gr_line
		(start 24.66086 -224.451164)
		(end 24.66086 -225.56851)
		(stroke
			(width 0.2)
			(type default)
		)
		(layer "In4.Cu")
	)
	(gr_arc
		(start 24.66086 -220.768672)
		(mid 25.273 -221.380812)
		(end 25.88514 -220.768672)
		(stroke
			(width 0.2)
			(type default)
		)
		(layer "In4.Cu")
	)
	(gr_line
		(start 24.66086 -219.651072)
		(end 24.66086 -220.768672)
		(stroke
			(width 0.2)
			(type default)
		)
		(layer "In4.Cu")
	)
	(gr_arc
		(start 24.66086 -140.16863)
		(mid 25.273 -140.78077)
		(end 25.88514 -140.16863)
		(stroke
			(width 0.2)
			(type default)
		)
		(layer "In4.Cu")
	)
	(gr_line
		(start 24.66086 -139.05103)
		(end 24.66086 -140.16863)
		(stroke
			(width 0.2)
			(type default)
		)
		(layer "In4.Cu")
	)
	(gr_arc
		(start 24.66086 -127.368554)
		(mid 25.272873 -127.980948)
		(end 25.88514 -127.368808)
		(stroke
			(width 0.2)
			(type default)
		)
		(layer "In4.Cu")
	)
	(gr_line
		(start 24.66086 -126.251208)
		(end 24.66086 -127.368554)
		(stroke
			(width 0.2)
			(type default)
		)
		(layer "In4.Cu")
	)
	(gr_arc
		(start 24.66086 -122.568462)
		(mid 25.272873 -123.180856)
		(end 25.88514 -122.568716)
		(stroke
			(width 0.2)
			(type default)
		)
		(layer "In4.Cu")
	)
	(gr_line
		(start 24.66086 -121.451116)
		(end 24.66086 -122.568462)
		(stroke
			(width 0.2)
			(type default)
		)
		(layer "In4.Cu")
	)
	(gr_arc
		(start 24.66086 -117.768624)
		(mid 25.273 -118.380764)
		(end 25.88514 -117.768624)
		(stroke
			(width 0.2)
			(type default)
		)
		(layer "In4.Cu")
	)
	(gr_line
		(start 24.66086 -116.651024)
		(end 24.66086 -117.768624)
		(stroke
			(width 0.2)
			(type default)
		)
		(layer "In4.Cu")
	)
	(gr_arc
		(start 24.66086 -37.168328)
		(mid 25.272873 -37.780722)
		(end 25.88514 -37.168582)
		(stroke
			(width 0.2)
			(type default)
		)
		(layer "In4.Cu")
	)
	(gr_line
		(start 24.66086 -36.050982)
		(end 24.66086 -37.168328)
		(stroke
			(width 0.2)
			(type default)
		)
		(layer "In4.Cu")
	)
	(gr_arc
		(start 24.66086 -24.368506)
		(mid 25.272873 -24.9809)
		(end 25.88514 -24.36876)
		(stroke
			(width 0.2)
			(type default)
		)
		(layer "In4.Cu")
	)
	(gr_line
		(start 24.66086 -23.25116)
		(end 24.66086 -24.368506)
		(stroke
			(width 0.2)
			(type default)
		)
		(layer "In4.Cu")
	)
	(gr_arc
		(start 24.66086 -19.568414)
		(mid 25.272873 -20.180808)
		(end 25.88514 -19.568668)
		(stroke
			(width 0.2)
			(type default)
		)
		(layer "In4.Cu")
	)
	(gr_line
		(start 24.66086 -18.451068)
		(end 24.66086 -19.568414)
		(stroke
			(width 0.2)
			(type default)
		)
		(layer "In4.Cu")
	)
	(gr_arc
		(start 24.66086 -14.793976)
		(mid 25.273 -15.406116)
		(end 25.88514 -14.793976)
		(stroke
			(width 0.2)
			(type default)
		)
		(layer "In4.Cu")
	)
	(gr_line
		(start 24.66086 -13.676376)
		(end 24.66086 -14.793976)
		(stroke
			(width 0.2)
			(type default)
		)
		(layer "In4.Cu")
	)
	(gr_line
		(start 25.88514 -449.168774)
		(end 25.88514 -448.051428)
		(stroke
			(width 0.2)
			(type default)
		)
		(layer "In4.Cu")
	)
	(gr_arc
		(start 25.88514 -448.051428)
		(mid 25.273127 -447.439034)
		(end 24.66086 -448.051174)
		(stroke
			(width 0.2)
			(type default)
		)
		(layer "In4.Cu")
	)
	(gr_line
		(start 25.88514 -436.368952)
		(end 25.88514 -435.251606)
		(stroke
			(width 0.2)
			(type default)
		)
		(layer "In4.Cu")
	)
	(gr_arc
		(start 25.88514 -435.251606)
		(mid 25.273127 -434.639212)
		(end 24.66086 -435.251352)
		(stroke
			(width 0.2)
			(type default)
		)
		(layer "In4.Cu")
	)
	(gr_line
		(start 25.88514 -431.56886)
		(end 25.88514 -430.451514)
		(stroke
			(width 0.2)
			(type default)
		)
		(layer "In4.Cu")
	)
	(gr_arc
		(start 25.88514 -430.451514)
		(mid 25.273127 -429.83912)
		(end 24.66086 -430.45126)
		(stroke
			(width 0.2)
			(type default)
		)
		(layer "In4.Cu")
	)
	(gr_line
		(start 25.88514 -426.768768)
		(end 25.88514 -425.651422)
		(stroke
			(width 0.2)
			(type default)
		)
		(layer "In4.Cu")
	)
	(gr_arc
		(start 25.88514 -425.651422)
		(mid 25.273127 -425.039028)
		(end 24.66086 -425.651168)
		(stroke
			(width 0.2)
			(type default)
		)
		(layer "In4.Cu")
	)
	(gr_line
		(start 25.88514 -346.168726)
		(end 25.88514 -345.05138)
		(stroke
			(width 0.2)
			(type default)
		)
		(layer "In4.Cu")
	)
	(gr_arc
		(start 25.88514 -345.05138)
		(mid 25.273127 -344.438986)
		(end 24.66086 -345.051126)
		(stroke
			(width 0.2)
			(type default)
		)
		(layer "In4.Cu")
	)
	(gr_line
		(start 25.88514 -333.368904)
		(end 25.88514 -332.251304)
		(stroke
			(width 0.2)
			(type default)
		)
		(layer "In4.Cu")
	)
	(gr_arc
		(start 25.88514 -332.251304)
		(mid 25.273 -331.639164)
		(end 24.66086 -332.251304)
		(stroke
			(width 0.2)
			(type default)
		)
		(layer "In4.Cu")
	)
	(gr_line
		(start 25.88514 -328.568812)
		(end 25.88514 -327.451212)
		(stroke
			(width 0.2)
			(type default)
		)
		(layer "In4.Cu")
	)
	(gr_arc
		(start 25.88514 -327.451212)
		(mid 25.273 -326.839072)
		(end 24.66086 -327.451212)
		(stroke
			(width 0.2)
			(type default)
		)
		(layer "In4.Cu")
	)
	(gr_line
		(start 25.88514 -323.76872)
		(end 25.88514 -322.65112)
		(stroke
			(width 0.2)
			(type default)
		)
		(layer "In4.Cu")
	)
	(gr_arc
		(start 25.88514 -322.65112)
		(mid 25.273 -322.03898)
		(end 24.66086 -322.65112)
		(stroke
			(width 0.2)
			(type default)
		)
		(layer "In4.Cu")
	)
	(gr_line
		(start 25.88514 -243.168678)
		(end 25.88514 -242.051078)
		(stroke
			(width 0.2)
			(type default)
		)
		(layer "In4.Cu")
	)
	(gr_arc
		(start 25.88514 -242.051078)
		(mid 25.273 -241.438938)
		(end 24.66086 -242.051078)
		(stroke
			(width 0.2)
			(type default)
		)
		(layer "In4.Cu")
	)
	(gr_line
		(start 25.88514 -230.368856)
		(end 25.88514 -229.251256)
		(stroke
			(width 0.2)
			(type default)
		)
		(layer "In4.Cu")
	)
	(gr_arc
		(start 25.88514 -229.251256)
		(mid 25.273 -228.639116)
		(end 24.66086 -229.251256)
		(stroke
			(width 0.2)
			(type default)
		)
		(layer "In4.Cu")
	)
	(gr_line
		(start 25.88514 -225.568764)
		(end 25.88514 -224.451164)
		(stroke
			(width 0.2)
			(type default)
		)
		(layer "In4.Cu")
	)
	(gr_arc
		(start 25.88514 -224.451164)
		(mid 25.273 -223.839024)
		(end 24.66086 -224.451164)
		(stroke
			(width 0.2)
			(type default)
		)
		(layer "In4.Cu")
	)
	(gr_line
		(start 25.88514 -220.768672)
		(end 25.88514 -219.651326)
		(stroke
			(width 0.2)
			(type default)
		)
		(layer "In4.Cu")
	)
	(gr_arc
		(start 25.88514 -219.651326)
		(mid 25.273127 -219.038932)
		(end 24.66086 -219.651072)
		(stroke
			(width 0.2)
			(type default)
		)
		(layer "In4.Cu")
	)
	(gr_line
		(start 25.88514 -140.16863)
		(end 25.88514 -139.051284)
		(stroke
			(width 0.2)
			(type default)
		)
		(layer "In4.Cu")
	)
	(gr_arc
		(start 25.88514 -139.051284)
		(mid 25.273127 -138.43889)
		(end 24.66086 -139.05103)
		(stroke
			(width 0.2)
			(type default)
		)
		(layer "In4.Cu")
	)
	(gr_line
		(start 25.88514 -127.368808)
		(end 25.88514 -126.251208)
		(stroke
			(width 0.2)
			(type default)
		)
		(layer "In4.Cu")
	)
	(gr_arc
		(start 25.88514 -126.251208)
		(mid 25.273 -125.639068)
		(end 24.66086 -126.251208)
		(stroke
			(width 0.2)
			(type default)
		)
		(layer "In4.Cu")
	)
	(gr_line
		(start 25.88514 -122.568716)
		(end 25.88514 -121.451116)
		(stroke
			(width 0.2)
			(type default)
		)
		(layer "In4.Cu")
	)
	(gr_arc
		(start 25.88514 -121.451116)
		(mid 25.273 -120.838976)
		(end 24.66086 -121.451116)
		(stroke
			(width 0.2)
			(type default)
		)
		(layer "In4.Cu")
	)
	(gr_line
		(start 25.88514 -117.768624)
		(end 25.88514 -116.651278)
		(stroke
			(width 0.2)
			(type default)
		)
		(layer "In4.Cu")
	)
	(gr_arc
		(start 25.88514 -116.651278)
		(mid 25.273127 -116.038884)
		(end 24.66086 -116.651024)
		(stroke
			(width 0.2)
			(type default)
		)
		(layer "In4.Cu")
	)
	(gr_line
		(start 25.88514 -37.168582)
		(end 25.88514 -36.050982)
		(stroke
			(width 0.2)
			(type default)
		)
		(layer "In4.Cu")
	)
	(gr_arc
		(start 25.88514 -36.050982)
		(mid 25.273 -35.438842)
		(end 24.66086 -36.050982)
		(stroke
			(width 0.2)
			(type default)
		)
		(layer "In4.Cu")
	)
	(gr_line
		(start 25.88514 -24.36876)
		(end 25.88514 -23.25116)
		(stroke
			(width 0.2)
			(type default)
		)
		(layer "In4.Cu")
	)
	(gr_arc
		(start 25.88514 -23.25116)
		(mid 25.273 -22.63902)
		(end 24.66086 -23.25116)
		(stroke
			(width 0.2)
			(type default)
		)
		(layer "In4.Cu")
	)
	(gr_line
		(start 25.88514 -19.568668)
		(end 25.88514 -18.451068)
		(stroke
			(width 0.2)
			(type default)
		)
		(layer "In4.Cu")
	)
	(gr_arc
		(start 25.88514 -18.451068)
		(mid 25.273 -17.838928)
		(end 24.66086 -18.451068)
		(stroke
			(width 0.2)
			(type default)
		)
		(layer "In4.Cu")
	)
	(gr_line
		(start 25.88514 -14.793976)
		(end 25.88514 -13.67663)
		(stroke
			(width 0.2)
			(type default)
		)
		(layer "In4.Cu")
	)
	(gr_arc
		(start 25.88514 -13.67663)
		(mid 25.273127 -13.064236)
		(end 24.66086 -13.676376)
		(stroke
			(width 0.2)
			(type default)
		)
		(layer "In4.Cu")
	)
	(gr_arc
		(start 26.15946 -451.41642)
		(mid 26.67 -451.92696)
		(end 27.18054 -451.41642)
		(stroke
			(width 0.2)
			(type default)
		)
		(layer "In4.Cu")
	)
	(gr_line
		(start 26.15946 -450.60362)
		(end 26.15946 -451.41642)
		(stroke
			(width 0.2)
			(type default)
		)
		(layer "In4.Cu")
	)
	(gr_arc
		(start 26.15946 -438.616344)
		(mid 26.67 -439.126884)
		(end 27.18054 -438.616344)
		(stroke
			(width 0.2)
			(type default)
		)
		(layer "In4.Cu")
	)
	(gr_line
		(start 26.15946 -437.803544)
		(end 26.15946 -438.616344)
		(stroke
			(width 0.2)
			(type default)
		)
		(layer "In4.Cu")
	)
	(gr_arc
		(start 26.15946 -433.816506)
		(mid 26.67 -434.327046)
		(end 27.18054 -433.816506)
		(stroke
			(width 0.2)
			(type default)
		)
		(layer "In4.Cu")
	)
	(gr_line
		(start 26.15946 -433.003706)
		(end 26.15946 -433.816506)
		(stroke
			(width 0.2)
			(type default)
		)
		(layer "In4.Cu")
	)
	(gr_arc
		(start 26.15946 -429.016414)
		(mid 26.67 -429.526954)
		(end 27.18054 -429.016414)
		(stroke
			(width 0.2)
			(type default)
		)
		(layer "In4.Cu")
	)
	(gr_line
		(start 26.15946 -428.203614)
		(end 26.15946 -429.016414)
		(stroke
			(width 0.2)
			(type default)
		)
		(layer "In4.Cu")
	)
	(gr_arc
		(start 26.15946 -348.416118)
		(mid 26.669873 -348.926912)
		(end 27.18054 -348.416372)
		(stroke
			(width 0.2)
			(type default)
		)
		(layer "In4.Cu")
	)
	(gr_line
		(start 26.15946 -347.603572)
		(end 26.15946 -348.416118)
		(stroke
			(width 0.2)
			(type default)
		)
		(layer "In4.Cu")
	)
	(gr_arc
		(start 26.15946 -335.616042)
		(mid 26.669873 -336.126836)
		(end 27.18054 -335.616296)
		(stroke
			(width 0.2)
			(type default)
		)
		(layer "In4.Cu")
	)
	(gr_line
		(start 26.15946 -334.803496)
		(end 26.15946 -335.616042)
		(stroke
			(width 0.2)
			(type default)
		)
		(layer "In4.Cu")
	)
	(gr_arc
		(start 26.15946 -330.816204)
		(mid 26.669873 -331.326998)
		(end 27.18054 -330.816458)
		(stroke
			(width 0.2)
			(type default)
		)
		(layer "In4.Cu")
	)
	(gr_line
		(start 26.15946 -330.003658)
		(end 26.15946 -330.816204)
		(stroke
			(width 0.2)
			(type default)
		)
		(layer "In4.Cu")
	)
	(gr_arc
		(start 26.15946 -326.016112)
		(mid 26.669873 -326.526906)
		(end 27.18054 -326.016366)
		(stroke
			(width 0.2)
			(type default)
		)
		(layer "In4.Cu")
	)
	(gr_line
		(start 26.15946 -325.203566)
		(end 26.15946 -326.016112)
		(stroke
			(width 0.2)
			(type default)
		)
		(layer "In4.Cu")
	)
	(gr_arc
		(start 26.15946 -245.41607)
		(mid 26.669873 -245.926864)
		(end 27.18054 -245.416324)
		(stroke
			(width 0.2)
			(type default)
		)
		(layer "In4.Cu")
	)
	(gr_line
		(start 26.15946 -244.603524)
		(end 26.15946 -245.41607)
		(stroke
			(width 0.2)
			(type default)
		)
		(layer "In4.Cu")
	)
	(gr_arc
		(start 26.15946 -232.615994)
		(mid 26.669873 -233.126788)
		(end 27.18054 -232.616248)
		(stroke
			(width 0.2)
			(type default)
		)
		(layer "In4.Cu")
	)
	(gr_line
		(start 26.15946 -231.803448)
		(end 26.15946 -232.615994)
		(stroke
			(width 0.2)
			(type default)
		)
		(layer "In4.Cu")
	)
	(gr_arc
		(start 26.15946 -227.816156)
		(mid 26.669873 -228.32695)
		(end 27.18054 -227.81641)
		(stroke
			(width 0.2)
			(type default)
		)
		(layer "In4.Cu")
	)
	(gr_line
		(start 26.15946 -227.00361)
		(end 26.15946 -227.816156)
		(stroke
			(width 0.2)
			(type default)
		)
		(layer "In4.Cu")
	)
	(gr_arc
		(start 26.15946 -223.016064)
		(mid 26.669873 -223.526858)
		(end 27.18054 -223.016318)
		(stroke
			(width 0.2)
			(type default)
		)
		(layer "In4.Cu")
	)
	(gr_line
		(start 26.15946 -222.203518)
		(end 26.15946 -223.016064)
		(stroke
			(width 0.2)
			(type default)
		)
		(layer "In4.Cu")
	)
	(gr_arc
		(start 26.15946 -142.416022)
		(mid 26.669873 -142.926816)
		(end 27.18054 -142.416276)
		(stroke
			(width 0.2)
			(type default)
		)
		(layer "In4.Cu")
	)
	(gr_line
		(start 26.15946 -141.603476)
		(end 26.15946 -142.416022)
		(stroke
			(width 0.2)
			(type default)
		)
		(layer "In4.Cu")
	)
	(gr_arc
		(start 26.15946 -129.615946)
		(mid 26.669873 -130.12674)
		(end 27.18054 -129.6162)
		(stroke
			(width 0.2)
			(type default)
		)
		(layer "In4.Cu")
	)
	(gr_line
		(start 26.15946 -128.8034)
		(end 26.15946 -129.615946)
		(stroke
			(width 0.2)
			(type default)
		)
		(layer "In4.Cu")
	)
	(gr_arc
		(start 26.15946 -124.816108)
		(mid 26.669873 -125.326902)
		(end 27.18054 -124.816362)
		(stroke
			(width 0.2)
			(type default)
		)
		(layer "In4.Cu")
	)
	(gr_line
		(start 26.15946 -124.003562)
		(end 26.15946 -124.816108)
		(stroke
			(width 0.2)
			(type default)
		)
		(layer "In4.Cu")
	)
	(gr_arc
		(start 26.15946 -120.016016)
		(mid 26.669873 -120.52681)
		(end 27.18054 -120.01627)
		(stroke
			(width 0.2)
			(type default)
		)
		(layer "In4.Cu")
	)
	(gr_line
		(start 26.15946 -119.20347)
		(end 26.15946 -120.016016)
		(stroke
			(width 0.2)
			(type default)
		)
		(layer "In4.Cu")
	)
	(gr_arc
		(start 26.15946 -39.415974)
		(mid 26.669873 -39.926768)
		(end 27.18054 -39.416228)
		(stroke
			(width 0.2)
			(type default)
		)
		(layer "In4.Cu")
	)
	(gr_line
		(start 26.15946 -38.603428)
		(end 26.15946 -39.415974)
		(stroke
			(width 0.2)
			(type default)
		)
		(layer "In4.Cu")
	)
	(gr_arc
		(start 26.15946 -26.615898)
		(mid 26.669873 -27.126692)
		(end 27.18054 -26.616152)
		(stroke
			(width 0.2)
			(type default)
		)
		(layer "In4.Cu")
	)
	(gr_line
		(start 26.15946 -25.803352)
		(end 26.15946 -26.615898)
		(stroke
			(width 0.2)
			(type default)
		)
		(layer "In4.Cu")
	)
	(gr_arc
		(start 26.15946 -21.81606)
		(mid 26.669873 -22.326854)
		(end 27.18054 -21.816314)
		(stroke
			(width 0.2)
			(type default)
		)
		(layer "In4.Cu")
	)
	(gr_line
		(start 26.15946 -21.003514)
		(end 26.15946 -21.81606)
		(stroke
			(width 0.2)
			(type default)
		)
		(layer "In4.Cu")
	)
	(gr_arc
		(start 26.15946 -17.015968)
		(mid 26.669873 -17.526762)
		(end 27.18054 -17.016222)
		(stroke
			(width 0.2)
			(type default)
		)
		(layer "In4.Cu")
	)
	(gr_line
		(start 26.15946 -16.203422)
		(end 26.15946 -17.015968)
		(stroke
			(width 0.2)
			(type default)
		)
		(layer "In4.Cu")
	)
	(gr_line
		(start 27.18054 -451.41642)
		(end 27.18054 -450.603874)
		(stroke
			(width 0.2)
			(type default)
		)
		(layer "In4.Cu")
	)
	(gr_arc
		(start 27.18054 -450.603874)
		(mid 26.670127 -450.09308)
		(end 26.15946 -450.60362)
		(stroke
			(width 0.2)
			(type default)
		)
		(layer "In4.Cu")
	)
	(gr_line
		(start 27.18054 -438.616344)
		(end 27.18054 -437.803798)
		(stroke
			(width 0.2)
			(type default)
		)
		(layer "In4.Cu")
	)
	(gr_arc
		(start 27.18054 -437.803798)
		(mid 26.670127 -437.293004)
		(end 26.15946 -437.803544)
		(stroke
			(width 0.2)
			(type default)
		)
		(layer "In4.Cu")
	)
	(gr_line
		(start 27.18054 -433.816506)
		(end 27.18054 -433.00396)
		(stroke
			(width 0.2)
			(type default)
		)
		(layer "In4.Cu")
	)
	(gr_arc
		(start 27.18054 -433.00396)
		(mid 26.670127 -432.493166)
		(end 26.15946 -433.003706)
		(stroke
			(width 0.2)
			(type default)
		)
		(layer "In4.Cu")
	)
	(gr_line
		(start 27.18054 -429.016414)
		(end 27.18054 -428.203868)
		(stroke
			(width 0.2)
			(type default)
		)
		(layer "In4.Cu")
	)
	(gr_arc
		(start 27.18054 -428.203868)
		(mid 26.670127 -427.693074)
		(end 26.15946 -428.203614)
		(stroke
			(width 0.2)
			(type default)
		)
		(layer "In4.Cu")
	)
	(gr_line
		(start 27.18054 -348.416372)
		(end 27.18054 -347.603572)
		(stroke
			(width 0.2)
			(type default)
		)
		(layer "In4.Cu")
	)
	(gr_arc
		(start 27.18054 -347.603572)
		(mid 26.67 -347.093032)
		(end 26.15946 -347.603572)
		(stroke
			(width 0.2)
			(type default)
		)
		(layer "In4.Cu")
	)
	(gr_line
		(start 27.18054 -335.616296)
		(end 27.18054 -334.803496)
		(stroke
			(width 0.2)
			(type default)
		)
		(layer "In4.Cu")
	)
	(gr_arc
		(start 27.18054 -334.803496)
		(mid 26.67 -334.292956)
		(end 26.15946 -334.803496)
		(stroke
			(width 0.2)
			(type default)
		)
		(layer "In4.Cu")
	)
	(gr_line
		(start 27.18054 -330.816458)
		(end 27.18054 -330.003658)
		(stroke
			(width 0.2)
			(type default)
		)
		(layer "In4.Cu")
	)
	(gr_arc
		(start 27.18054 -330.003658)
		(mid 26.67 -329.493118)
		(end 26.15946 -330.003658)
		(stroke
			(width 0.2)
			(type default)
		)
		(layer "In4.Cu")
	)
	(gr_line
		(start 27.18054 -326.016366)
		(end 27.18054 -325.203566)
		(stroke
			(width 0.2)
			(type default)
		)
		(layer "In4.Cu")
	)
	(gr_arc
		(start 27.18054 -325.203566)
		(mid 26.67 -324.693026)
		(end 26.15946 -325.203566)
		(stroke
			(width 0.2)
			(type default)
		)
		(layer "In4.Cu")
	)
	(gr_line
		(start 27.18054 -245.416324)
		(end 27.18054 -244.603524)
		(stroke
			(width 0.2)
			(type default)
		)
		(layer "In4.Cu")
	)
	(gr_arc
		(start 27.18054 -244.603524)
		(mid 26.67 -244.092984)
		(end 26.15946 -244.603524)
		(stroke
			(width 0.2)
			(type default)
		)
		(layer "In4.Cu")
	)
	(gr_line
		(start 27.18054 -232.616248)
		(end 27.18054 -231.803448)
		(stroke
			(width 0.2)
			(type default)
		)
		(layer "In4.Cu")
	)
	(gr_arc
		(start 27.18054 -231.803448)
		(mid 26.67 -231.292908)
		(end 26.15946 -231.803448)
		(stroke
			(width 0.2)
			(type default)
		)
		(layer "In4.Cu")
	)
	(gr_line
		(start 27.18054 -227.81641)
		(end 27.18054 -227.00361)
		(stroke
			(width 0.2)
			(type default)
		)
		(layer "In4.Cu")
	)
	(gr_arc
		(start 27.18054 -227.00361)
		(mid 26.67 -226.49307)
		(end 26.15946 -227.00361)
		(stroke
			(width 0.2)
			(type default)
		)
		(layer "In4.Cu")
	)
	(gr_line
		(start 27.18054 -223.016318)
		(end 27.18054 -222.203518)
		(stroke
			(width 0.2)
			(type default)
		)
		(layer "In4.Cu")
	)
	(gr_arc
		(start 27.18054 -222.203518)
		(mid 26.67 -221.692978)
		(end 26.15946 -222.203518)
		(stroke
			(width 0.2)
			(type default)
		)
		(layer "In4.Cu")
	)
	(gr_line
		(start 27.18054 -142.416276)
		(end 27.18054 -141.603476)
		(stroke
			(width 0.2)
			(type default)
		)
		(layer "In4.Cu")
	)
	(gr_arc
		(start 27.18054 -141.603476)
		(mid 26.67 -141.092936)
		(end 26.15946 -141.603476)
		(stroke
			(width 0.2)
			(type default)
		)
		(layer "In4.Cu")
	)
	(gr_line
		(start 27.18054 -129.6162)
		(end 27.18054 -128.8034)
		(stroke
			(width 0.2)
			(type default)
		)
		(layer "In4.Cu")
	)
	(gr_arc
		(start 27.18054 -128.8034)
		(mid 26.67 -128.29286)
		(end 26.15946 -128.8034)
		(stroke
			(width 0.2)
			(type default)
		)
		(layer "In4.Cu")
	)
	(gr_line
		(start 27.18054 -124.816362)
		(end 27.18054 -124.003562)
		(stroke
			(width 0.2)
			(type default)
		)
		(layer "In4.Cu")
	)
	(gr_arc
		(start 27.18054 -124.003562)
		(mid 26.67 -123.493022)
		(end 26.15946 -124.003562)
		(stroke
			(width 0.2)
			(type default)
		)
		(layer "In4.Cu")
	)
	(gr_line
		(start 27.18054 -120.01627)
		(end 27.18054 -119.20347)
		(stroke
			(width 0.2)
			(type default)
		)
		(layer "In4.Cu")
	)
	(gr_arc
		(start 27.18054 -119.20347)
		(mid 26.67 -118.69293)
		(end 26.15946 -119.20347)
		(stroke
			(width 0.2)
			(type default)
		)
		(layer "In4.Cu")
	)
	(gr_line
		(start 27.18054 -39.416228)
		(end 27.18054 -38.603428)
		(stroke
			(width 0.2)
			(type default)
		)
		(layer "In4.Cu")
	)
	(gr_arc
		(start 27.18054 -38.603428)
		(mid 26.67 -38.092888)
		(end 26.15946 -38.603428)
		(stroke
			(width 0.2)
			(type default)
		)
		(layer "In4.Cu")
	)
	(gr_line
		(start 27.18054 -26.616152)
		(end 27.18054 -25.803352)
		(stroke
			(width 0.2)
			(type default)
		)
		(layer "In4.Cu")
	)
	(gr_arc
		(start 27.18054 -25.803352)
		(mid 26.67 -25.292812)
		(end 26.15946 -25.803352)
		(stroke
			(width 0.2)
			(type default)
		)
		(layer "In4.Cu")
	)
	(gr_line
		(start 27.18054 -21.816314)
		(end 27.18054 -21.003514)
		(stroke
			(width 0.2)
			(type default)
		)
		(layer "In4.Cu")
	)
	(gr_arc
		(start 27.18054 -21.003514)
		(mid 26.67 -20.492974)
		(end 26.15946 -21.003514)
		(stroke
			(width 0.2)
			(type default)
		)
		(layer "In4.Cu")
	)
	(gr_line
		(start 27.18054 -17.016222)
		(end 27.18054 -16.203422)
		(stroke
			(width 0.2)
			(type default)
		)
		(layer "In4.Cu")
	)
	(gr_arc
		(start 27.18054 -16.203422)
		(mid 26.67 -15.692882)
		(end 26.15946 -16.203422)
		(stroke
			(width 0.2)
			(type default)
		)
		(layer "In4.Cu")
	)
	(gr_line
		(start 30.80004 0)
		(end 32.33674 -3.019552)
		(stroke
			(width 2.54)
			(type default)
		)
		(layer "In4.Cu")
	)
	(gr_arc
		(start 30.98546 -136.416542)
		(mid 31.496 -136.927082)
		(end 32.00654 -136.416542)
		(stroke
			(width 0.2)
			(type default)
		)
		(layer "In4.Cu")
	)
	(gr_line
		(start 30.98546 -135.603742)
		(end 30.98546 -136.416542)
		(stroke
			(width 0.2)
			(type default)
		)
		(layer "In4.Cu")
	)
	(gr_arc
		(start 30.98546 -33.415986)
		(mid 31.496 -33.926526)
		(end 32.00654 -33.415986)
		(stroke
			(width 0.2)
			(type default)
		)
		(layer "In4.Cu")
	)
	(gr_line
		(start 30.98546 -32.603186)
		(end 30.98546 -33.415986)
		(stroke
			(width 0.2)
			(type default)
		)
		(layer "In4.Cu")
	)
	(gr_arc
		(start 31.23946 -445.397636)
		(mid 31.75 -445.908176)
		(end 32.26054 -445.397636)
		(stroke
			(width 0.2)
			(type default)
		)
		(layer "In4.Cu")
	)
	(gr_line
		(start 31.23946 -444.584836)
		(end 31.23946 -445.397636)
		(stroke
			(width 0.2)
			(type default)
		)
		(layer "In4.Cu")
	)
	(gr_line
		(start 32.00654 -136.416542)
		(end 32.00654 -135.603996)
		(stroke
			(width 0.2)
			(type default)
		)
		(layer "In4.Cu")
	)
	(gr_arc
		(start 32.00654 -135.603996)
		(mid 31.496127 -135.093202)
		(end 30.98546 -135.603742)
		(stroke
			(width 0.2)
			(type default)
		)
		(layer "In4.Cu")
	)
	(gr_line
		(start 32.00654 -33.415986)
		(end 32.00654 -32.60344)
		(stroke
			(width 0.2)
			(type default)
		)
		(layer "In4.Cu")
	)
	(gr_arc
		(start 32.00654 -32.60344)
		(mid 31.496127 -32.092646)
		(end 30.98546 -32.603186)
		(stroke
			(width 0.2)
			(type default)
		)
		(layer "In4.Cu")
	)
	(gr_line
		(start 32.26054 -445.397636)
		(end 32.26054 -444.58509)
		(stroke
			(width 0.2)
			(type default)
		)
		(layer "In4.Cu")
	)
	(gr_arc
		(start 32.26054 -444.58509)
		(mid 31.750127 -444.074296)
		(end 31.23946 -444.584836)
		(stroke
			(width 0.2)
			(type default)
		)
		(layer "In4.Cu")
	)
	(gr_arc
		(start 32.38246 -342.397334)
		(mid 32.893 -342.907874)
		(end 33.40354 -342.397334)
		(stroke
			(width 0.2)
			(type default)
		)
		(layer "In4.Cu")
	)
	(gr_line
		(start 32.38246 -341.584534)
		(end 32.38246 -342.397334)
		(stroke
			(width 0.2)
			(type default)
		)
		(layer "In4.Cu")
	)
	(gr_arc
		(start 32.500062 -4.500118)
		(mid 34.000186 -6.000242)
		(end 35.500056 -4.500118)
		(stroke
			(width 2.54)
			(type default)
		)
		(layer "In4.Cu")
	)
	(gr_arc
		(start 32.500062 -3.700018)
		(mid 32.458636 -3.350129)
		(end 32.33674 -3.019552)
		(stroke
			(width 2.54)
			(type default)
		)
		(layer "In4.Cu")
	)
	(gr_line
		(start 32.500062 -3.700018)
		(end 32.500062 -4.500118)
		(stroke
			(width 2.54)
			(type default)
		)
		(layer "In4.Cu")
	)
	(gr_line
		(start 33.40354 -342.397334)
		(end 33.40354 -341.584788)
		(stroke
			(width 0.2)
			(type default)
		)
		(layer "In4.Cu")
	)
	(gr_arc
		(start 33.40354 -341.584788)
		(mid 32.893127 -341.073994)
		(end 32.38246 -341.584534)
		(stroke
			(width 0.2)
			(type default)
		)
		(layer "In4.Cu")
	)
	(gr_arc
		(start 34.81959 -489.796328)
		(mid 35.330003 -490.307122)
		(end 35.84067 -489.796582)
		(stroke
			(width 0.2)
			(type default)
		)
		(layer "In4.Cu")
	)
	(gr_line
		(start 34.81959 -488.983782)
		(end 34.81959 -489.796328)
		(stroke
			(width 0.2)
			(type default)
		)
		(layer "In4.Cu")
	)
	(gr_arc
		(start 34.81959 -484.996236)
		(mid 35.330003 -485.50703)
		(end 35.84067 -484.99649)
		(stroke
			(width 0.2)
			(type default)
		)
		(layer "In4.Cu")
	)
	(gr_line
		(start 34.81959 -484.18369)
		(end 34.81959 -484.996236)
		(stroke
			(width 0.2)
			(type default)
		)
		(layer "In4.Cu")
	)
	(gr_arc
		(start 34.81959 -480.196398)
		(mid 35.330003 -480.707192)
		(end 35.84067 -480.196652)
		(stroke
			(width 0.2)
			(type default)
		)
		(layer "In4.Cu")
	)
	(gr_line
		(start 34.81959 -479.383852)
		(end 34.81959 -480.196398)
		(stroke
			(width 0.2)
			(type default)
		)
		(layer "In4.Cu")
	)
	(gr_arc
		(start 34.81959 -467.396322)
		(mid 35.330003 -467.907116)
		(end 35.84067 -467.396576)
		(stroke
			(width 0.2)
			(type default)
		)
		(layer "In4.Cu")
	)
	(gr_line
		(start 34.81959 -466.583776)
		(end 34.81959 -467.396322)
		(stroke
			(width 0.2)
			(type default)
		)
		(layer "In4.Cu")
	)
	(gr_arc
		(start 34.81959 -386.796534)
		(mid 35.33013 -387.307074)
		(end 35.84067 -386.796534)
		(stroke
			(width 0.2)
			(type default)
		)
		(layer "In4.Cu")
	)
	(gr_line
		(start 34.81959 -385.983734)
		(end 34.81959 -386.796534)
		(stroke
			(width 0.2)
			(type default)
		)
		(layer "In4.Cu")
	)
	(gr_arc
		(start 34.81959 -381.996442)
		(mid 35.33013 -382.506982)
		(end 35.84067 -381.996442)
		(stroke
			(width 0.2)
			(type default)
		)
		(layer "In4.Cu")
	)
	(gr_line
		(start 34.81959 -381.183642)
		(end 34.81959 -381.996442)
		(stroke
			(width 0.2)
			(type default)
		)
		(layer "In4.Cu")
	)
	(gr_arc
		(start 34.81959 -377.196604)
		(mid 35.33013 -377.707144)
		(end 35.84067 -377.196604)
		(stroke
			(width 0.2)
			(type default)
		)
		(layer "In4.Cu")
	)
	(gr_line
		(start 34.81959 -376.383804)
		(end 34.81959 -377.196604)
		(stroke
			(width 0.2)
			(type default)
		)
		(layer "In4.Cu")
	)
	(gr_arc
		(start 34.81959 -364.396528)
		(mid 35.33013 -364.907068)
		(end 35.84067 -364.396528)
		(stroke
			(width 0.2)
			(type default)
		)
		(layer "In4.Cu")
	)
	(gr_line
		(start 34.81959 -363.583728)
		(end 34.81959 -364.396528)
		(stroke
			(width 0.2)
			(type default)
		)
		(layer "In4.Cu")
	)
	(gr_arc
		(start 34.81959 -283.796486)
		(mid 35.33013 -284.307026)
		(end 35.84067 -283.796486)
		(stroke
			(width 0.2)
			(type default)
		)
		(layer "In4.Cu")
	)
	(gr_line
		(start 34.81959 -282.983686)
		(end 34.81959 -283.796486)
		(stroke
			(width 0.2)
			(type default)
		)
		(layer "In4.Cu")
	)
	(gr_arc
		(start 34.81959 -278.996394)
		(mid 35.33013 -279.506934)
		(end 35.84067 -278.996394)
		(stroke
			(width 0.2)
			(type default)
		)
		(layer "In4.Cu")
	)
	(gr_line
		(start 34.81959 -278.183594)
		(end 34.81959 -278.996394)
		(stroke
			(width 0.2)
			(type default)
		)
		(layer "In4.Cu")
	)
	(gr_arc
		(start 34.81959 -274.196556)
		(mid 35.33013 -274.707096)
		(end 35.84067 -274.196556)
		(stroke
			(width 0.2)
			(type default)
		)
		(layer "In4.Cu")
	)
	(gr_line
		(start 34.81959 -273.383756)
		(end 34.81959 -274.196556)
		(stroke
			(width 0.2)
			(type default)
		)
		(layer "In4.Cu")
	)
	(gr_arc
		(start 34.81959 -261.39648)
		(mid 35.33013 -261.90702)
		(end 35.84067 -261.39648)
		(stroke
			(width 0.2)
			(type default)
		)
		(layer "In4.Cu")
	)
	(gr_line
		(start 34.81959 -260.58368)
		(end 34.81959 -261.39648)
		(stroke
			(width 0.2)
			(type default)
		)
		(layer "In4.Cu")
	)
	(gr_arc
		(start 34.81959 -180.796438)
		(mid 35.33013 -181.306978)
		(end 35.84067 -180.796438)
		(stroke
			(width 0.2)
			(type default)
		)
		(layer "In4.Cu")
	)
	(gr_line
		(start 34.81959 -179.983638)
		(end 34.81959 -180.796438)
		(stroke
			(width 0.2)
			(type default)
		)
		(layer "In4.Cu")
	)
	(gr_arc
		(start 34.81959 -175.996346)
		(mid 35.33013 -176.506886)
		(end 35.84067 -175.996346)
		(stroke
			(width 0.2)
			(type default)
		)
		(layer "In4.Cu")
	)
	(gr_line
		(start 34.81959 -175.183546)
		(end 34.81959 -175.996346)
		(stroke
			(width 0.2)
			(type default)
		)
		(layer "In4.Cu")
	)
	(gr_arc
		(start 34.81959 -171.196508)
		(mid 35.33013 -171.707048)
		(end 35.84067 -171.196508)
		(stroke
			(width 0.2)
			(type default)
		)
		(layer "In4.Cu")
	)
	(gr_line
		(start 34.81959 -170.383708)
		(end 34.81959 -171.196508)
		(stroke
			(width 0.2)
			(type default)
		)
		(layer "In4.Cu")
	)
	(gr_arc
		(start 34.81959 -158.396432)
		(mid 35.33013 -158.906972)
		(end 35.84067 -158.396432)
		(stroke
			(width 0.2)
			(type default)
		)
		(layer "In4.Cu")
	)
	(gr_line
		(start 34.81959 -157.583632)
		(end 34.81959 -158.396432)
		(stroke
			(width 0.2)
			(type default)
		)
		(layer "In4.Cu")
	)
	(gr_arc
		(start 34.81959 -77.79639)
		(mid 35.33013 -78.30693)
		(end 35.84067 -77.79639)
		(stroke
			(width 0.2)
			(type default)
		)
		(layer "In4.Cu")
	)
	(gr_line
		(start 34.81959 -76.98359)
		(end 34.81959 -77.79639)
		(stroke
			(width 0.2)
			(type default)
		)
		(layer "In4.Cu")
	)
	(gr_arc
		(start 34.81959 -72.996298)
		(mid 35.33013 -73.506838)
		(end 35.84067 -72.996298)
		(stroke
			(width 0.2)
			(type default)
		)
		(layer "In4.Cu")
	)
	(gr_line
		(start 34.81959 -72.183498)
		(end 34.81959 -72.996298)
		(stroke
			(width 0.2)
			(type default)
		)
		(layer "In4.Cu")
	)
	(gr_arc
		(start 34.81959 -68.19646)
		(mid 35.33013 -68.707)
		(end 35.84067 -68.19646)
		(stroke
			(width 0.2)
			(type default)
		)
		(layer "In4.Cu")
	)
	(gr_line
		(start 34.81959 -67.38366)
		(end 34.81959 -68.19646)
		(stroke
			(width 0.2)
			(type default)
		)
		(layer "In4.Cu")
	)
	(gr_arc
		(start 34.81959 -55.396384)
		(mid 35.33013 -55.906924)
		(end 35.84067 -55.396384)
		(stroke
			(width 0.2)
			(type default)
		)
		(layer "In4.Cu")
	)
	(gr_line
		(start 34.81959 -54.583584)
		(end 34.81959 -55.396384)
		(stroke
			(width 0.2)
			(type default)
		)
		(layer "In4.Cu")
	)
	(gr_line
		(start 35.500056 -4.500118)
		(end 35.500056 -3.700018)
		(stroke
			(width 2.54)
			(type default)
		)
		(layer "In4.Cu")
	)
	(gr_arc
		(start 35.663124 -3.019552)
		(mid 35.541364 -3.350145)
		(end 35.500056 -3.700018)
		(stroke
			(width 2.54)
			(type default)
		)
		(layer "In4.Cu")
	)
	(gr_line
		(start 35.663124 -3.019552)
		(end 37.200078 0)
		(stroke
			(width 2.54)
			(type default)
		)
		(layer "In4.Cu")
	)
	(gr_line
		(start 35.84067 -489.796582)
		(end 35.84067 -488.983782)
		(stroke
			(width 0.2)
			(type default)
		)
		(layer "In4.Cu")
	)
	(gr_arc
		(start 35.84067 -488.983782)
		(mid 35.33013 -488.473242)
		(end 34.81959 -488.983782)
		(stroke
			(width 0.2)
			(type default)
		)
		(layer "In4.Cu")
	)
	(gr_line
		(start 35.84067 -484.99649)
		(end 35.84067 -484.18369)
		(stroke
			(width 0.2)
			(type default)
		)
		(layer "In4.Cu")
	)
	(gr_arc
		(start 35.84067 -484.18369)
		(mid 35.33013 -483.67315)
		(end 34.81959 -484.18369)
		(stroke
			(width 0.2)
			(type default)
		)
		(layer "In4.Cu")
	)
	(gr_line
		(start 35.84067 -480.196652)
		(end 35.84067 -479.383852)
		(stroke
			(width 0.2)
			(type default)
		)
		(layer "In4.Cu")
	)
	(gr_arc
		(start 35.84067 -479.383852)
		(mid 35.33013 -478.873312)
		(end 34.81959 -479.383852)
		(stroke
			(width 0.2)
			(type default)
		)
		(layer "In4.Cu")
	)
	(gr_line
		(start 35.84067 -467.396576)
		(end 35.84067 -466.583776)
		(stroke
			(width 0.2)
			(type default)
		)
		(layer "In4.Cu")
	)
	(gr_arc
		(start 35.84067 -466.583776)
		(mid 35.33013 -466.073236)
		(end 34.81959 -466.583776)
		(stroke
			(width 0.2)
			(type default)
		)
		(layer "In4.Cu")
	)
	(gr_line
		(start 35.84067 -386.796534)
		(end 35.84067 -385.983988)
		(stroke
			(width 0.2)
			(type default)
		)
		(layer "In4.Cu")
	)
	(gr_arc
		(start 35.84067 -385.983988)
		(mid 35.330257 -385.473194)
		(end 34.81959 -385.983734)
		(stroke
			(width 0.2)
			(type default)
		)
		(layer "In4.Cu")
	)
	(gr_line
		(start 35.84067 -381.996442)
		(end 35.84067 -381.183896)
		(stroke
			(width 0.2)
			(type default)
		)
		(layer "In4.Cu")
	)
	(gr_arc
		(start 35.84067 -381.183896)
		(mid 35.330257 -380.673102)
		(end 34.81959 -381.183642)
		(stroke
			(width 0.2)
			(type default)
		)
		(layer "In4.Cu")
	)
	(gr_line
		(start 35.84067 -377.196604)
		(end 35.84067 -376.384058)
		(stroke
			(width 0.2)
			(type default)
		)
		(layer "In4.Cu")
	)
	(gr_arc
		(start 35.84067 -376.384058)
		(mid 35.330257 -375.873264)
		(end 34.81959 -376.383804)
		(stroke
			(width 0.2)
			(type default)
		)
		(layer "In4.Cu")
	)
	(gr_line
		(start 35.84067 -364.396528)
		(end 35.84067 -363.583982)
		(stroke
			(width 0.2)
			(type default)
		)
		(layer "In4.Cu")
	)
	(gr_arc
		(start 35.84067 -363.583982)
		(mid 35.330257 -363.073188)
		(end 34.81959 -363.583728)
		(stroke
			(width 0.2)
			(type default)
		)
		(layer "In4.Cu")
	)
	(gr_line
		(start 35.84067 -283.796486)
		(end 35.84067 -282.98394)
		(stroke
			(width 0.2)
			(type default)
		)
		(layer "In4.Cu")
	)
	(gr_arc
		(start 35.84067 -282.98394)
		(mid 35.330257 -282.473146)
		(end 34.81959 -282.983686)
		(stroke
			(width 0.2)
			(type default)
		)
		(layer "In4.Cu")
	)
	(gr_line
		(start 35.84067 -278.996394)
		(end 35.84067 -278.183848)
		(stroke
			(width 0.2)
			(type default)
		)
		(layer "In4.Cu")
	)
	(gr_arc
		(start 35.84067 -278.183848)
		(mid 35.330257 -277.673054)
		(end 34.81959 -278.183594)
		(stroke
			(width 0.2)
			(type default)
		)
		(layer "In4.Cu")
	)
	(gr_line
		(start 35.84067 -274.196556)
		(end 35.84067 -273.38401)
		(stroke
			(width 0.2)
			(type default)
		)
		(layer "In4.Cu")
	)
	(gr_arc
		(start 35.84067 -273.38401)
		(mid 35.330257 -272.873216)
		(end 34.81959 -273.383756)
		(stroke
			(width 0.2)
			(type default)
		)
		(layer "In4.Cu")
	)
	(gr_line
		(start 35.84067 -261.39648)
		(end 35.84067 -260.583934)
		(stroke
			(width 0.2)
			(type default)
		)
		(layer "In4.Cu")
	)
	(gr_arc
		(start 35.84067 -260.583934)
		(mid 35.330257 -260.07314)
		(end 34.81959 -260.58368)
		(stroke
			(width 0.2)
			(type default)
		)
		(layer "In4.Cu")
	)
	(gr_line
		(start 35.84067 -180.796438)
		(end 35.84067 -179.983892)
		(stroke
			(width 0.2)
			(type default)
		)
		(layer "In4.Cu")
	)
	(gr_arc
		(start 35.84067 -179.983892)
		(mid 35.330257 -179.473098)
		(end 34.81959 -179.983638)
		(stroke
			(width 0.2)
			(type default)
		)
		(layer "In4.Cu")
	)
	(gr_line
		(start 35.84067 -175.996346)
		(end 35.84067 -175.1838)
		(stroke
			(width 0.2)
			(type default)
		)
		(layer "In4.Cu")
	)
	(gr_arc
		(start 35.84067 -175.1838)
		(mid 35.330257 -174.673006)
		(end 34.81959 -175.183546)
		(stroke
			(width 0.2)
			(type default)
		)
		(layer "In4.Cu")
	)
	(gr_line
		(start 35.84067 -171.196508)
		(end 35.84067 -170.383962)
		(stroke
			(width 0.2)
			(type default)
		)
		(layer "In4.Cu")
	)
	(gr_arc
		(start 35.84067 -170.383962)
		(mid 35.330257 -169.873168)
		(end 34.81959 -170.383708)
		(stroke
			(width 0.2)
			(type default)
		)
		(layer "In4.Cu")
	)
	(gr_line
		(start 35.84067 -158.396432)
		(end 35.84067 -157.583886)
		(stroke
			(width 0.2)
			(type default)
		)
		(layer "In4.Cu")
	)
	(gr_arc
		(start 35.84067 -157.583886)
		(mid 35.330257 -157.073092)
		(end 34.81959 -157.583632)
		(stroke
			(width 0.2)
			(type default)
		)
		(layer "In4.Cu")
	)
	(gr_line
		(start 35.84067 -77.79639)
		(end 35.84067 -76.983844)
		(stroke
			(width 0.2)
			(type default)
		)
		(layer "In4.Cu")
	)
	(gr_arc
		(start 35.84067 -76.983844)
		(mid 35.330257 -76.47305)
		(end 34.81959 -76.98359)
		(stroke
			(width 0.2)
			(type default)
		)
		(layer "In4.Cu")
	)
	(gr_line
		(start 35.84067 -72.996298)
		(end 35.84067 -72.183752)
		(stroke
			(width 0.2)
			(type default)
		)
		(layer "In4.Cu")
	)
	(gr_arc
		(start 35.84067 -72.183752)
		(mid 35.330257 -71.672958)
		(end 34.81959 -72.183498)
		(stroke
			(width 0.2)
			(type default)
		)
		(layer "In4.Cu")
	)
	(gr_line
		(start 35.84067 -68.19646)
		(end 35.84067 -67.383914)
		(stroke
			(width 0.2)
			(type default)
		)
		(layer "In4.Cu")
	)
	(gr_arc
		(start 35.84067 -67.383914)
		(mid 35.330257 -66.87312)
		(end 34.81959 -67.38366)
		(stroke
			(width 0.2)
			(type default)
		)
		(layer "In4.Cu")
	)
	(gr_line
		(start 35.84067 -55.396384)
		(end 35.84067 -54.583838)
		(stroke
			(width 0.2)
			(type default)
		)
		(layer "In4.Cu")
	)
	(gr_arc
		(start 35.84067 -54.583838)
		(mid 35.330257 -54.073044)
		(end 34.81959 -54.583584)
		(stroke
			(width 0.2)
			(type default)
		)
		(layer "In4.Cu")
	)
	(gr_arc
		(start 36.11499 -492.348774)
		(mid 36.727003 -492.961168)
		(end 37.33927 -492.349028)
		(stroke
			(width 0.2)
			(type default)
		)
		(layer "In4.Cu")
	)
	(gr_line
		(start 36.11499 -491.231428)
		(end 36.11499 -492.348774)
		(stroke
			(width 0.2)
			(type default)
		)
		(layer "In4.Cu")
	)
	(gr_arc
		(start 36.11499 -487.548936)
		(mid 36.72713 -488.161076)
		(end 37.33927 -487.548936)
		(stroke
			(width 0.2)
			(type default)
		)
		(layer "In4.Cu")
	)
	(gr_line
		(start 36.11499 -486.431336)
		(end 36.11499 -487.548936)
		(stroke
			(width 0.2)
			(type default)
		)
		(layer "In4.Cu")
	)
	(gr_arc
		(start 36.11499 -482.74859)
		(mid 36.727003 -483.360984)
		(end 37.33927 -482.748844)
		(stroke
			(width 0.2)
			(type default)
		)
		(layer "In4.Cu")
	)
	(gr_line
		(start 36.11499 -481.631244)
		(end 36.11499 -482.74859)
		(stroke
			(width 0.2)
			(type default)
		)
		(layer "In4.Cu")
	)
	(gr_arc
		(start 36.11499 -469.948768)
		(mid 36.727003 -470.561162)
		(end 37.33927 -469.949022)
		(stroke
			(width 0.2)
			(type default)
		)
		(layer "In4.Cu")
	)
	(gr_line
		(start 36.11499 -468.831422)
		(end 36.11499 -469.948768)
		(stroke
			(width 0.2)
			(type default)
		)
		(layer "In4.Cu")
	)
	(gr_arc
		(start 36.11499 -389.34898)
		(mid 36.72713 -389.96112)
		(end 37.33927 -389.34898)
		(stroke
			(width 0.2)
			(type default)
		)
		(layer "In4.Cu")
	)
	(gr_line
		(start 36.11499 -388.23138)
		(end 36.11499 -389.34898)
		(stroke
			(width 0.2)
			(type default)
		)
		(layer "In4.Cu")
	)
	(gr_arc
		(start 36.11499 -384.548888)
		(mid 36.72713 -385.161028)
		(end 37.33927 -384.548888)
		(stroke
			(width 0.2)
			(type default)
		)
		(layer "In4.Cu")
	)
	(gr_line
		(start 36.11499 -383.431288)
		(end 36.11499 -384.548888)
		(stroke
			(width 0.2)
			(type default)
		)
		(layer "In4.Cu")
	)
	(gr_arc
		(start 36.11499 -379.748796)
		(mid 36.72713 -380.360936)
		(end 37.33927 -379.748796)
		(stroke
			(width 0.2)
			(type default)
		)
		(layer "In4.Cu")
	)
	(gr_line
		(start 36.11499 -378.631196)
		(end 36.11499 -379.748796)
		(stroke
			(width 0.2)
			(type default)
		)
		(layer "In4.Cu")
	)
	(gr_arc
		(start 36.11499 -366.948974)
		(mid 36.72713 -367.561114)
		(end 37.33927 -366.948974)
		(stroke
			(width 0.2)
			(type default)
		)
		(layer "In4.Cu")
	)
	(gr_line
		(start 36.11499 -365.831374)
		(end 36.11499 -366.948974)
		(stroke
			(width 0.2)
			(type default)
		)
		(layer "In4.Cu")
	)
	(gr_arc
		(start 36.11499 -286.348932)
		(mid 36.72713 -286.961072)
		(end 37.33927 -286.348932)
		(stroke
			(width 0.2)
			(type default)
		)
		(layer "In4.Cu")
	)
	(gr_line
		(start 36.11499 -285.231332)
		(end 36.11499 -286.348932)
		(stroke
			(width 0.2)
			(type default)
		)
		(layer "In4.Cu")
	)
	(gr_arc
		(start 36.11499 -281.54884)
		(mid 36.72713 -282.16098)
		(end 37.33927 -281.54884)
		(stroke
			(width 0.2)
			(type default)
		)
		(layer "In4.Cu")
	)
	(gr_line
		(start 36.11499 -280.43124)
		(end 36.11499 -281.54884)
		(stroke
			(width 0.2)
			(type default)
		)
		(layer "In4.Cu")
	)
	(gr_arc
		(start 36.11499 -276.748748)
		(mid 36.72713 -277.360888)
		(end 37.33927 -276.748748)
		(stroke
			(width 0.2)
			(type default)
		)
		(layer "In4.Cu")
	)
	(gr_line
		(start 36.11499 -275.631148)
		(end 36.11499 -276.748748)
		(stroke
			(width 0.2)
			(type default)
		)
		(layer "In4.Cu")
	)
	(gr_arc
		(start 36.11499 -263.948926)
		(mid 36.72713 -264.561066)
		(end 37.33927 -263.948926)
		(stroke
			(width 0.2)
			(type default)
		)
		(layer "In4.Cu")
	)
	(gr_line
		(start 36.11499 -262.831326)
		(end 36.11499 -263.948926)
		(stroke
			(width 0.2)
			(type default)
		)
		(layer "In4.Cu")
	)
	(gr_arc
		(start 36.11499 -183.348884)
		(mid 36.72713 -183.961024)
		(end 37.33927 -183.348884)
		(stroke
			(width 0.2)
			(type default)
		)
		(layer "In4.Cu")
	)
	(gr_line
		(start 36.11499 -182.231284)
		(end 36.11499 -183.348884)
		(stroke
			(width 0.2)
			(type default)
		)
		(layer "In4.Cu")
	)
	(gr_arc
		(start 36.11499 -178.548792)
		(mid 36.72713 -179.160932)
		(end 37.33927 -178.548792)
		(stroke
			(width 0.2)
			(type default)
		)
		(layer "In4.Cu")
	)
	(gr_line
		(start 36.11499 -177.431192)
		(end 36.11499 -178.548792)
		(stroke
			(width 0.2)
			(type default)
		)
		(layer "In4.Cu")
	)
	(gr_arc
		(start 36.11499 -173.7487)
		(mid 36.72713 -174.36084)
		(end 37.33927 -173.7487)
		(stroke
			(width 0.2)
			(type default)
		)
		(layer "In4.Cu")
	)
	(gr_line
		(start 36.11499 -172.6311)
		(end 36.11499 -173.7487)
		(stroke
			(width 0.2)
			(type default)
		)
		(layer "In4.Cu")
	)
	(gr_arc
		(start 36.11499 -160.948878)
		(mid 36.72713 -161.561018)
		(end 37.33927 -160.948878)
		(stroke
			(width 0.2)
			(type default)
		)
		(layer "In4.Cu")
	)
	(gr_line
		(start 36.11499 -159.831278)
		(end 36.11499 -160.948878)
		(stroke
			(width 0.2)
			(type default)
		)
		(layer "In4.Cu")
	)
	(gr_arc
		(start 36.11499 -80.348836)
		(mid 36.72713 -80.960976)
		(end 37.33927 -80.348836)
		(stroke
			(width 0.2)
			(type default)
		)
		(layer "In4.Cu")
	)
	(gr_line
		(start 36.11499 -79.231236)
		(end 36.11499 -80.348836)
		(stroke
			(width 0.2)
			(type default)
		)
		(layer "In4.Cu")
	)
	(gr_arc
		(start 36.11499 -75.548744)
		(mid 36.72713 -76.160884)
		(end 37.33927 -75.548744)
		(stroke
			(width 0.2)
			(type default)
		)
		(layer "In4.Cu")
	)
	(gr_line
		(start 36.11499 -74.431144)
		(end 36.11499 -75.548744)
		(stroke
			(width 0.2)
			(type default)
		)
		(layer "In4.Cu")
	)
	(gr_arc
		(start 36.11499 -70.748652)
		(mid 36.72713 -71.360792)
		(end 37.33927 -70.748652)
		(stroke
			(width 0.2)
			(type default)
		)
		(layer "In4.Cu")
	)
	(gr_line
		(start 36.11499 -69.631052)
		(end 36.11499 -70.748652)
		(stroke
			(width 0.2)
			(type default)
		)
		(layer "In4.Cu")
	)
	(gr_arc
		(start 36.11499 -57.94883)
		(mid 36.72713 -58.56097)
		(end 37.33927 -57.94883)
		(stroke
			(width 0.2)
			(type default)
		)
		(layer "In4.Cu")
	)
	(gr_line
		(start 36.11499 -56.83123)
		(end 36.11499 -57.94883)
		(stroke
			(width 0.2)
			(type default)
		)
		(layer "In4.Cu")
	)
	(gr_line
		(start 37.200078 0)
		(end 262.50011 0)
		(stroke
			(width 2.54)
			(type default)
		)
		(layer "In4.Cu")
	)
	(gr_line
		(start 37.33927 -492.349028)
		(end 37.33927 -491.231428)
		(stroke
			(width 0.2)
			(type default)
		)
		(layer "In4.Cu")
	)
	(gr_arc
		(start 37.33927 -491.231428)
		(mid 36.72713 -490.619288)
		(end 36.11499 -491.231428)
		(stroke
			(width 0.2)
			(type default)
		)
		(layer "In4.Cu")
	)
	(gr_line
		(start 37.33927 -487.548936)
		(end 37.33927 -486.43159)
		(stroke
			(width 0.2)
			(type default)
		)
		(layer "In4.Cu")
	)
	(gr_arc
		(start 37.33927 -486.43159)
		(mid 36.727257 -485.819196)
		(end 36.11499 -486.431336)
		(stroke
			(width 0.2)
			(type default)
		)
		(layer "In4.Cu")
	)
	(gr_line
		(start 37.33927 -482.748844)
		(end 37.33927 -481.631244)
		(stroke
			(width 0.2)
			(type default)
		)
		(layer "In4.Cu")
	)
	(gr_arc
		(start 37.33927 -481.631244)
		(mid 36.72713 -481.019104)
		(end 36.11499 -481.631244)
		(stroke
			(width 0.2)
			(type default)
		)
		(layer "In4.Cu")
	)
	(gr_line
		(start 37.33927 -469.949022)
		(end 37.33927 -468.831422)
		(stroke
			(width 0.2)
			(type default)
		)
		(layer "In4.Cu")
	)
	(gr_arc
		(start 37.33927 -468.831422)
		(mid 36.72713 -468.219282)
		(end 36.11499 -468.831422)
		(stroke
			(width 0.2)
			(type default)
		)
		(layer "In4.Cu")
	)
	(gr_line
		(start 37.33927 -389.34898)
		(end 37.33927 -388.231634)
		(stroke
			(width 0.2)
			(type default)
		)
		(layer "In4.Cu")
	)
	(gr_arc
		(start 37.33927 -388.231634)
		(mid 36.727257 -387.61924)
		(end 36.11499 -388.23138)
		(stroke
			(width 0.2)
			(type default)
		)
		(layer "In4.Cu")
	)
	(gr_line
		(start 37.33927 -384.548888)
		(end 37.33927 -383.431542)
		(stroke
			(width 0.2)
			(type default)
		)
		(layer "In4.Cu")
	)
	(gr_arc
		(start 37.33927 -383.431542)
		(mid 36.727257 -382.819148)
		(end 36.11499 -383.431288)
		(stroke
			(width 0.2)
			(type default)
		)
		(layer "In4.Cu")
	)
	(gr_line
		(start 37.33927 -379.748796)
		(end 37.33927 -378.63145)
		(stroke
			(width 0.2)
			(type default)
		)
		(layer "In4.Cu")
	)
	(gr_arc
		(start 37.33927 -378.63145)
		(mid 36.727257 -378.019056)
		(end 36.11499 -378.631196)
		(stroke
			(width 0.2)
			(type default)
		)
		(layer "In4.Cu")
	)
	(gr_line
		(start 37.33927 -366.948974)
		(end 37.33927 -365.831628)
		(stroke
			(width 0.2)
			(type default)
		)
		(layer "In4.Cu")
	)
	(gr_arc
		(start 37.33927 -365.831628)
		(mid 36.727257 -365.219234)
		(end 36.11499 -365.831374)
		(stroke
			(width 0.2)
			(type default)
		)
		(layer "In4.Cu")
	)
	(gr_line
		(start 37.33927 -286.348932)
		(end 37.33927 -285.231586)
		(stroke
			(width 0.2)
			(type default)
		)
		(layer "In4.Cu")
	)
	(gr_arc
		(start 37.33927 -285.231586)
		(mid 36.727257 -284.619192)
		(end 36.11499 -285.231332)
		(stroke
			(width 0.2)
			(type default)
		)
		(layer "In4.Cu")
	)
	(gr_line
		(start 37.33927 -281.54884)
		(end 37.33927 -280.431494)
		(stroke
			(width 0.2)
			(type default)
		)
		(layer "In4.Cu")
	)
	(gr_arc
		(start 37.33927 -280.431494)
		(mid 36.727257 -279.8191)
		(end 36.11499 -280.43124)
		(stroke
			(width 0.2)
			(type default)
		)
		(layer "In4.Cu")
	)
	(gr_line
		(start 37.33927 -276.748748)
		(end 37.33927 -275.631402)
		(stroke
			(width 0.2)
			(type default)
		)
		(layer "In4.Cu")
	)
	(gr_arc
		(start 37.33927 -275.631402)
		(mid 36.727257 -275.019008)
		(end 36.11499 -275.631148)
		(stroke
			(width 0.2)
			(type default)
		)
		(layer "In4.Cu")
	)
	(gr_line
		(start 37.33927 -263.948926)
		(end 37.33927 -262.83158)
		(stroke
			(width 0.2)
			(type default)
		)
		(layer "In4.Cu")
	)
	(gr_arc
		(start 37.33927 -262.83158)
		(mid 36.727257 -262.219186)
		(end 36.11499 -262.831326)
		(stroke
			(width 0.2)
			(type default)
		)
		(layer "In4.Cu")
	)
	(gr_line
		(start 37.33927 -183.348884)
		(end 37.33927 -182.231538)
		(stroke
			(width 0.2)
			(type default)
		)
		(layer "In4.Cu")
	)
	(gr_arc
		(start 37.33927 -182.231538)
		(mid 36.727257 -181.619144)
		(end 36.11499 -182.231284)
		(stroke
			(width 0.2)
			(type default)
		)
		(layer "In4.Cu")
	)
	(gr_line
		(start 37.33927 -178.548792)
		(end 37.33927 -177.431446)
		(stroke
			(width 0.2)
			(type default)
		)
		(layer "In4.Cu")
	)
	(gr_arc
		(start 37.33927 -177.431446)
		(mid 36.727257 -176.819052)
		(end 36.11499 -177.431192)
		(stroke
			(width 0.2)
			(type default)
		)
		(layer "In4.Cu")
	)
	(gr_line
		(start 37.33927 -173.7487)
		(end 37.33927 -172.631354)
		(stroke
			(width 0.2)
			(type default)
		)
		(layer "In4.Cu")
	)
	(gr_arc
		(start 37.33927 -172.631354)
		(mid 36.727257 -172.01896)
		(end 36.11499 -172.6311)
		(stroke
			(width 0.2)
			(type default)
		)
		(layer "In4.Cu")
	)
	(gr_line
		(start 37.33927 -160.948878)
		(end 37.33927 -159.831532)
		(stroke
			(width 0.2)
			(type default)
		)
		(layer "In4.Cu")
	)
	(gr_arc
		(start 37.33927 -159.831532)
		(mid 36.727257 -159.219138)
		(end 36.11499 -159.831278)
		(stroke
			(width 0.2)
			(type default)
		)
		(layer "In4.Cu")
	)
	(gr_line
		(start 37.33927 -80.348836)
		(end 37.33927 -79.23149)
		(stroke
			(width 0.2)
			(type default)
		)
		(layer "In4.Cu")
	)
	(gr_arc
		(start 37.33927 -79.23149)
		(mid 36.727257 -78.619096)
		(end 36.11499 -79.231236)
		(stroke
			(width 0.2)
			(type default)
		)
		(layer "In4.Cu")
	)
	(gr_line
		(start 37.33927 -75.548744)
		(end 37.33927 -74.431398)
		(stroke
			(width 0.2)
			(type default)
		)
		(layer "In4.Cu")
	)
	(gr_arc
		(start 37.33927 -74.431398)
		(mid 36.727257 -73.819004)
		(end 36.11499 -74.431144)
		(stroke
			(width 0.2)
			(type default)
		)
		(layer "In4.Cu")
	)
	(gr_line
		(start 37.33927 -70.748652)
		(end 37.33927 -69.631306)
		(stroke
			(width 0.2)
			(type default)
		)
		(layer "In4.Cu")
	)
	(gr_arc
		(start 37.33927 -69.631306)
		(mid 36.727257 -69.018912)
		(end 36.11499 -69.631052)
		(stroke
			(width 0.2)
			(type default)
		)
		(layer "In4.Cu")
	)
	(gr_line
		(start 37.33927 -57.94883)
		(end 37.33927 -56.831484)
		(stroke
			(width 0.2)
			(type default)
		)
		(layer "In4.Cu")
	)
	(gr_arc
		(start 37.33927 -56.831484)
		(mid 36.727257 -56.21909)
		(end 36.11499 -56.83123)
		(stroke
			(width 0.2)
			(type default)
		)
		(layer "In4.Cu")
	)
	(gr_arc
		(start 41.90746 -239.397286)
		(mid 42.418 -239.907826)
		(end 42.92854 -239.397286)
		(stroke
			(width 0.2)
			(type default)
		)
		(layer "In4.Cu")
	)
	(gr_line
		(start 41.90746 -238.584486)
		(end 41.90746 -239.397286)
		(stroke
			(width 0.2)
			(type default)
		)
		(layer "In4.Cu")
	)
	(gr_line
		(start 42.92854 -239.397286)
		(end 42.92854 -238.58474)
		(stroke
			(width 0.2)
			(type default)
		)
		(layer "In4.Cu")
	)
	(gr_arc
		(start 42.92854 -238.58474)
		(mid 42.418127 -238.073946)
		(end 41.90746 -238.584486)
		(stroke
			(width 0.2)
			(type default)
		)
		(layer "In4.Cu")
	)
	(gr_line
		(start 44.9072 -472.300808)
		(end 45.719746 -472.300808)
		(stroke
			(width 0.2)
			(type default)
		)
		(layer "In4.Cu")
	)
	(gr_arc
		(start 44.9072 -471.279728)
		(mid 44.39666 -471.790268)
		(end 44.9072 -472.300808)
		(stroke
			(width 0.2)
			(type default)
		)
		(layer "In4.Cu")
	)
	(gr_line
		(start 44.9072 -369.30076)
		(end 45.72 -369.30076)
		(stroke
			(width 0.2)
			(type default)
		)
		(layer "In4.Cu")
	)
	(gr_line
		(start 44.9072 -266.300712)
		(end 45.72 -266.300712)
		(stroke
			(width 0.2)
			(type default)
		)
		(layer "In4.Cu")
	)
	(gr_line
		(start 44.9072 -163.300664)
		(end 45.72 -163.300664)
		(stroke
			(width 0.2)
			(type default)
		)
		(layer "In4.Cu")
	)
	(gr_line
		(start 44.9072 -60.300616)
		(end 45.72 -60.300616)
		(stroke
			(width 0.2)
			(type default)
		)
		(layer "In4.Cu")
	)
	(gr_arc
		(start 44.907454 -368.27968)
		(mid 44.39666 -368.790093)
		(end 44.9072 -369.30076)
		(stroke
			(width 0.2)
			(type default)
		)
		(layer "In4.Cu")
	)
	(gr_arc
		(start 44.907454 -265.279632)
		(mid 44.39666 -265.790045)
		(end 44.9072 -266.300712)
		(stroke
			(width 0.2)
			(type default)
		)
		(layer "In4.Cu")
	)
	(gr_arc
		(start 44.907454 -162.279584)
		(mid 44.39666 -162.789997)
		(end 44.9072 -163.300664)
		(stroke
			(width 0.2)
			(type default)
		)
		(layer "In4.Cu")
	)
	(gr_arc
		(start 44.907454 -59.279536)
		(mid 44.39666 -59.789949)
		(end 44.9072 -60.300616)
		(stroke
			(width 0.2)
			(type default)
		)
		(layer "In4.Cu")
	)
	(gr_arc
		(start 45.719746 -472.300808)
		(mid 46.23054 -471.790395)
		(end 45.72 -471.279728)
		(stroke
			(width 0.2)
			(type default)
		)
		(layer "In4.Cu")
	)
	(gr_line
		(start 45.72 -471.279728)
		(end 44.9072 -471.279728)
		(stroke
			(width 0.2)
			(type default)
		)
		(layer "In4.Cu")
	)
	(gr_arc
		(start 45.72 -369.30076)
		(mid 46.23054 -368.79022)
		(end 45.72 -368.27968)
		(stroke
			(width 0.2)
			(type default)
		)
		(layer "In4.Cu")
	)
	(gr_line
		(start 45.72 -368.27968)
		(end 44.907454 -368.27968)
		(stroke
			(width 0.2)
			(type default)
		)
		(layer "In4.Cu")
	)
	(gr_arc
		(start 45.72 -266.300712)
		(mid 46.23054 -265.790172)
		(end 45.72 -265.279632)
		(stroke
			(width 0.2)
			(type default)
		)
		(layer "In4.Cu")
	)
	(gr_line
		(start 45.72 -265.279632)
		(end 44.907454 -265.279632)
		(stroke
			(width 0.2)
			(type default)
		)
		(layer "In4.Cu")
	)
	(gr_arc
		(start 45.72 -163.300664)
		(mid 46.23054 -162.790124)
		(end 45.72 -162.279584)
		(stroke
			(width 0.2)
			(type default)
		)
		(layer "In4.Cu")
	)
	(gr_line
		(start 45.72 -162.279584)
		(end 44.907454 -162.279584)
		(stroke
			(width 0.2)
			(type default)
		)
		(layer "In4.Cu")
	)
	(gr_arc
		(start 45.72 -60.300616)
		(mid 46.23054 -59.790076)
		(end 45.72 -59.279536)
		(stroke
			(width 0.2)
			(type default)
		)
		(layer "In4.Cu")
	)
	(gr_line
		(start 45.72 -59.279536)
		(end 44.907454 -59.279536)
		(stroke
			(width 0.2)
			(type default)
		)
		(layer "In4.Cu")
	)
	(gr_arc
		(start 47.87646 -473.392246)
		(mid 48.387 -473.902786)
		(end 48.89754 -473.392246)
		(stroke
			(width 0.2)
			(type default)
		)
		(layer "In4.Cu")
	)
	(gr_line
		(start 47.87646 -472.579446)
		(end 47.87646 -473.392246)
		(stroke
			(width 0.2)
			(type default)
		)
		(layer "In4.Cu")
	)
	(gr_arc
		(start 47.87646 -370.392198)
		(mid 48.387 -370.902738)
		(end 48.89754 -370.392198)
		(stroke
			(width 0.2)
			(type default)
		)
		(layer "In4.Cu")
	)
	(gr_line
		(start 47.87646 -369.579398)
		(end 47.87646 -370.392198)
		(stroke
			(width 0.2)
			(type default)
		)
		(layer "In4.Cu")
	)
	(gr_arc
		(start 47.87646 -267.39215)
		(mid 48.387 -267.90269)
		(end 48.89754 -267.39215)
		(stroke
			(width 0.2)
			(type default)
		)
		(layer "In4.Cu")
	)
	(gr_line
		(start 47.87646 -266.57935)
		(end 47.87646 -267.39215)
		(stroke
			(width 0.2)
			(type default)
		)
		(layer "In4.Cu")
	)
	(gr_arc
		(start 47.87646 -164.392102)
		(mid 48.387 -164.902642)
		(end 48.89754 -164.392102)
		(stroke
			(width 0.2)
			(type default)
		)
		(layer "In4.Cu")
	)
	(gr_line
		(start 47.87646 -163.579302)
		(end 47.87646 -164.392102)
		(stroke
			(width 0.2)
			(type default)
		)
		(layer "In4.Cu")
	)
	(gr_arc
		(start 47.87646 -61.392054)
		(mid 48.387 -61.902594)
		(end 48.89754 -61.392054)
		(stroke
			(width 0.2)
			(type default)
		)
		(layer "In4.Cu")
	)
	(gr_line
		(start 47.87646 -60.579254)
		(end 47.87646 -61.392054)
		(stroke
			(width 0.2)
			(type default)
		)
		(layer "In4.Cu")
	)
	(gr_line
		(start 48.89754 -473.392246)
		(end 48.89754 -472.5797)
		(stroke
			(width 0.2)
			(type default)
		)
		(layer "In4.Cu")
	)
	(gr_arc
		(start 48.89754 -472.5797)
		(mid 48.387127 -472.068906)
		(end 47.87646 -472.579446)
		(stroke
			(width 0.2)
			(type default)
		)
		(layer "In4.Cu")
	)
	(gr_line
		(start 48.89754 -370.392198)
		(end 48.89754 -369.579652)
		(stroke
			(width 0.2)
			(type default)
		)
		(layer "In4.Cu")
	)
	(gr_arc
		(start 48.89754 -369.579652)
		(mid 48.387127 -369.068858)
		(end 47.87646 -369.579398)
		(stroke
			(width 0.2)
			(type default)
		)
		(layer "In4.Cu")
	)
	(gr_line
		(start 48.89754 -267.39215)
		(end 48.89754 -266.579604)
		(stroke
			(width 0.2)
			(type default)
		)
		(layer "In4.Cu")
	)
	(gr_arc
		(start 48.89754 -266.579604)
		(mid 48.387127 -266.06881)
		(end 47.87646 -266.57935)
		(stroke
			(width 0.2)
			(type default)
		)
		(layer "In4.Cu")
	)
	(gr_line
		(start 48.89754 -164.392102)
		(end 48.89754 -163.579556)
		(stroke
			(width 0.2)
			(type default)
		)
		(layer "In4.Cu")
	)
	(gr_arc
		(start 48.89754 -163.579556)
		(mid 48.387127 -163.068762)
		(end 47.87646 -163.579302)
		(stroke
			(width 0.2)
			(type default)
		)
		(layer "In4.Cu")
	)
	(gr_line
		(start 48.89754 -61.392054)
		(end 48.89754 -60.579508)
		(stroke
			(width 0.2)
			(type default)
		)
		(layer "In4.Cu")
	)
	(gr_arc
		(start 48.89754 -60.579508)
		(mid 48.387127 -60.068714)
		(end 47.87646 -60.579254)
		(stroke
			(width 0.2)
			(type default)
		)
		(layer "In4.Cu")
	)
	(gr_arc
		(start 71.87946 -431.9524)
		(mid 72.39 -432.46294)
		(end 72.90054 -431.9524)
		(stroke
			(width 0.2)
			(type default)
		)
		(layer "In4.Cu")
	)
	(gr_line
		(start 71.87946 -431.1396)
		(end 71.87946 -431.9524)
		(stroke
			(width 0.2)
			(type default)
		)
		(layer "In4.Cu")
	)
	(gr_line
		(start 72.90054 -431.9524)
		(end 72.90054 -431.139854)
		(stroke
			(width 0.2)
			(type default)
		)
		(layer "In4.Cu")
	)
	(gr_arc
		(start 72.90054 -431.139854)
		(mid 72.390127 -430.62906)
		(end 71.87946 -431.1396)
		(stroke
			(width 0.2)
			(type default)
		)
		(layer "In4.Cu")
	)
	(gr_line
		(start 73.025 -343.789)
		(end 127.762 -398.526)
		(stroke
			(width 0.381)
			(type default)
		)
		(layer "In4.Cu")
	)
	(gr_line
		(start 73.025 -280.67)
		(end 73.025 -343.789)
		(stroke
			(width 0.381)
			(type default)
		)
		(layer "In4.Cu")
	)
	(gr_line
		(start 73.025 -269.676118)
		(end 75.198224 -271.849342)
		(stroke
			(width 0.381)
			(type default)
		)
		(layer "In4.Cu")
	)
	(gr_line
		(start 73.025 -179.578)
		(end 73.025 -269.676118)
		(stroke
			(width 0.381)
			(type default)
		)
		(layer "In4.Cu")
	)
	(gr_line
		(start 73.025 -166.67607)
		(end 75.198224 -168.849294)
		(stroke
			(width 0.381)
			(type default)
		)
		(layer "In4.Cu")
	)
	(gr_line
		(start 73.025 -93.091)
		(end 73.025 -166.67607)
		(stroke
			(width 0.381)
			(type default)
		)
		(layer "In4.Cu")
	)
	(gr_line
		(start 74.2696 -430.63414)
		(end 75.0824 -430.63414)
		(stroke
			(width 0.2)
			(type default)
		)
		(layer "In4.Cu")
	)
	(gr_arc
		(start 74.269854 -429.61306)
		(mid 73.75906 -430.123473)
		(end 74.2696 -430.63414)
		(stroke
			(width 0.2)
			(type default)
		)
		(layer "In4.Cu")
	)
	(gr_arc
		(start 75.0824 -430.63414)
		(mid 75.59294 -430.1236)
		(end 75.0824 -429.61306)
		(stroke
			(width 0.2)
			(type default)
		)
		(layer "In4.Cu")
	)
	(gr_line
		(start 75.0824 -429.61306)
		(end 74.269854 -429.61306)
		(stroke
			(width 0.2)
			(type default)
		)
		(layer "In4.Cu")
	)
	(gr_line
		(start 75.198224 -278.496776)
		(end 73.025 -280.67)
		(stroke
			(width 0.381)
			(type default)
		)
		(layer "In4.Cu")
	)
	(gr_line
		(start 75.198224 -271.849342)
		(end 75.198224 -278.496776)
		(stroke
			(width 0.381)
			(type default)
		)
		(layer "In4.Cu")
	)
	(gr_line
		(start 75.198224 -177.404776)
		(end 73.025 -179.578)
		(stroke
			(width 0.381)
			(type default)
		)
		(layer "In4.Cu")
	)
	(gr_line
		(start 75.198224 -173.14799)
		(end 75.198224 -173.150022)
		(stroke
			(width 0.381)
			(type default)
		)
		(layer "In4.Cu")
	)
	(gr_line
		(start 75.198224 -168.849294)
		(end 75.198224 -177.404776)
		(stroke
			(width 0.381)
			(type default)
		)
		(layer "In4.Cu")
	)
	(gr_line
		(start 97.409 -68.707)
		(end 73.025 -93.091)
		(stroke
			(width 0.381)
			(type default)
		)
		(layer "In4.Cu")
	)
	(gr_line
		(start 127.762 -398.526)
		(end 169.799 -398.526)
		(stroke
			(width 0.381)
			(type default)
		)
		(layer "In4.Cu")
	)
	(gr_line
		(start 169.799 -398.526)
		(end 170.434 -397.891)
		(stroke
			(width 0.381)
			(type default)
		)
		(layer "In4.Cu")
	)
	(gr_line
		(start 169.799 -68.707)
		(end 97.409 -68.707)
		(stroke
			(width 0.381)
			(type default)
		)
		(layer "In4.Cu")
	)
	(gr_line
		(start 170.434 -397.891)
		(end 170.434 -69.342)
		(stroke
			(width 0.381)
			(type default)
		)
		(layer "In4.Cu")
	)
	(gr_line
		(start 170.434 -69.342)
		(end 169.799 -68.707)
		(stroke
			(width 0.381)
			(type default)
		)
		(layer "In4.Cu")
	)
	(gr_arc
		(start 219.819474 -489.796582)
		(mid 220.330014 -490.307122)
		(end 220.840554 -489.796582)
		(stroke
			(width 0.2)
			(type default)
		)
		(layer "In4.Cu")
	)
	(gr_line
		(start 219.819474 -488.983782)
		(end 219.819474 -489.796582)
		(stroke
			(width 0.2)
			(type default)
		)
		(layer "In4.Cu")
	)
	(gr_arc
		(start 219.819474 -484.99649)
		(mid 220.330014 -485.50703)
		(end 220.840554 -484.99649)
		(stroke
			(width 0.2)
			(type default)
		)
		(layer "In4.Cu")
	)
	(gr_line
		(start 219.819474 -484.18369)
		(end 219.819474 -484.99649)
		(stroke
			(width 0.2)
			(type default)
		)
		(layer "In4.Cu")
	)
	(gr_arc
		(start 219.819474 -480.196652)
		(mid 220.330014 -480.707192)
		(end 220.840554 -480.196652)
		(stroke
			(width 0.2)
			(type default)
		)
		(layer "In4.Cu")
	)
	(gr_line
		(start 219.819474 -479.383852)
		(end 219.819474 -480.196652)
		(stroke
			(width 0.2)
			(type default)
		)
		(layer "In4.Cu")
	)
	(gr_arc
		(start 219.819474 -467.396576)
		(mid 220.330014 -467.907116)
		(end 220.840554 -467.396576)
		(stroke
			(width 0.2)
			(type default)
		)
		(layer "In4.Cu")
	)
	(gr_line
		(start 219.819474 -466.583776)
		(end 219.819474 -467.396576)
		(stroke
			(width 0.2)
			(type default)
		)
		(layer "In4.Cu")
	)
	(gr_arc
		(start 219.819474 -386.796534)
		(mid 220.330014 -387.307074)
		(end 220.840554 -386.796534)
		(stroke
			(width 0.2)
			(type default)
		)
		(layer "In4.Cu")
	)
	(gr_line
		(start 219.819474 -385.983734)
		(end 219.819474 -386.796534)
		(stroke
			(width 0.2)
			(type default)
		)
		(layer "In4.Cu")
	)
	(gr_arc
		(start 219.819474 -381.996442)
		(mid 220.330014 -382.506982)
		(end 220.840554 -381.996442)
		(stroke
			(width 0.2)
			(type default)
		)
		(layer "In4.Cu")
	)
	(gr_line
		(start 219.819474 -381.183642)
		(end 219.819474 -381.996442)
		(stroke
			(width 0.2)
			(type default)
		)
		(layer "In4.Cu")
	)
	(gr_arc
		(start 219.819474 -377.196604)
		(mid 220.330014 -377.707144)
		(end 220.840554 -377.196604)
		(stroke
			(width 0.2)
			(type default)
		)
		(layer "In4.Cu")
	)
	(gr_line
		(start 219.819474 -376.383804)
		(end 219.819474 -377.196604)
		(stroke
			(width 0.2)
			(type default)
		)
		(layer "In4.Cu")
	)
	(gr_arc
		(start 219.819474 -364.396528)
		(mid 220.330014 -364.907068)
		(end 220.840554 -364.396528)
		(stroke
			(width 0.2)
			(type default)
		)
		(layer "In4.Cu")
	)
	(gr_line
		(start 219.819474 -363.583728)
		(end 219.819474 -364.396528)
		(stroke
			(width 0.2)
			(type default)
		)
		(layer "In4.Cu")
	)
	(gr_arc
		(start 219.819474 -283.796486)
		(mid 220.330014 -284.307026)
		(end 220.840554 -283.796486)
		(stroke
			(width 0.2)
			(type default)
		)
		(layer "In4.Cu")
	)
	(gr_line
		(start 219.819474 -282.983686)
		(end 219.819474 -283.796486)
		(stroke
			(width 0.2)
			(type default)
		)
		(layer "In4.Cu")
	)
	(gr_arc
		(start 219.819474 -278.996394)
		(mid 220.330014 -279.506934)
		(end 220.840554 -278.996394)
		(stroke
			(width 0.2)
			(type default)
		)
		(layer "In4.Cu")
	)
	(gr_line
		(start 219.819474 -278.183594)
		(end 219.819474 -278.996394)
		(stroke
			(width 0.2)
			(type default)
		)
		(layer "In4.Cu")
	)
	(gr_arc
		(start 219.819474 -274.196556)
		(mid 220.330014 -274.707096)
		(end 220.840554 -274.196556)
		(stroke
			(width 0.2)
			(type default)
		)
		(layer "In4.Cu")
	)
	(gr_line
		(start 219.819474 -273.383756)
		(end 219.819474 -274.196556)
		(stroke
			(width 0.2)
			(type default)
		)
		(layer "In4.Cu")
	)
	(gr_arc
		(start 219.819474 -261.39648)
		(mid 220.330014 -261.90702)
		(end 220.840554 -261.39648)
		(stroke
			(width 0.2)
			(type default)
		)
		(layer "In4.Cu")
	)
	(gr_line
		(start 219.819474 -260.58368)
		(end 219.819474 -261.39648)
		(stroke
			(width 0.2)
			(type default)
		)
		(layer "In4.Cu")
	)
	(gr_arc
		(start 219.819474 -180.796438)
		(mid 220.330014 -181.306978)
		(end 220.840554 -180.796438)
		(stroke
			(width 0.2)
			(type default)
		)
		(layer "In4.Cu")
	)
	(gr_line
		(start 219.819474 -179.983638)
		(end 219.819474 -180.796438)
		(stroke
			(width 0.2)
			(type default)
		)
		(layer "In4.Cu")
	)
	(gr_arc
		(start 219.819474 -175.996346)
		(mid 220.330014 -176.506886)
		(end 220.840554 -175.996346)
		(stroke
			(width 0.2)
			(type default)
		)
		(layer "In4.Cu")
	)
	(gr_line
		(start 219.819474 -175.183546)
		(end 219.819474 -175.996346)
		(stroke
			(width 0.2)
			(type default)
		)
		(layer "In4.Cu")
	)
	(gr_arc
		(start 219.819474 -171.196508)
		(mid 220.330014 -171.707048)
		(end 220.840554 -171.196508)
		(stroke
			(width 0.2)
			(type default)
		)
		(layer "In4.Cu")
	)
	(gr_line
		(start 219.819474 -170.383708)
		(end 219.819474 -171.196508)
		(stroke
			(width 0.2)
			(type default)
		)
		(layer "In4.Cu")
	)
	(gr_arc
		(start 219.819474 -158.396432)
		(mid 220.330014 -158.906972)
		(end 220.840554 -158.396432)
		(stroke
			(width 0.2)
			(type default)
		)
		(layer "In4.Cu")
	)
	(gr_line
		(start 219.819474 -157.583632)
		(end 219.819474 -158.396432)
		(stroke
			(width 0.2)
			(type default)
		)
		(layer "In4.Cu")
	)
	(gr_arc
		(start 219.819474 -77.79639)
		(mid 220.330014 -78.30693)
		(end 220.840554 -77.79639)
		(stroke
			(width 0.2)
			(type default)
		)
		(layer "In4.Cu")
	)
	(gr_line
		(start 219.819474 -76.98359)
		(end 219.819474 -77.79639)
		(stroke
			(width 0.2)
			(type default)
		)
		(layer "In4.Cu")
	)
	(gr_arc
		(start 219.819474 -72.996298)
		(mid 220.330014 -73.506838)
		(end 220.840554 -72.996298)
		(stroke
			(width 0.2)
			(type default)
		)
		(layer "In4.Cu")
	)
	(gr_line
		(start 219.819474 -72.183498)
		(end 219.819474 -72.996298)
		(stroke
			(width 0.2)
			(type default)
		)
		(layer "In4.Cu")
	)
	(gr_arc
		(start 219.819474 -68.19646)
		(mid 220.330014 -68.707)
		(end 220.840554 -68.19646)
		(stroke
			(width 0.2)
			(type default)
		)
		(layer "In4.Cu")
	)
	(gr_line
		(start 219.819474 -67.38366)
		(end 219.819474 -68.19646)
		(stroke
			(width 0.2)
			(type default)
		)
		(layer "In4.Cu")
	)
	(gr_arc
		(start 219.819474 -55.396384)
		(mid 220.330014 -55.906924)
		(end 220.840554 -55.396384)
		(stroke
			(width 0.2)
			(type default)
		)
		(layer "In4.Cu")
	)
	(gr_line
		(start 219.819474 -54.583584)
		(end 219.819474 -55.396384)
		(stroke
			(width 0.2)
			(type default)
		)
		(layer "In4.Cu")
	)
	(gr_line
		(start 220.840554 -489.796582)
		(end 220.840554 -488.984036)
		(stroke
			(width 0.2)
			(type default)
		)
		(layer "In4.Cu")
	)
	(gr_arc
		(start 220.840554 -488.984036)
		(mid 220.330141 -488.473242)
		(end 219.819474 -488.983782)
		(stroke
			(width 0.2)
			(type default)
		)
		(layer "In4.Cu")
	)
	(gr_line
		(start 220.840554 -484.99649)
		(end 220.840554 -484.183944)
		(stroke
			(width 0.2)
			(type default)
		)
		(layer "In4.Cu")
	)
	(gr_arc
		(start 220.840554 -484.183944)
		(mid 220.330141 -483.67315)
		(end 219.819474 -484.18369)
		(stroke
			(width 0.2)
			(type default)
		)
		(layer "In4.Cu")
	)
	(gr_line
		(start 220.840554 -480.196652)
		(end 220.840554 -479.384106)
		(stroke
			(width 0.2)
			(type default)
		)
		(layer "In4.Cu")
	)
	(gr_arc
		(start 220.840554 -479.384106)
		(mid 220.330141 -478.873312)
		(end 219.819474 -479.383852)
		(stroke
			(width 0.2)
			(type default)
		)
		(layer "In4.Cu")
	)
	(gr_line
		(start 220.840554 -467.396576)
		(end 220.840554 -466.58403)
		(stroke
			(width 0.2)
			(type default)
		)
		(layer "In4.Cu")
	)
	(gr_arc
		(start 220.840554 -466.58403)
		(mid 220.330141 -466.073236)
		(end 219.819474 -466.583776)
		(stroke
			(width 0.2)
			(type default)
		)
		(layer "In4.Cu")
	)
	(gr_line
		(start 220.840554 -386.796534)
		(end 220.840554 -385.983988)
		(stroke
			(width 0.2)
			(type default)
		)
		(layer "In4.Cu")
	)
	(gr_arc
		(start 220.840554 -385.983988)
		(mid 220.330141 -385.473194)
		(end 219.819474 -385.983734)
		(stroke
			(width 0.2)
			(type default)
		)
		(layer "In4.Cu")
	)
	(gr_line
		(start 220.840554 -381.996442)
		(end 220.840554 -381.183896)
		(stroke
			(width 0.2)
			(type default)
		)
		(layer "In4.Cu")
	)
	(gr_arc
		(start 220.840554 -381.183896)
		(mid 220.330141 -380.673102)
		(end 219.819474 -381.183642)
		(stroke
			(width 0.2)
			(type default)
		)
		(layer "In4.Cu")
	)
	(gr_line
		(start 220.840554 -377.196604)
		(end 220.840554 -376.384058)
		(stroke
			(width 0.2)
			(type default)
		)
		(layer "In4.Cu")
	)
	(gr_arc
		(start 220.840554 -376.384058)
		(mid 220.330141 -375.873264)
		(end 219.819474 -376.383804)
		(stroke
			(width 0.2)
			(type default)
		)
		(layer "In4.Cu")
	)
	(gr_line
		(start 220.840554 -364.396528)
		(end 220.840554 -363.583982)
		(stroke
			(width 0.2)
			(type default)
		)
		(layer "In4.Cu")
	)
	(gr_arc
		(start 220.840554 -363.583982)
		(mid 220.330141 -363.073188)
		(end 219.819474 -363.583728)
		(stroke
			(width 0.2)
			(type default)
		)
		(layer "In4.Cu")
	)
	(gr_line
		(start 220.840554 -283.796486)
		(end 220.840554 -282.98394)
		(stroke
			(width 0.2)
			(type default)
		)
		(layer "In4.Cu")
	)
	(gr_arc
		(start 220.840554 -282.98394)
		(mid 220.330141 -282.473146)
		(end 219.819474 -282.983686)
		(stroke
			(width 0.2)
			(type default)
		)
		(layer "In4.Cu")
	)
	(gr_line
		(start 220.840554 -278.996394)
		(end 220.840554 -278.183848)
		(stroke
			(width 0.2)
			(type default)
		)
		(layer "In4.Cu")
	)
	(gr_arc
		(start 220.840554 -278.183848)
		(mid 220.330141 -277.673054)
		(end 219.819474 -278.183594)
		(stroke
			(width 0.2)
			(type default)
		)
		(layer "In4.Cu")
	)
	(gr_line
		(start 220.840554 -274.196556)
		(end 220.840554 -273.38401)
		(stroke
			(width 0.2)
			(type default)
		)
		(layer "In4.Cu")
	)
	(gr_arc
		(start 220.840554 -273.38401)
		(mid 220.330141 -272.873216)
		(end 219.819474 -273.383756)
		(stroke
			(width 0.2)
			(type default)
		)
		(layer "In4.Cu")
	)
	(gr_line
		(start 220.840554 -261.39648)
		(end 220.840554 -260.583934)
		(stroke
			(width 0.2)
			(type default)
		)
		(layer "In4.Cu")
	)
	(gr_arc
		(start 220.840554 -260.583934)
		(mid 220.330141 -260.07314)
		(end 219.819474 -260.58368)
		(stroke
			(width 0.2)
			(type default)
		)
		(layer "In4.Cu")
	)
	(gr_line
		(start 220.840554 -180.796438)
		(end 220.840554 -179.983892)
		(stroke
			(width 0.2)
			(type default)
		)
		(layer "In4.Cu")
	)
	(gr_arc
		(start 220.840554 -179.983892)
		(mid 220.330141 -179.473098)
		(end 219.819474 -179.983638)
		(stroke
			(width 0.2)
			(type default)
		)
		(layer "In4.Cu")
	)
	(gr_line
		(start 220.840554 -175.996346)
		(end 220.840554 -175.1838)
		(stroke
			(width 0.2)
			(type default)
		)
		(layer "In4.Cu")
	)
	(gr_arc
		(start 220.840554 -175.1838)
		(mid 220.330141 -174.673006)
		(end 219.819474 -175.183546)
		(stroke
			(width 0.2)
			(type default)
		)
		(layer "In4.Cu")
	)
	(gr_line
		(start 220.840554 -171.196508)
		(end 220.840554 -170.383962)
		(stroke
			(width 0.2)
			(type default)
		)
		(layer "In4.Cu")
	)
	(gr_arc
		(start 220.840554 -170.383962)
		(mid 220.330141 -169.873168)
		(end 219.819474 -170.383708)
		(stroke
			(width 0.2)
			(type default)
		)
		(layer "In4.Cu")
	)
	(gr_line
		(start 220.840554 -158.396432)
		(end 220.840554 -157.583886)
		(stroke
			(width 0.2)
			(type default)
		)
		(layer "In4.Cu")
	)
	(gr_arc
		(start 220.840554 -157.583886)
		(mid 220.330141 -157.073092)
		(end 219.819474 -157.583632)
		(stroke
			(width 0.2)
			(type default)
		)
		(layer "In4.Cu")
	)
	(gr_line
		(start 220.840554 -77.79639)
		(end 220.840554 -76.983844)
		(stroke
			(width 0.2)
			(type default)
		)
		(layer "In4.Cu")
	)
	(gr_arc
		(start 220.840554 -76.983844)
		(mid 220.330141 -76.47305)
		(end 219.819474 -76.98359)
		(stroke
			(width 0.2)
			(type default)
		)
		(layer "In4.Cu")
	)
	(gr_line
		(start 220.840554 -72.996298)
		(end 220.840554 -72.183752)
		(stroke
			(width 0.2)
			(type default)
		)
		(layer "In4.Cu")
	)
	(gr_arc
		(start 220.840554 -72.183752)
		(mid 220.330141 -71.672958)
		(end 219.819474 -72.183498)
		(stroke
			(width 0.2)
			(type default)
		)
		(layer "In4.Cu")
	)
	(gr_line
		(start 220.840554 -68.19646)
		(end 220.840554 -67.383914)
		(stroke
			(width 0.2)
			(type default)
		)
		(layer "In4.Cu")
	)
	(gr_arc
		(start 220.840554 -67.383914)
		(mid 220.330141 -66.87312)
		(end 219.819474 -67.38366)
		(stroke
			(width 0.2)
			(type default)
		)
		(layer "In4.Cu")
	)
	(gr_line
		(start 220.840554 -55.396384)
		(end 220.840554 -54.583838)
		(stroke
			(width 0.2)
			(type default)
		)
		(layer "In4.Cu")
	)
	(gr_arc
		(start 220.840554 -54.583838)
		(mid 220.330141 -54.073044)
		(end 219.819474 -54.583584)
		(stroke
			(width 0.2)
			(type default)
		)
		(layer "In4.Cu")
	)
	(gr_arc
		(start 221.114874 -492.349028)
		(mid 221.727014 -492.961168)
		(end 222.339154 -492.349028)
		(stroke
			(width 0.2)
			(type default)
		)
		(layer "In4.Cu")
	)
	(gr_line
		(start 221.114874 -491.231428)
		(end 221.114874 -492.349028)
		(stroke
			(width 0.2)
			(type default)
		)
		(layer "In4.Cu")
	)
	(gr_arc
		(start 221.114874 -487.548936)
		(mid 221.727014 -488.161076)
		(end 222.339154 -487.548936)
		(stroke
			(width 0.2)
			(type default)
		)
		(layer "In4.Cu")
	)
	(gr_line
		(start 221.114874 -486.431336)
		(end 221.114874 -487.548936)
		(stroke
			(width 0.2)
			(type default)
		)
		(layer "In4.Cu")
	)
	(gr_arc
		(start 221.114874 -482.748844)
		(mid 221.727014 -483.360984)
		(end 222.339154 -482.748844)
		(stroke
			(width 0.2)
			(type default)
		)
		(layer "In4.Cu")
	)
	(gr_line
		(start 221.114874 -481.631244)
		(end 221.114874 -482.748844)
		(stroke
			(width 0.2)
			(type default)
		)
		(layer "In4.Cu")
	)
	(gr_arc
		(start 221.114874 -469.949022)
		(mid 221.727014 -470.561162)
		(end 222.339154 -469.949022)
		(stroke
			(width 0.2)
			(type default)
		)
		(layer "In4.Cu")
	)
	(gr_line
		(start 221.114874 -468.831422)
		(end 221.114874 -469.949022)
		(stroke
			(width 0.2)
			(type default)
		)
		(layer "In4.Cu")
	)
	(gr_arc
		(start 221.114874 -389.34898)
		(mid 221.727014 -389.96112)
		(end 222.339154 -389.34898)
		(stroke
			(width 0.2)
			(type default)
		)
		(layer "In4.Cu")
	)
	(gr_line
		(start 221.114874 -388.23138)
		(end 221.114874 -389.34898)
		(stroke
			(width 0.2)
			(type default)
		)
		(layer "In4.Cu")
	)
	(gr_arc
		(start 221.114874 -384.548888)
		(mid 221.727014 -385.161028)
		(end 222.339154 -384.548888)
		(stroke
			(width 0.2)
			(type default)
		)
		(layer "In4.Cu")
	)
	(gr_line
		(start 221.114874 -383.431288)
		(end 221.114874 -384.548888)
		(stroke
			(width 0.2)
			(type default)
		)
		(layer "In4.Cu")
	)
	(gr_arc
		(start 221.114874 -379.748796)
		(mid 221.727014 -380.360936)
		(end 222.339154 -379.748796)
		(stroke
			(width 0.2)
			(type default)
		)
		(layer "In4.Cu")
	)
	(gr_line
		(start 221.114874 -378.631196)
		(end 221.114874 -379.748796)
		(stroke
			(width 0.2)
			(type default)
		)
		(layer "In4.Cu")
	)
	(gr_arc
		(start 221.114874 -366.948974)
		(mid 221.727014 -367.561114)
		(end 222.339154 -366.948974)
		(stroke
			(width 0.2)
			(type default)
		)
		(layer "In4.Cu")
	)
	(gr_line
		(start 221.114874 -365.831374)
		(end 221.114874 -366.948974)
		(stroke
			(width 0.2)
			(type default)
		)
		(layer "In4.Cu")
	)
	(gr_arc
		(start 221.114874 -286.348932)
		(mid 221.727014 -286.961072)
		(end 222.339154 -286.348932)
		(stroke
			(width 0.2)
			(type default)
		)
		(layer "In4.Cu")
	)
	(gr_line
		(start 221.114874 -285.231332)
		(end 221.114874 -286.348932)
		(stroke
			(width 0.2)
			(type default)
		)
		(layer "In4.Cu")
	)
	(gr_arc
		(start 221.114874 -281.54884)
		(mid 221.727014 -282.16098)
		(end 222.339154 -281.54884)
		(stroke
			(width 0.2)
			(type default)
		)
		(layer "In4.Cu")
	)
	(gr_line
		(start 221.114874 -280.43124)
		(end 221.114874 -281.54884)
		(stroke
			(width 0.2)
			(type default)
		)
		(layer "In4.Cu")
	)
	(gr_arc
		(start 221.114874 -276.748748)
		(mid 221.727014 -277.360888)
		(end 222.339154 -276.748748)
		(stroke
			(width 0.2)
			(type default)
		)
		(layer "In4.Cu")
	)
	(gr_line
		(start 221.114874 -275.631148)
		(end 221.114874 -276.748748)
		(stroke
			(width 0.2)
			(type default)
		)
		(layer "In4.Cu")
	)
	(gr_arc
		(start 221.114874 -263.948926)
		(mid 221.727014 -264.561066)
		(end 222.339154 -263.948926)
		(stroke
			(width 0.2)
			(type default)
		)
		(layer "In4.Cu")
	)
	(gr_line
		(start 221.114874 -262.831326)
		(end 221.114874 -263.948926)
		(stroke
			(width 0.2)
			(type default)
		)
		(layer "In4.Cu")
	)
	(gr_arc
		(start 221.114874 -183.348884)
		(mid 221.727014 -183.961024)
		(end 222.339154 -183.348884)
		(stroke
			(width 0.2)
			(type default)
		)
		(layer "In4.Cu")
	)
	(gr_line
		(start 221.114874 -182.231284)
		(end 221.114874 -183.348884)
		(stroke
			(width 0.2)
			(type default)
		)
		(layer "In4.Cu")
	)
	(gr_arc
		(start 221.114874 -178.548792)
		(mid 221.727014 -179.160932)
		(end 222.339154 -178.548792)
		(stroke
			(width 0.2)
			(type default)
		)
		(layer "In4.Cu")
	)
	(gr_line
		(start 221.114874 -177.431192)
		(end 221.114874 -178.548792)
		(stroke
			(width 0.2)
			(type default)
		)
		(layer "In4.Cu")
	)
	(gr_arc
		(start 221.114874 -173.7487)
		(mid 221.727014 -174.36084)
		(end 222.339154 -173.7487)
		(stroke
			(width 0.2)
			(type default)
		)
		(layer "In4.Cu")
	)
	(gr_line
		(start 221.114874 -172.6311)
		(end 221.114874 -173.7487)
		(stroke
			(width 0.2)
			(type default)
		)
		(layer "In4.Cu")
	)
	(gr_arc
		(start 221.114874 -160.948878)
		(mid 221.727014 -161.561018)
		(end 222.339154 -160.948878)
		(stroke
			(width 0.2)
			(type default)
		)
		(layer "In4.Cu")
	)
	(gr_line
		(start 221.114874 -159.831278)
		(end 221.114874 -160.948878)
		(stroke
			(width 0.2)
			(type default)
		)
		(layer "In4.Cu")
	)
	(gr_arc
		(start 221.114874 -80.348836)
		(mid 221.727014 -80.960976)
		(end 222.339154 -80.348836)
		(stroke
			(width 0.2)
			(type default)
		)
		(layer "In4.Cu")
	)
	(gr_line
		(start 221.114874 -79.231236)
		(end 221.114874 -80.348836)
		(stroke
			(width 0.2)
			(type default)
		)
		(layer "In4.Cu")
	)
	(gr_arc
		(start 221.114874 -75.548744)
		(mid 221.727014 -76.160884)
		(end 222.339154 -75.548744)
		(stroke
			(width 0.2)
			(type default)
		)
		(layer "In4.Cu")
	)
	(gr_line
		(start 221.114874 -74.431144)
		(end 221.114874 -75.548744)
		(stroke
			(width 0.2)
			(type default)
		)
		(layer "In4.Cu")
	)
	(gr_arc
		(start 221.114874 -70.748652)
		(mid 221.727014 -71.360792)
		(end 222.339154 -70.748652)
		(stroke
			(width 0.2)
			(type default)
		)
		(layer "In4.Cu")
	)
	(gr_line
		(start 221.114874 -69.631052)
		(end 221.114874 -70.748652)
		(stroke
			(width 0.2)
			(type default)
		)
		(layer "In4.Cu")
	)
	(gr_arc
		(start 221.114874 -57.94883)
		(mid 221.727014 -58.56097)
		(end 222.339154 -57.94883)
		(stroke
			(width 0.2)
			(type default)
		)
		(layer "In4.Cu")
	)
	(gr_line
		(start 221.114874 -56.83123)
		(end 221.114874 -57.94883)
		(stroke
			(width 0.2)
			(type default)
		)
		(layer "In4.Cu")
	)
	(gr_line
		(start 222.339154 -492.349028)
		(end 222.339154 -491.231682)
		(stroke
			(width 0.2)
			(type default)
		)
		(layer "In4.Cu")
	)
	(gr_arc
		(start 222.339154 -491.231682)
		(mid 221.727141 -490.619288)
		(end 221.114874 -491.231428)
		(stroke
			(width 0.2)
			(type default)
		)
		(layer "In4.Cu")
	)
	(gr_line
		(start 222.339154 -487.548936)
		(end 222.339154 -486.43159)
		(stroke
			(width 0.2)
			(type default)
		)
		(layer "In4.Cu")
	)
	(gr_arc
		(start 222.339154 -486.43159)
		(mid 221.727141 -485.819196)
		(end 221.114874 -486.431336)
		(stroke
			(width 0.2)
			(type default)
		)
		(layer "In4.Cu")
	)
	(gr_line
		(start 222.339154 -482.748844)
		(end 222.339154 -481.631498)
		(stroke
			(width 0.2)
			(type default)
		)
		(layer "In4.Cu")
	)
	(gr_arc
		(start 222.339154 -481.631498)
		(mid 221.727141 -481.019104)
		(end 221.114874 -481.631244)
		(stroke
			(width 0.2)
			(type default)
		)
		(layer "In4.Cu")
	)
	(gr_line
		(start 222.339154 -469.949022)
		(end 222.339154 -468.831676)
		(stroke
			(width 0.2)
			(type default)
		)
		(layer "In4.Cu")
	)
	(gr_arc
		(start 222.339154 -468.831676)
		(mid 221.727141 -468.219282)
		(end 221.114874 -468.831422)
		(stroke
			(width 0.2)
			(type default)
		)
		(layer "In4.Cu")
	)
	(gr_line
		(start 222.339154 -389.34898)
		(end 222.339154 -388.231634)
		(stroke
			(width 0.2)
			(type default)
		)
		(layer "In4.Cu")
	)
	(gr_arc
		(start 222.339154 -388.231634)
		(mid 221.727141 -387.61924)
		(end 221.114874 -388.23138)
		(stroke
			(width 0.2)
			(type default)
		)
		(layer "In4.Cu")
	)
	(gr_line
		(start 222.339154 -384.548888)
		(end 222.339154 -383.431542)
		(stroke
			(width 0.2)
			(type default)
		)
		(layer "In4.Cu")
	)
	(gr_arc
		(start 222.339154 -383.431542)
		(mid 221.727141 -382.819148)
		(end 221.114874 -383.431288)
		(stroke
			(width 0.2)
			(type default)
		)
		(layer "In4.Cu")
	)
	(gr_line
		(start 222.339154 -379.748796)
		(end 222.339154 -378.63145)
		(stroke
			(width 0.2)
			(type default)
		)
		(layer "In4.Cu")
	)
	(gr_arc
		(start 222.339154 -378.63145)
		(mid 221.727141 -378.019056)
		(end 221.114874 -378.631196)
		(stroke
			(width 0.2)
			(type default)
		)
		(layer "In4.Cu")
	)
	(gr_line
		(start 222.339154 -366.948974)
		(end 222.339154 -365.831628)
		(stroke
			(width 0.2)
			(type default)
		)
		(layer "In4.Cu")
	)
	(gr_arc
		(start 222.339154 -365.831628)
		(mid 221.727141 -365.219234)
		(end 221.114874 -365.831374)
		(stroke
			(width 0.2)
			(type default)
		)
		(layer "In4.Cu")
	)
	(gr_line
		(start 222.339154 -286.348932)
		(end 222.339154 -285.231586)
		(stroke
			(width 0.2)
			(type default)
		)
		(layer "In4.Cu")
	)
	(gr_arc
		(start 222.339154 -285.231586)
		(mid 221.727141 -284.619192)
		(end 221.114874 -285.231332)
		(stroke
			(width 0.2)
			(type default)
		)
		(layer "In4.Cu")
	)
	(gr_line
		(start 222.339154 -281.54884)
		(end 222.339154 -280.431494)
		(stroke
			(width 0.2)
			(type default)
		)
		(layer "In4.Cu")
	)
	(gr_arc
		(start 222.339154 -280.431494)
		(mid 221.727141 -279.8191)
		(end 221.114874 -280.43124)
		(stroke
			(width 0.2)
			(type default)
		)
		(layer "In4.Cu")
	)
	(gr_line
		(start 222.339154 -276.748748)
		(end 222.339154 -275.631402)
		(stroke
			(width 0.2)
			(type default)
		)
		(layer "In4.Cu")
	)
	(gr_arc
		(start 222.339154 -275.631402)
		(mid 221.727141 -275.019008)
		(end 221.114874 -275.631148)
		(stroke
			(width 0.2)
			(type default)
		)
		(layer "In4.Cu")
	)
	(gr_line
		(start 222.339154 -263.948926)
		(end 222.339154 -262.83158)
		(stroke
			(width 0.2)
			(type default)
		)
		(layer "In4.Cu")
	)
	(gr_arc
		(start 222.339154 -262.83158)
		(mid 221.727141 -262.219186)
		(end 221.114874 -262.831326)
		(stroke
			(width 0.2)
			(type default)
		)
		(layer "In4.Cu")
	)
	(gr_line
		(start 222.339154 -183.348884)
		(end 222.339154 -182.231538)
		(stroke
			(width 0.2)
			(type default)
		)
		(layer "In4.Cu")
	)
	(gr_arc
		(start 222.339154 -182.231538)
		(mid 221.727141 -181.619144)
		(end 221.114874 -182.231284)
		(stroke
			(width 0.2)
			(type default)
		)
		(layer "In4.Cu")
	)
	(gr_line
		(start 222.339154 -178.548792)
		(end 222.339154 -177.431446)
		(stroke
			(width 0.2)
			(type default)
		)
		(layer "In4.Cu")
	)
	(gr_arc
		(start 222.339154 -177.431446)
		(mid 221.727141 -176.819052)
		(end 221.114874 -177.431192)
		(stroke
			(width 0.2)
			(type default)
		)
		(layer "In4.Cu")
	)
	(gr_line
		(start 222.339154 -173.7487)
		(end 222.339154 -172.631354)
		(stroke
			(width 0.2)
			(type default)
		)
		(layer "In4.Cu")
	)
	(gr_arc
		(start 222.339154 -172.631354)
		(mid 221.727141 -172.01896)
		(end 221.114874 -172.6311)
		(stroke
			(width 0.2)
			(type default)
		)
		(layer "In4.Cu")
	)
	(gr_line
		(start 222.339154 -160.948878)
		(end 222.339154 -159.831532)
		(stroke
			(width 0.2)
			(type default)
		)
		(layer "In4.Cu")
	)
	(gr_arc
		(start 222.339154 -159.831532)
		(mid 221.727141 -159.219138)
		(end 221.114874 -159.831278)
		(stroke
			(width 0.2)
			(type default)
		)
		(layer "In4.Cu")
	)
	(gr_line
		(start 222.339154 -80.348836)
		(end 222.339154 -79.23149)
		(stroke
			(width 0.2)
			(type default)
		)
		(layer "In4.Cu")
	)
	(gr_arc
		(start 222.339154 -79.23149)
		(mid 221.727141 -78.619096)
		(end 221.114874 -79.231236)
		(stroke
			(width 0.2)
			(type default)
		)
		(layer "In4.Cu")
	)
	(gr_line
		(start 222.339154 -75.548744)
		(end 222.339154 -74.431398)
		(stroke
			(width 0.2)
			(type default)
		)
		(layer "In4.Cu")
	)
	(gr_arc
		(start 222.339154 -74.431398)
		(mid 221.727141 -73.819004)
		(end 221.114874 -74.431144)
		(stroke
			(width 0.2)
			(type default)
		)
		(layer "In4.Cu")
	)
	(gr_line
		(start 222.339154 -70.748652)
		(end 222.339154 -69.631306)
		(stroke
			(width 0.2)
			(type default)
		)
		(layer "In4.Cu")
	)
	(gr_arc
		(start 222.339154 -69.631306)
		(mid 221.727141 -69.018912)
		(end 221.114874 -69.631052)
		(stroke
			(width 0.2)
			(type default)
		)
		(layer "In4.Cu")
	)
	(gr_line
		(start 222.339154 -57.94883)
		(end 222.339154 -56.831484)
		(stroke
			(width 0.2)
			(type default)
		)
		(layer "In4.Cu")
	)
	(gr_arc
		(start 222.339154 -56.831484)
		(mid 221.727141 -56.21909)
		(end 221.114874 -56.83123)
		(stroke
			(width 0.2)
			(type default)
		)
		(layer "In4.Cu")
	)
	(gr_line
		(start 229.907084 -472.300808)
		(end 230.71963 -472.300808)
		(stroke
			(width 0.2)
			(type default)
		)
		(layer "In4.Cu")
	)
	(gr_arc
		(start 229.907084 -471.279728)
		(mid 229.396544 -471.790268)
		(end 229.907084 -472.300808)
		(stroke
			(width 0.2)
			(type default)
		)
		(layer "In4.Cu")
	)
	(gr_line
		(start 229.907084 -369.30076)
		(end 230.71963 -369.30076)
		(stroke
			(width 0.2)
			(type default)
		)
		(layer "In4.Cu")
	)
	(gr_arc
		(start 229.907084 -368.27968)
		(mid 229.396544 -368.79022)
		(end 229.907084 -369.30076)
		(stroke
			(width 0.2)
			(type default)
		)
		(layer "In4.Cu")
	)
	(gr_line
		(start 229.907084 -266.300712)
		(end 230.71963 -266.300712)
		(stroke
			(width 0.2)
			(type default)
		)
		(layer "In4.Cu")
	)
	(gr_arc
		(start 229.907084 -265.279632)
		(mid 229.396544 -265.790172)
		(end 229.907084 -266.300712)
		(stroke
			(width 0.2)
			(type default)
		)
		(layer "In4.Cu")
	)
	(gr_line
		(start 229.907084 -163.300664)
		(end 230.71963 -163.300664)
		(stroke
			(width 0.2)
			(type default)
		)
		(layer "In4.Cu")
	)
	(gr_arc
		(start 229.907084 -162.279584)
		(mid 229.396544 -162.790124)
		(end 229.907084 -163.300664)
		(stroke
			(width 0.2)
			(type default)
		)
		(layer "In4.Cu")
	)
	(gr_line
		(start 229.907084 -60.300616)
		(end 230.71963 -60.300616)
		(stroke
			(width 0.2)
			(type default)
		)
		(layer "In4.Cu")
	)
	(gr_arc
		(start 229.907084 -59.279536)
		(mid 229.396544 -59.790076)
		(end 229.907084 -60.300616)
		(stroke
			(width 0.2)
			(type default)
		)
		(layer "In4.Cu")
	)
	(gr_arc
		(start 230.71963 -472.300808)
		(mid 231.230424 -471.790395)
		(end 230.719884 -471.279728)
		(stroke
			(width 0.2)
			(type default)
		)
		(layer "In4.Cu")
	)
	(gr_arc
		(start 230.71963 -369.30076)
		(mid 231.230424 -368.790347)
		(end 230.719884 -368.27968)
		(stroke
			(width 0.2)
			(type default)
		)
		(layer "In4.Cu")
	)
	(gr_arc
		(start 230.71963 -266.300712)
		(mid 231.230424 -265.790299)
		(end 230.719884 -265.279632)
		(stroke
			(width 0.2)
			(type default)
		)
		(layer "In4.Cu")
	)
	(gr_arc
		(start 230.71963 -163.300664)
		(mid 231.230424 -162.790251)
		(end 230.719884 -162.279584)
		(stroke
			(width 0.2)
			(type default)
		)
		(layer "In4.Cu")
	)
	(gr_arc
		(start 230.71963 -60.300616)
		(mid 231.230424 -59.790203)
		(end 230.719884 -59.279536)
		(stroke
			(width 0.2)
			(type default)
		)
		(layer "In4.Cu")
	)
	(gr_line
		(start 230.719884 -471.279728)
		(end 229.907084 -471.279728)
		(stroke
			(width 0.2)
			(type default)
		)
		(layer "In4.Cu")
	)
	(gr_line
		(start 230.719884 -368.27968)
		(end 229.907084 -368.27968)
		(stroke
			(width 0.2)
			(type default)
		)
		(layer "In4.Cu")
	)
	(gr_line
		(start 230.719884 -265.279632)
		(end 229.907084 -265.279632)
		(stroke
			(width 0.2)
			(type default)
		)
		(layer "In4.Cu")
	)
	(gr_line
		(start 230.719884 -162.279584)
		(end 229.907084 -162.279584)
		(stroke
			(width 0.2)
			(type default)
		)
		(layer "In4.Cu")
	)
	(gr_line
		(start 230.719884 -59.279536)
		(end 229.907084 -59.279536)
		(stroke
			(width 0.2)
			(type default)
		)
		(layer "In4.Cu")
	)
	(gr_arc
		(start 232.876344 -473.391992)
		(mid 233.386757 -473.902786)
		(end 233.897424 -473.392246)
		(stroke
			(width 0.2)
			(type default)
		)
		(layer "In4.Cu")
	)
	(gr_line
		(start 232.876344 -472.579446)
		(end 232.876344 -473.391992)
		(stroke
			(width 0.2)
			(type default)
		)
		(layer "In4.Cu")
	)
	(gr_arc
		(start 232.876344 -370.391944)
		(mid 233.386757 -370.902738)
		(end 233.897424 -370.392198)
		(stroke
			(width 0.2)
			(type default)
		)
		(layer "In4.Cu")
	)
	(gr_line
		(start 232.876344 -369.579398)
		(end 232.876344 -370.391944)
		(stroke
			(width 0.2)
			(type default)
		)
		(layer "In4.Cu")
	)
	(gr_arc
		(start 232.876344 -267.391896)
		(mid 233.386757 -267.90269)
		(end 233.897424 -267.39215)
		(stroke
			(width 0.2)
			(type default)
		)
		(layer "In4.Cu")
	)
	(gr_line
		(start 232.876344 -266.57935)
		(end 232.876344 -267.391896)
		(stroke
			(width 0.2)
			(type default)
		)
		(layer "In4.Cu")
	)
	(gr_arc
		(start 232.876344 -164.391848)
		(mid 233.386757 -164.902642)
		(end 233.897424 -164.392102)
		(stroke
			(width 0.2)
			(type default)
		)
		(layer "In4.Cu")
	)
	(gr_line
		(start 232.876344 -163.579302)
		(end 232.876344 -164.391848)
		(stroke
			(width 0.2)
			(type default)
		)
		(layer "In4.Cu")
	)
	(gr_arc
		(start 232.876344 -61.3918)
		(mid 233.386757 -61.902594)
		(end 233.897424 -61.392054)
		(stroke
			(width 0.2)
			(type default)
		)
		(layer "In4.Cu")
	)
	(gr_line
		(start 232.876344 -60.579254)
		(end 232.876344 -61.3918)
		(stroke
			(width 0.2)
			(type default)
		)
		(layer "In4.Cu")
	)
	(gr_line
		(start 233.897424 -473.392246)
		(end 233.897424 -472.579446)
		(stroke
			(width 0.2)
			(type default)
		)
		(layer "In4.Cu")
	)
	(gr_arc
		(start 233.897424 -472.579446)
		(mid 233.386884 -472.068906)
		(end 232.876344 -472.579446)
		(stroke
			(width 0.2)
			(type default)
		)
		(layer "In4.Cu")
	)
	(gr_line
		(start 233.897424 -370.392198)
		(end 233.897424 -369.579398)
		(stroke
			(width 0.2)
			(type default)
		)
		(layer "In4.Cu")
	)
	(gr_arc
		(start 233.897424 -369.579398)
		(mid 233.386884 -369.068858)
		(end 232.876344 -369.579398)
		(stroke
			(width 0.2)
			(type default)
		)
		(layer "In4.Cu")
	)
	(gr_line
		(start 233.897424 -267.39215)
		(end 233.897424 -266.57935)
		(stroke
			(width 0.2)
			(type default)
		)
		(layer "In4.Cu")
	)
	(gr_arc
		(start 233.897424 -266.57935)
		(mid 233.386884 -266.06881)
		(end 232.876344 -266.57935)
		(stroke
			(width 0.2)
			(type default)
		)
		(layer "In4.Cu")
	)
	(gr_line
		(start 233.897424 -164.392102)
		(end 233.897424 -163.579302)
		(stroke
			(width 0.2)
			(type default)
		)
		(layer "In4.Cu")
	)
	(gr_arc
		(start 233.897424 -163.579302)
		(mid 233.386884 -163.068762)
		(end 232.876344 -163.579302)
		(stroke
			(width 0.2)
			(type default)
		)
		(layer "In4.Cu")
	)
	(gr_line
		(start 233.897424 -61.392054)
		(end 233.897424 -60.579254)
		(stroke
			(width 0.2)
			(type default)
		)
		(layer "In4.Cu")
	)
	(gr_arc
		(start 233.897424 -60.579254)
		(mid 233.386884 -60.068714)
		(end 232.876344 -60.579254)
		(stroke
			(width 0.2)
			(type default)
		)
		(layer "In4.Cu")
	)
	(gr_line
		(start 252.394974 -410.485082)
		(end 258.899914 -410.485082)
		(stroke
			(width 2.54)
			(type default)
		)
		(layer "In4.Cu")
	)
	(gr_arc
		(start 252.394974 -409.41498)
		(mid 251.859796 -409.950158)
		(end 252.394974 -410.485082)
		(stroke
			(width 2.54)
			(type default)
		)
		(layer "In4.Cu")
	)
	(gr_line
		(start 258.899914 -410.485082)
		(end 259.899912 -411.48508)
		(stroke
			(width 2.54)
			(type default)
		)
		(layer "In4.Cu")
	)
	(gr_line
		(start 258.899914 -409.41498)
		(end 252.394974 -409.41498)
		(stroke
			(width 2.54)
			(type default)
		)
		(layer "In4.Cu")
	)
	(gr_arc
		(start 259.899912 -425.69003)
		(mid 260.307091 -426.672919)
		(end 261.290054 -427.079918)
		(stroke
			(width 2.54)
			(type default)
		)
		(layer "In4.Cu")
	)
	(gr_line
		(start 259.899912 -411.48508)
		(end 259.899912 -425.69003)
		(stroke
			(width 2.54)
			(type default)
		)
		(layer "In4.Cu")
	)
	(gr_line
		(start 259.899912 -408.414982)
		(end 258.899914 -409.41498)
		(stroke
			(width 2.54)
			(type default)
		)
		(layer "In4.Cu")
	)
	(gr_line
		(start 259.899912 -364.309914)
		(end 259.899912 -408.414982)
		(stroke
			(width 2.54)
			(type default)
		)
		(layer "In4.Cu")
	)
	(gr_line
		(start 261.290054 -427.079918)
		(end 262.50011 -427.079918)
		(stroke
			(width 2.54)
			(type default)
		)
		(layer "In4.Cu")
	)
	(gr_arc
		(start 261.290054 -362.920026)
		(mid 260.307165 -363.327099)
		(end 259.899912 -364.309914)
		(stroke
			(width 2.54)
			(type default)
		)
		(layer "In4.Cu")
	)
	(gr_line
		(start 262.50011 -506.000004)
		(end 0.999998 -506.000004)
		(stroke
			(width 2.54)
			(type default)
		)
		(layer "In4.Cu")
	)
	(gr_arc
		(start 262.50011 -506.000004)
		(mid 263.207211 -505.707108)
		(end 263.500108 -505.000006)
		(stroke
			(width 2.54)
			(type default)
		)
		(layer "In4.Cu")
	)
	(gr_line
		(start 262.50011 -427.079918)
		(end 263.500108 -428.079916)
		(stroke
			(width 2.54)
			(type default)
		)
		(layer "In4.Cu")
	)
	(gr_line
		(start 262.50011 -362.920026)
		(end 261.290054 -362.920026)
		(stroke
			(width 2.54)
			(type default)
		)
		(layer "In4.Cu")
	)
	(gr_line
		(start 263.500108 -428.079916)
		(end 263.500108 -505.000006)
		(stroke
			(width 2.54)
			(type default)
		)
		(layer "In4.Cu")
	)
	(gr_line
		(start 263.500108 -361.920028)
		(end 262.50011 -362.920026)
		(stroke
			(width 2.54)
			(type default)
		)
		(layer "In4.Cu")
	)
	(gr_arc
		(start 263.500108 -0.999998)
		(mid 263.207215 -0.29289)
		(end 262.50011 0)
		(stroke
			(width 2.54)
			(type default)
		)
		(layer "In4.Cu")
	)
	(gr_line
		(start 263.500108 -0.999998)
		(end 263.500108 -361.920028)
		(stroke
			(width 2.54)
			(type default)
		)
		(layer "In4.Cu")
	)
	(gr_line
		(start 6.290818 -104.54386)
		(end 6.294374 -104.564688)
		(stroke
			(width 0.08255)
			(type default)
		)
		(layer "In5.Cu")
	)
	(gr_line
		(start 6.290818 -104.54386)
		(end 6.294374 -104.523286)
		(stroke
			(width 0.08255)
			(type default)
		)
		(layer "In5.Cu")
	)
	(gr_line
		(start 6.294374 -104.564434)
		(end 6.294374 -104.565196)
		(stroke
			(width 0.08255)
			(type default)
		)
		(layer "In5.Cu")
	)
	(gr_line
		(start 6.348222 -105.952798)
		(end 6.434328 -106.440478)
		(stroke
			(width 0.08255)
			(type default)
		)
		(layer "In5.Cu")
	)
	(gr_line
		(start 6.348222 -105.952798)
		(end 6.498844 -105.737914)
		(stroke
			(width 0.08255)
			(type default)
		)
		(layer "In5.Cu")
	)
	(gr_line
		(start 6.434328 -106.440478)
		(end 6.649212 -106.590846)
		(stroke
			(width 0.08255)
			(type default)
		)
		(layer "In5.Cu")
	)
	(gr_line
		(start 6.585458 -107.29849)
		(end 6.671564 -107.78617)
		(stroke
			(width 0.08255)
			(type default)
		)
		(layer "In5.Cu")
	)
	(gr_line
		(start 6.585458 -107.29849)
		(end 6.73608 -107.083606)
		(stroke
			(width 0.08255)
			(type default)
		)
		(layer "In5.Cu")
	)
	(gr_line
		(start 6.671564 -107.78617)
		(end 6.886448 -107.936538)
		(stroke
			(width 0.08255)
			(type default)
		)
		(layer "In5.Cu")
	)
	(gr_line
		(start 6.73354 -107.054396)
		(end 6.738112 -107.080558)
		(stroke
			(width 0.08255)
			(type default)
		)
		(layer "In5.Cu")
	)
	(gr_line
		(start 6.858508 -105.7148)
		(end 6.995414 -106.491024)
		(stroke
			(width 0.08255)
			(type default)
		)
		(layer "In5.Cu")
	)
	(gr_line
		(start 6.992366 -447.196972)
		(end 7.145528 -447.04381)
		(stroke
			(width 0.08255)
			(type default)
		)
		(layer "In5.Cu")
	)
	(gr_line
		(start 6.992366 -446.384172)
		(end 7.145528 -446.537334)
		(stroke
			(width 0.08255)
			(type default)
		)
		(layer "In5.Cu")
	)
	(gr_line
		(start 6.992366 -443.99708)
		(end 7.145528 -443.843918)
		(stroke
			(width 0.08255)
			(type default)
		)
		(layer "In5.Cu")
	)
	(gr_line
		(start 6.992366 -443.18428)
		(end 7.145528 -443.337442)
		(stroke
			(width 0.08255)
			(type default)
		)
		(layer "In5.Cu")
	)
	(gr_line
		(start 6.992366 -440.796934)
		(end 7.145528 -440.643772)
		(stroke
			(width 0.08255)
			(type default)
		)
		(layer "In5.Cu")
	)
	(gr_line
		(start 6.992366 -439.984134)
		(end 7.145528 -440.137296)
		(stroke
			(width 0.08255)
			(type default)
		)
		(layer "In5.Cu")
	)
	(gr_line
		(start 6.992366 -437.597042)
		(end 7.145528 -437.44388)
		(stroke
			(width 0.08255)
			(type default)
		)
		(layer "In5.Cu")
	)
	(gr_line
		(start 6.992366 -436.784242)
		(end 7.145528 -436.937404)
		(stroke
			(width 0.08255)
			(type default)
		)
		(layer "In5.Cu")
	)
	(gr_line
		(start 6.992366 -431.997104)
		(end 7.145528 -431.843942)
		(stroke
			(width 0.08255)
			(type default)
		)
		(layer "In5.Cu")
	)
	(gr_line
		(start 6.992366 -431.184304)
		(end 7.145528 -431.337466)
		(stroke
			(width 0.08255)
			(type default)
		)
		(layer "In5.Cu")
	)
	(gr_line
		(start 6.992366 -428.796958)
		(end 7.145528 -428.643796)
		(stroke
			(width 0.08255)
			(type default)
		)
		(layer "In5.Cu")
	)
	(gr_line
		(start 6.992366 -427.984158)
		(end 7.145528 -428.13732)
		(stroke
			(width 0.08255)
			(type default)
		)
		(layer "In5.Cu")
	)
	(gr_line
		(start 6.992366 -425.597066)
		(end 7.145528 -425.443904)
		(stroke
			(width 0.08255)
			(type default)
		)
		(layer "In5.Cu")
	)
	(gr_line
		(start 6.992366 -424.784266)
		(end 7.145528 -424.937428)
		(stroke
			(width 0.08255)
			(type default)
		)
		(layer "In5.Cu")
	)
	(gr_line
		(start 6.992366 -415.948622)
		(end 7.145528 -415.79546)
		(stroke
			(width 0.08255)
			(type default)
		)
		(layer "In5.Cu")
	)
	(gr_line
		(start 6.992366 -415.135822)
		(end 7.145528 -415.288984)
		(stroke
			(width 0.08255)
			(type default)
		)
		(layer "In5.Cu")
	)
	(gr_line
		(start 6.992366 -412.748476)
		(end 7.145528 -412.595314)
		(stroke
			(width 0.08255)
			(type default)
		)
		(layer "In5.Cu")
	)
	(gr_line
		(start 6.992366 -411.935676)
		(end 7.145528 -412.088838)
		(stroke
			(width 0.08255)
			(type default)
		)
		(layer "In5.Cu")
	)
	(gr_line
		(start 6.992366 -409.548584)
		(end 7.145528 -409.395422)
		(stroke
			(width 0.08255)
			(type default)
		)
		(layer "In5.Cu")
	)
	(gr_line
		(start 6.992366 -408.735784)
		(end 7.145528 -408.888946)
		(stroke
			(width 0.08255)
			(type default)
		)
		(layer "In5.Cu")
	)
	(gr_line
		(start 6.992366 -406.348438)
		(end 7.145528 -406.195276)
		(stroke
			(width 0.08255)
			(type default)
		)
		(layer "In5.Cu")
	)
	(gr_line
		(start 6.992366 -405.535638)
		(end 7.145528 -405.6888)
		(stroke
			(width 0.08255)
			(type default)
		)
		(layer "In5.Cu")
	)
	(gr_line
		(start 6.992366 -403.148546)
		(end 7.145528 -402.995384)
		(stroke
			(width 0.08255)
			(type default)
		)
		(layer "In5.Cu")
	)
	(gr_line
		(start 6.992366 -402.335746)
		(end 7.145528 -402.488908)
		(stroke
			(width 0.08255)
			(type default)
		)
		(layer "In5.Cu")
	)
	(gr_line
		(start 6.992366 -397.548608)
		(end 7.145528 -397.395446)
		(stroke
			(width 0.08255)
			(type default)
		)
		(layer "In5.Cu")
	)
	(gr_line
		(start 6.992366 -396.735808)
		(end 7.145528 -396.88897)
		(stroke
			(width 0.08255)
			(type default)
		)
		(layer "In5.Cu")
	)
	(gr_line
		(start 6.992366 -394.348462)
		(end 7.145528 -394.1953)
		(stroke
			(width 0.08255)
			(type default)
		)
		(layer "In5.Cu")
	)
	(gr_line
		(start 6.992366 -393.535662)
		(end 7.145528 -393.688824)
		(stroke
			(width 0.08255)
			(type default)
		)
		(layer "In5.Cu")
	)
	(gr_line
		(start 6.992366 -391.14857)
		(end 7.145528 -390.995408)
		(stroke
			(width 0.08255)
			(type default)
		)
		(layer "In5.Cu")
	)
	(gr_line
		(start 6.992366 -390.33577)
		(end 7.145528 -390.488932)
		(stroke
			(width 0.08255)
			(type default)
		)
		(layer "In5.Cu")
	)
	(gr_line
		(start 6.992366 -387.948424)
		(end 7.145528 -387.795262)
		(stroke
			(width 0.08255)
			(type default)
		)
		(layer "In5.Cu")
	)
	(gr_line
		(start 6.992366 -387.135624)
		(end 7.145528 -387.288786)
		(stroke
			(width 0.08255)
			(type default)
		)
		(layer "In5.Cu")
	)
	(gr_line
		(start 6.992366 -357.148638)
		(end 7.145528 -356.995476)
		(stroke
			(width 0.08255)
			(type default)
		)
		(layer "In5.Cu")
	)
	(gr_line
		(start 6.992366 -356.335838)
		(end 7.145528 -356.489)
		(stroke
			(width 0.08255)
			(type default)
		)
		(layer "In5.Cu")
	)
	(gr_line
		(start 6.992366 -353.948746)
		(end 7.145528 -353.795584)
		(stroke
			(width 0.08255)
			(type default)
		)
		(layer "In5.Cu")
	)
	(gr_line
		(start 6.992366 -353.135946)
		(end 7.145528 -353.289108)
		(stroke
			(width 0.08255)
			(type default)
		)
		(layer "In5.Cu")
	)
	(gr_line
		(start 6.992366 -350.7486)
		(end 7.145528 -350.595438)
		(stroke
			(width 0.08255)
			(type default)
		)
		(layer "In5.Cu")
	)
	(gr_line
		(start 6.992366 -349.9358)
		(end 7.145528 -350.088962)
		(stroke
			(width 0.08255)
			(type default)
		)
		(layer "In5.Cu")
	)
	(gr_line
		(start 6.992366 -347.548708)
		(end 7.145528 -347.395546)
		(stroke
			(width 0.08255)
			(type default)
		)
		(layer "In5.Cu")
	)
	(gr_line
		(start 6.992366 -346.735908)
		(end 7.145528 -346.88907)
		(stroke
			(width 0.08255)
			(type default)
		)
		(layer "In5.Cu")
	)
	(gr_line
		(start 6.992366 -344.399616)
		(end 7.145528 -344.246454)
		(stroke
			(width 0.08255)
			(type default)
		)
		(layer "In5.Cu")
	)
	(gr_line
		(start 6.992366 -343.586816)
		(end 7.145528 -343.739978)
		(stroke
			(width 0.08255)
			(type default)
		)
		(layer "In5.Cu")
	)
	(gr_line
		(start 6.992366 -341.19947)
		(end 7.145528 -341.046308)
		(stroke
			(width 0.08255)
			(type default)
		)
		(layer "In5.Cu")
	)
	(gr_line
		(start 6.992366 -340.38667)
		(end 7.145528 -340.539832)
		(stroke
			(width 0.08255)
			(type default)
		)
		(layer "In5.Cu")
	)
	(gr_line
		(start 6.992366 -337.999578)
		(end 7.145528 -337.846416)
		(stroke
			(width 0.08255)
			(type default)
		)
		(layer "In5.Cu")
	)
	(gr_line
		(start 6.992366 -337.186778)
		(end 7.145528 -337.33994)
		(stroke
			(width 0.08255)
			(type default)
		)
		(layer "In5.Cu")
	)
	(gr_line
		(start 6.992366 -334.799432)
		(end 7.145528 -334.64627)
		(stroke
			(width 0.08255)
			(type default)
		)
		(layer "In5.Cu")
	)
	(gr_line
		(start 6.992366 -333.986632)
		(end 7.145528 -334.139794)
		(stroke
			(width 0.08255)
			(type default)
		)
		(layer "In5.Cu")
	)
	(gr_line
		(start 6.992366 -329.148694)
		(end 7.145528 -328.995532)
		(stroke
			(width 0.08255)
			(type default)
		)
		(layer "In5.Cu")
	)
	(gr_line
		(start 6.992366 -328.335894)
		(end 7.145528 -328.489056)
		(stroke
			(width 0.08255)
			(type default)
		)
		(layer "In5.Cu")
	)
	(gr_line
		(start 6.992366 -325.948802)
		(end 7.145528 -325.79564)
		(stroke
			(width 0.08255)
			(type default)
		)
		(layer "In5.Cu")
	)
	(gr_line
		(start 6.992366 -325.136002)
		(end 7.145528 -325.289164)
		(stroke
			(width 0.08255)
			(type default)
		)
		(layer "In5.Cu")
	)
	(gr_line
		(start 6.992366 -322.748656)
		(end 7.145528 -322.595494)
		(stroke
			(width 0.08255)
			(type default)
		)
		(layer "In5.Cu")
	)
	(gr_line
		(start 6.992366 -321.935856)
		(end 7.145528 -322.089018)
		(stroke
			(width 0.08255)
			(type default)
		)
		(layer "In5.Cu")
	)
	(gr_line
		(start 6.992366 -319.548764)
		(end 7.145528 -319.395602)
		(stroke
			(width 0.08255)
			(type default)
		)
		(layer "In5.Cu")
	)
	(gr_line
		(start 6.992366 -318.735964)
		(end 7.145528 -318.889126)
		(stroke
			(width 0.08255)
			(type default)
		)
		(layer "In5.Cu")
	)
	(gr_line
		(start 6.992366 -311.54878)
		(end 7.145528 -311.395618)
		(stroke
			(width 0.08255)
			(type default)
		)
		(layer "In5.Cu")
	)
	(gr_line
		(start 6.992366 -310.73598)
		(end 7.145528 -310.889142)
		(stroke
			(width 0.08255)
			(type default)
		)
		(layer "In5.Cu")
	)
	(gr_line
		(start 6.992366 -308.348634)
		(end 7.145528 -308.195472)
		(stroke
			(width 0.08255)
			(type default)
		)
		(layer "In5.Cu")
	)
	(gr_line
		(start 6.992366 -307.535834)
		(end 7.145528 -307.688996)
		(stroke
			(width 0.08255)
			(type default)
		)
		(layer "In5.Cu")
	)
	(gr_line
		(start 6.992366 -305.148742)
		(end 7.145528 -304.99558)
		(stroke
			(width 0.08255)
			(type default)
		)
		(layer "In5.Cu")
	)
	(gr_line
		(start 6.992366 -304.335942)
		(end 7.145528 -304.489104)
		(stroke
			(width 0.08255)
			(type default)
		)
		(layer "In5.Cu")
	)
	(gr_line
		(start 6.992366 -301.948596)
		(end 7.145528 -301.795434)
		(stroke
			(width 0.08255)
			(type default)
		)
		(layer "In5.Cu")
	)
	(gr_line
		(start 6.992366 -301.135796)
		(end 7.145528 -301.288958)
		(stroke
			(width 0.08255)
			(type default)
		)
		(layer "In5.Cu")
	)
	(gr_line
		(start 6.992366 -298.748704)
		(end 7.145528 -298.595542)
		(stroke
			(width 0.08255)
			(type default)
		)
		(layer "In5.Cu")
	)
	(gr_line
		(start 6.992366 -297.935904)
		(end 7.145528 -298.089066)
		(stroke
			(width 0.08255)
			(type default)
		)
		(layer "In5.Cu")
	)
	(gr_line
		(start 6.992366 -295.548812)
		(end 7.145528 -295.39565)
		(stroke
			(width 0.08255)
			(type default)
		)
		(layer "In5.Cu")
	)
	(gr_line
		(start 6.992366 -294.736012)
		(end 7.145528 -294.889174)
		(stroke
			(width 0.08255)
			(type default)
		)
		(layer "In5.Cu")
	)
	(gr_line
		(start 6.992366 -292.348666)
		(end 7.145528 -292.195504)
		(stroke
			(width 0.08255)
			(type default)
		)
		(layer "In5.Cu")
	)
	(gr_line
		(start 6.992366 -291.535866)
		(end 7.145528 -291.689028)
		(stroke
			(width 0.08255)
			(type default)
		)
		(layer "In5.Cu")
	)
	(gr_line
		(start 6.992366 -289.148774)
		(end 7.145528 -288.995612)
		(stroke
			(width 0.08255)
			(type default)
		)
		(layer "In5.Cu")
	)
	(gr_line
		(start 6.992366 -288.335974)
		(end 7.145528 -288.489136)
		(stroke
			(width 0.08255)
			(type default)
		)
		(layer "In5.Cu")
	)
	(gr_line
		(start 6.992366 -282.799536)
		(end 7.145528 -282.646374)
		(stroke
			(width 0.08255)
			(type default)
		)
		(layer "In5.Cu")
	)
	(gr_line
		(start 6.992366 -281.986736)
		(end 7.145528 -282.139898)
		(stroke
			(width 0.08255)
			(type default)
		)
		(layer "In5.Cu")
	)
	(gr_line
		(start 6.992366 -279.59939)
		(end 7.145528 -279.446228)
		(stroke
			(width 0.08255)
			(type default)
		)
		(layer "In5.Cu")
	)
	(gr_line
		(start 6.992366 -278.78659)
		(end 7.145528 -278.939752)
		(stroke
			(width 0.08255)
			(type default)
		)
		(layer "In5.Cu")
	)
	(gr_line
		(start 6.992366 -231.148636)
		(end 7.145528 -230.995474)
		(stroke
			(width 0.08255)
			(type default)
		)
		(layer "In5.Cu")
	)
	(gr_line
		(start 6.992366 -230.335836)
		(end 7.145528 -230.488998)
		(stroke
			(width 0.08255)
			(type default)
		)
		(layer "In5.Cu")
	)
	(gr_line
		(start 6.992366 -227.948744)
		(end 7.145528 -227.795582)
		(stroke
			(width 0.08255)
			(type default)
		)
		(layer "In5.Cu")
	)
	(gr_line
		(start 6.992366 -227.135944)
		(end 7.145528 -227.289106)
		(stroke
			(width 0.08255)
			(type default)
		)
		(layer "In5.Cu")
	)
	(gr_line
		(start 6.992366 -224.710498)
		(end 7.145528 -224.557336)
		(stroke
			(width 0.08255)
			(type default)
		)
		(layer "In5.Cu")
	)
	(gr_line
		(start 6.992366 -223.897698)
		(end 7.145528 -224.05086)
		(stroke
			(width 0.08255)
			(type default)
		)
		(layer "In5.Cu")
	)
	(gr_line
		(start 6.992366 -221.497906)
		(end 7.145528 -221.344744)
		(stroke
			(width 0.08255)
			(type default)
		)
		(layer "In5.Cu")
	)
	(gr_line
		(start 6.992366 -220.685106)
		(end 7.145528 -220.838268)
		(stroke
			(width 0.08255)
			(type default)
		)
		(layer "In5.Cu")
	)
	(gr_line
		(start 6.992366 -218.298014)
		(end 7.145528 -218.144852)
		(stroke
			(width 0.08255)
			(type default)
		)
		(layer "In5.Cu")
	)
	(gr_line
		(start 6.992366 -217.485214)
		(end 7.145528 -217.638376)
		(stroke
			(width 0.08255)
			(type default)
		)
		(layer "In5.Cu")
	)
	(gr_line
		(start 6.992366 -215.097868)
		(end 7.145528 -214.944706)
		(stroke
			(width 0.08255)
			(type default)
		)
		(layer "In5.Cu")
	)
	(gr_line
		(start 6.992366 -214.285068)
		(end 7.145528 -214.43823)
		(stroke
			(width 0.08255)
			(type default)
		)
		(layer "In5.Cu")
	)
	(gr_line
		(start 6.992366 -211.948776)
		(end 7.145528 -211.795614)
		(stroke
			(width 0.08255)
			(type default)
		)
		(layer "In5.Cu")
	)
	(gr_line
		(start 6.992366 -211.135976)
		(end 7.145528 -211.289138)
		(stroke
			(width 0.08255)
			(type default)
		)
		(layer "In5.Cu")
	)
	(gr_line
		(start 6.992366 -208.74863)
		(end 7.145528 -208.595468)
		(stroke
			(width 0.08255)
			(type default)
		)
		(layer "In5.Cu")
	)
	(gr_line
		(start 6.992366 -207.93583)
		(end 7.145528 -208.088992)
		(stroke
			(width 0.08255)
			(type default)
		)
		(layer "In5.Cu")
	)
	(gr_line
		(start 6.992366 -205.548738)
		(end 7.145528 -205.395576)
		(stroke
			(width 0.08255)
			(type default)
		)
		(layer "In5.Cu")
	)
	(gr_line
		(start 6.992366 -204.735938)
		(end 7.145528 -204.8891)
		(stroke
			(width 0.08255)
			(type default)
		)
		(layer "In5.Cu")
	)
	(gr_line
		(start 6.992366 -202.348592)
		(end 7.145528 -202.19543)
		(stroke
			(width 0.08255)
			(type default)
		)
		(layer "In5.Cu")
	)
	(gr_line
		(start 6.992366 -201.535792)
		(end 7.145528 -201.688954)
		(stroke
			(width 0.08255)
			(type default)
		)
		(layer "In5.Cu")
	)
	(gr_line
		(start 6.992366 -196.748654)
		(end 7.145528 -196.595492)
		(stroke
			(width 0.08255)
			(type default)
		)
		(layer "In5.Cu")
	)
	(gr_line
		(start 6.992366 -195.935854)
		(end 7.145528 -196.089016)
		(stroke
			(width 0.08255)
			(type default)
		)
		(layer "In5.Cu")
	)
	(gr_line
		(start 6.992366 -193.548762)
		(end 7.145528 -193.3956)
		(stroke
			(width 0.08255)
			(type default)
		)
		(layer "In5.Cu")
	)
	(gr_line
		(start 6.992366 -192.735962)
		(end 7.145528 -192.889124)
		(stroke
			(width 0.08255)
			(type default)
		)
		(layer "In5.Cu")
	)
	(gr_line
		(start 6.992366 -185.548778)
		(end 7.145528 -185.395616)
		(stroke
			(width 0.08255)
			(type default)
		)
		(layer "In5.Cu")
	)
	(gr_line
		(start 6.992366 -184.735978)
		(end 7.145528 -184.88914)
		(stroke
			(width 0.08255)
			(type default)
		)
		(layer "In5.Cu")
	)
	(gr_line
		(start 6.992366 -182.348632)
		(end 7.145528 -182.19547)
		(stroke
			(width 0.08255)
			(type default)
		)
		(layer "In5.Cu")
	)
	(gr_line
		(start 6.992366 -181.535832)
		(end 7.145528 -181.688994)
		(stroke
			(width 0.08255)
			(type default)
		)
		(layer "In5.Cu")
	)
	(gr_line
		(start 6.992366 -179.19954)
		(end 7.145528 -179.046378)
		(stroke
			(width 0.08255)
			(type default)
		)
		(layer "In5.Cu")
	)
	(gr_line
		(start 6.992366 -178.38674)
		(end 7.145528 -178.539902)
		(stroke
			(width 0.08255)
			(type default)
		)
		(layer "In5.Cu")
	)
	(gr_line
		(start 6.992366 -175.999394)
		(end 7.145528 -175.846232)
		(stroke
			(width 0.08255)
			(type default)
		)
		(layer "In5.Cu")
	)
	(gr_line
		(start 6.992366 -175.186594)
		(end 7.145528 -175.339756)
		(stroke
			(width 0.08255)
			(type default)
		)
		(layer "In5.Cu")
	)
	(gr_line
		(start 6.992366 -172.799502)
		(end 7.145528 -172.64634)
		(stroke
			(width 0.08255)
			(type default)
		)
		(layer "In5.Cu")
	)
	(gr_line
		(start 6.992366 -171.986702)
		(end 7.145528 -172.139864)
		(stroke
			(width 0.08255)
			(type default)
		)
		(layer "In5.Cu")
	)
	(gr_line
		(start 6.992366 -169.59961)
		(end 7.145528 -169.446448)
		(stroke
			(width 0.08255)
			(type default)
		)
		(layer "In5.Cu")
	)
	(gr_line
		(start 6.992366 -168.78681)
		(end 7.145528 -168.939972)
		(stroke
			(width 0.08255)
			(type default)
		)
		(layer "In5.Cu")
	)
	(gr_line
		(start 6.992366 -163.199572)
		(end 7.145528 -163.04641)
		(stroke
			(width 0.08255)
			(type default)
		)
		(layer "In5.Cu")
	)
	(gr_line
		(start 6.992366 -162.386772)
		(end 7.145528 -162.539934)
		(stroke
			(width 0.08255)
			(type default)
		)
		(layer "In5.Cu")
	)
	(gr_line
		(start 6.992366 -159.999426)
		(end 7.145528 -159.846264)
		(stroke
			(width 0.08255)
			(type default)
		)
		(layer "In5.Cu")
	)
	(gr_line
		(start 6.992366 -159.186626)
		(end 7.145528 -159.339788)
		(stroke
			(width 0.08255)
			(type default)
		)
		(layer "In5.Cu")
	)
	(gr_line
		(start 6.992366 -156.786834)
		(end 7.145528 -156.633672)
		(stroke
			(width 0.08255)
			(type default)
		)
		(layer "In5.Cu")
	)
	(gr_line
		(start 6.992366 -155.974034)
		(end 7.145528 -156.127196)
		(stroke
			(width 0.08255)
			(type default)
		)
		(layer "In5.Cu")
	)
	(gr_line
		(start 6.992366 -153.599388)
		(end 7.145528 -153.446226)
		(stroke
			(width 0.08255)
			(type default)
		)
		(layer "In5.Cu")
	)
	(gr_line
		(start 6.992366 -152.786588)
		(end 7.145528 -152.93975)
		(stroke
			(width 0.08255)
			(type default)
		)
		(layer "In5.Cu")
	)
	(gr_line
		(start 7.083552 -106.992674)
		(end 7.089648 -107.026456)
		(stroke
			(width 0.08255)
			(type default)
		)
		(layer "In5.Cu")
	)
	(gr_line
		(start 7.095744 -107.061)
		(end 7.232396 -107.835954)
		(stroke
			(width 0.08255)
			(type default)
		)
		(layer "In5.Cu")
	)
	(gr_line
		(start 7.79907 -107.691428)
		(end 7.802626 -107.712256)
		(stroke
			(width 0.08255)
			(type default)
		)
		(layer "In5.Cu")
	)
	(gr_line
		(start 7.79907 -107.691428)
		(end 7.802626 -107.670854)
		(stroke
			(width 0.08255)
			(type default)
		)
		(layer "In5.Cu")
	)
	(gr_line
		(start 7.802626 -107.712002)
		(end 7.802626 -107.712764)
		(stroke
			(width 0.08255)
			(type default)
		)
		(layer "In5.Cu")
	)
	(gr_line
		(start 7.812786 -159.691578)
		(end 7.848854 -159.685228)
		(stroke
			(width 0.08255)
			(type default)
		)
		(layer "In5.Cu")
	)
	(gr_line
		(start 7.821422 -172.126402)
		(end 7.972044 -171.911518)
		(stroke
			(width 0.08255)
			(type default)
		)
		(layer "In5.Cu")
	)
	(gr_line
		(start 7.82193 -175.326294)
		(end 7.972298 -175.11141)
		(stroke
			(width 0.08255)
			(type default)
		)
		(layer "In5.Cu")
	)
	(gr_line
		(start 7.848854 -159.685228)
		(end 7.87908 -159.664146)
		(stroke
			(width 0.08255)
			(type default)
		)
		(layer "In5.Cu")
	)
	(gr_line
		(start 7.922006 -172.47235)
		(end 8.69696 -172.335698)
		(stroke
			(width 0.08255)
			(type default)
		)
		(layer "In5.Cu")
	)
	(gr_line
		(start 7.922768 -175.672242)
		(end 8.698484 -175.535336)
		(stroke
			(width 0.08255)
			(type default)
		)
		(layer "In5.Cu")
	)
	(gr_line
		(start 7.930642 -415.364422)
		(end 7.987792 -415.4043)
		(stroke
			(width 0.08255)
			(type default)
		)
		(layer "In5.Cu")
	)
	(gr_line
		(start 7.94639 -397.377412)
		(end 7.976362 -397.382746)
		(stroke
			(width 0.08255)
			(type default)
		)
		(layer "In5.Cu")
	)
	(gr_line
		(start 7.972044 -171.911518)
		(end 8.459724 -171.825666)
		(stroke
			(width 0.08255)
			(type default)
		)
		(layer "In5.Cu")
	)
	(gr_line
		(start 7.972298 -175.11141)
		(end 8.460232 -175.025304)
		(stroke
			(width 0.08255)
			(type default)
		)
		(layer "In5.Cu")
	)
	(gr_line
		(start 7.976362 -397.382746)
		(end 8.109458 -397.406114)
		(stroke
			(width 0.08255)
			(type default)
		)
		(layer "In5.Cu")
	)
	(gr_line
		(start 7.998714 -440.225434)
		(end 8.034782 -440.231784)
		(stroke
			(width 0.08255)
			(type default)
		)
		(layer "In5.Cu")
	)
	(gr_line
		(start 8.03402 -397.031718)
		(end 8.17118 -397.056102)
		(stroke
			(width 0.08255)
			(type default)
		)
		(layer "In5.Cu")
	)
	(gr_line
		(start 8.034782 -440.231784)
		(end 8.065008 -440.252866)
		(stroke
			(width 0.08255)
			(type default)
		)
		(layer "In5.Cu")
	)
	(gr_line
		(start 8.115808 -159.06115)
		(end 8.161274 -158.802832)
		(stroke
			(width 0.08255)
			(type default)
		)
		(layer "In5.Cu")
	)
	(gr_line
		(start 8.129778 -393.84859)
		(end 8.165846 -393.85494)
		(stroke
			(width 0.08255)
			(type default)
		)
		(layer "In5.Cu")
	)
	(gr_line
		(start 8.133588 -446.649094)
		(end 8.170672 -446.655698)
		(stroke
			(width 0.08255)
			(type default)
		)
		(layer "In5.Cu")
	)
	(gr_line
		(start 8.139684 -443.450472)
		(end 8.175498 -443.456822)
		(stroke
			(width 0.08255)
			(type default)
		)
		(layer "In5.Cu")
	)
	(gr_line
		(start 8.161274 -158.802832)
		(end 8.567166 -158.51886)
		(stroke
			(width 0.08255)
			(type default)
		)
		(layer "In5.Cu")
	)
	(gr_line
		(start 8.165846 -393.85494)
		(end 8.196072 -393.876022)
		(stroke
			(width 0.08255)
			(type default)
		)
		(layer "In5.Cu")
	)
	(gr_line
		(start 8.170672 -446.655698)
		(end 8.200898 -446.67678)
		(stroke
			(width 0.08255)
			(type default)
		)
		(layer "In5.Cu")
	)
	(gr_line
		(start 8.175498 -443.456822)
		(end 8.205724 -443.477904)
		(stroke
			(width 0.08255)
			(type default)
		)
		(layer "In5.Cu")
	)
	(gr_line
		(start 8.210296 -328.465942)
		(end 8.21055 -328.465942)
		(stroke
			(width 0.08255)
			(type default)
		)
		(layer "In5.Cu")
	)
	(gr_line
		(start 8.305038 -387.47954)
		(end 8.340852 -387.48589)
		(stroke
			(width 0.08255)
			(type default)
		)
		(layer "In5.Cu")
	)
	(gr_line
		(start 8.314182 -328.808842)
		(end 8.349742 -328.802492)
		(stroke
			(width 0.08255)
			(type default)
		)
		(layer "In5.Cu")
	)
	(gr_line
		(start 8.340852 -387.48589)
		(end 8.371078 -387.506972)
		(stroke
			(width 0.08255)
			(type default)
		)
		(layer "In5.Cu")
	)
	(gr_line
		(start 8.349742 -328.802492)
		(end 8.35025 -328.802492)
		(stroke
			(width 0.08255)
			(type default)
		)
		(layer "In5.Cu")
	)
	(gr_line
		(start 8.35025 -328.802492)
		(end 8.360664 -328.795126)
		(stroke
			(width 0.08255)
			(type default)
		)
		(layer "In5.Cu")
	)
	(gr_line
		(start 8.354822 -159.331152)
		(end 8.997442 -158.881064)
		(stroke
			(width 0.08255)
			(type default)
		)
		(layer "In5.Cu")
	)
	(gr_line
		(start 8.360664 -328.795126)
		(end 8.38073 -328.781156)
		(stroke
			(width 0.08255)
			(type default)
		)
		(layer "In5.Cu")
	)
	(gr_line
		(start 8.36803 -153.193496)
		(end 8.403844 -153.187146)
		(stroke
			(width 0.08255)
			(type default)
		)
		(layer "In5.Cu")
	)
	(gr_line
		(start 8.377428 -415.676588)
		(end 8.39597 -415.689542)
		(stroke
			(width 0.08255)
			(type default)
		)
		(layer "In5.Cu")
	)
	(gr_line
		(start 8.382 -227.487734)
		(end 8.418068 -227.494084)
		(stroke
			(width 0.08255)
			(type default)
		)
		(layer "In5.Cu")
	)
	(gr_line
		(start 8.38708 -322.396104)
		(end 8.423148 -322.389754)
		(stroke
			(width 0.08255)
			(type default)
		)
		(layer "In5.Cu")
	)
	(gr_line
		(start 8.389874 -211.595462)
		(end 8.425942 -211.589112)
		(stroke
			(width 0.08255)
			(type default)
		)
		(layer "In5.Cu")
	)
	(gr_line
		(start 8.39597 -415.689542)
		(end 8.408162 -415.707068)
		(stroke
			(width 0.08255)
			(type default)
		)
		(layer "In5.Cu")
	)
	(gr_line
		(start 8.39978 -230.690928)
		(end 8.435594 -230.697278)
		(stroke
			(width 0.08255)
			(type default)
		)
		(layer "In5.Cu")
	)
	(gr_line
		(start 8.403844 -153.187146)
		(end 8.43407 -153.166064)
		(stroke
			(width 0.08255)
			(type default)
		)
		(layer "In5.Cu")
	)
	(gr_line
		(start 8.405876 -319.192656)
		(end 8.441944 -319.186306)
		(stroke
			(width 0.08255)
			(type default)
		)
		(layer "In5.Cu")
	)
	(gr_line
		(start 8.418068 -227.494084)
		(end 8.448294 -227.515166)
		(stroke
			(width 0.08255)
			(type default)
		)
		(layer "In5.Cu")
	)
	(gr_line
		(start 8.423148 -322.389754)
		(end 8.453374 -322.368672)
		(stroke
			(width 0.08255)
			(type default)
		)
		(layer "In5.Cu")
	)
	(gr_line
		(start 8.425942 -211.589112)
		(end 8.456168 -211.56803)
		(stroke
			(width 0.08255)
			(type default)
		)
		(layer "In5.Cu")
	)
	(gr_line
		(start 8.435594 -230.697278)
		(end 8.46582 -230.71836)
		(stroke
			(width 0.08255)
			(type default)
		)
		(layer "In5.Cu")
	)
	(gr_line
		(start 8.436864 -397.102838)
		(end 8.472932 -397.109188)
		(stroke
			(width 0.08255)
			(type default)
		)
		(layer "In5.Cu")
	)
	(gr_line
		(start 8.441944 -319.186306)
		(end 8.47217 -319.165224)
		(stroke
			(width 0.08255)
			(type default)
		)
		(layer "In5.Cu")
	)
	(gr_line
		(start 8.4455 -390.704324)
		(end 8.481568 -390.710674)
		(stroke
			(width 0.08255)
			(type default)
		)
		(layer "In5.Cu")
	)
	(gr_line
		(start 8.459724 -171.825666)
		(end 8.674608 -171.976034)
		(stroke
			(width 0.08255)
			(type default)
		)
		(layer "In5.Cu")
	)
	(gr_line
		(start 8.460232 -175.025304)
		(end 8.675116 -175.175672)
		(stroke
			(width 0.08255)
			(type default)
		)
		(layer "In5.Cu")
	)
	(gr_line
		(start 8.472932 -397.109188)
		(end 8.503158 -397.13027)
		(stroke
			(width 0.08255)
			(type default)
		)
		(layer "In5.Cu")
	)
	(gr_line
		(start 8.475726 -446.868804)
		(end 8.493506 -446.88125)
		(stroke
			(width 0.08255)
			(type default)
		)
		(layer "In5.Cu")
	)
	(gr_line
		(start 8.481568 -390.710674)
		(end 8.511794 -390.731756)
		(stroke
			(width 0.08255)
			(type default)
		)
		(layer "In5.Cu")
	)
	(gr_line
		(start 8.493506 -446.88125)
		(end 8.506206 -446.899538)
		(stroke
			(width 0.08255)
			(type default)
		)
		(layer "In5.Cu")
	)
	(gr_line
		(start 8.509508 -437.138064)
		(end 8.545576 -437.144414)
		(stroke
			(width 0.08255)
			(type default)
		)
		(layer "In5.Cu")
	)
	(gr_line
		(start 8.544052 -347.1164)
		(end 8.579866 -347.12275)
		(stroke
			(width 0.08255)
			(type default)
		)
		(layer "In5.Cu")
	)
	(gr_line
		(start 8.545576 -437.144414)
		(end 8.57504 -437.165242)
		(stroke
			(width 0.08255)
			(type default)
		)
		(layer "In5.Cu")
	)
	(gr_line
		(start 8.567166 -158.51886)
		(end 8.825738 -158.56458)
		(stroke
			(width 0.08255)
			(type default)
		)
		(layer "In5.Cu")
	)
	(gr_line
		(start 8.579866 -347.12275)
		(end 8.6106 -347.144086)
		(stroke
			(width 0.08255)
			(type default)
		)
		(layer "In5.Cu")
	)
	(gr_line
		(start 8.631936 -208.352644)
		(end 8.668004 -208.346294)
		(stroke
			(width 0.08255)
			(type default)
		)
		(layer "In5.Cu")
	)
	(gr_line
		(start 8.642604 -304.750978)
		(end 8.678672 -304.744628)
		(stroke
			(width 0.08255)
			(type default)
		)
		(layer "In5.Cu")
	)
	(gr_line
		(start 8.659876 -325.54799)
		(end 8.695944 -325.54164)
		(stroke
			(width 0.08255)
			(type default)
		)
		(layer "In5.Cu")
	)
	(gr_line
		(start 8.66775 -431.546508)
		(end 8.703818 -431.552858)
		(stroke
			(width 0.08255)
			(type default)
		)
		(layer "In5.Cu")
	)
	(gr_line
		(start 8.668004 -208.346294)
		(end 8.69823 -208.325212)
		(stroke
			(width 0.08255)
			(type default)
		)
		(layer "In5.Cu")
	)
	(gr_line
		(start 8.678672 -304.744628)
		(end 8.708898 -304.723546)
		(stroke
			(width 0.08255)
			(type default)
		)
		(layer "In5.Cu")
	)
	(gr_line
		(start 8.681974 -343.951814)
		(end 8.718042 -343.958164)
		(stroke
			(width 0.08255)
			(type default)
		)
		(layer "In5.Cu")
	)
	(gr_line
		(start 8.695944 -325.54164)
		(end 8.699246 -325.54164)
		(stroke
			(width 0.08255)
			(type default)
		)
		(layer "In5.Cu")
	)
	(gr_line
		(start 8.699246 -325.54164)
		(end 8.706866 -325.53402)
		(stroke
			(width 0.08255)
			(type default)
		)
		(layer "In5.Cu")
	)
	(gr_line
		(start 8.703818 -431.552858)
		(end 8.734044 -431.57394)
		(stroke
			(width 0.08255)
			(type default)
		)
		(layer "In5.Cu")
	)
	(gr_line
		(start 8.706866 -325.53402)
		(end 8.72617 -325.520558)
		(stroke
			(width 0.08255)
			(type default)
		)
		(layer "In5.Cu")
	)
	(gr_line
		(start 8.715248 -214.68715)
		(end 8.752078 -214.680546)
		(stroke
			(width 0.08255)
			(type default)
		)
		(layer "In5.Cu")
	)
	(gr_line
		(start 8.718042 -343.958164)
		(end 8.748268 -343.979246)
		(stroke
			(width 0.08255)
			(type default)
		)
		(layer "In5.Cu")
	)
	(gr_line
		(start 8.752078 -214.680546)
		(end 8.782304 -214.65921)
		(stroke
			(width 0.08255)
			(type default)
		)
		(layer "In5.Cu")
	)
	(gr_line
		(start 8.757158 -156.369004)
		(end 8.794496 -156.362654)
		(stroke
			(width 0.08255)
			(type default)
		)
		(layer "In5.Cu")
	)
	(gr_line
		(start 8.794496 -156.362654)
		(end 8.826246 -156.340556)
		(stroke
			(width 0.08255)
			(type default)
		)
		(layer "In5.Cu")
	)
	(gr_line
		(start 8.826754 -440.785758)
		(end 8.845042 -440.798712)
		(stroke
			(width 0.08255)
			(type default)
		)
		(layer "In5.Cu")
	)
	(gr_line
		(start 8.836406 -428.373286)
		(end 8.87222 -428.379636)
		(stroke
			(width 0.08255)
			(type default)
		)
		(layer "In5.Cu")
	)
	(gr_line
		(start 8.839708 -162.710622)
		(end 8.875776 -162.704272)
		(stroke
			(width 0.08255)
			(type default)
		)
		(layer "In5.Cu")
	)
	(gr_line
		(start 8.845042 -440.798712)
		(end 8.857742 -440.817)
		(stroke
			(width 0.08255)
			(type default)
		)
		(layer "In5.Cu")
	)
	(gr_line
		(start 8.87222 -428.379636)
		(end 8.902446 -428.400718)
		(stroke
			(width 0.08255)
			(type default)
		)
		(layer "In5.Cu")
	)
	(gr_line
		(start 8.875776 -162.704272)
		(end 8.906002 -162.68319)
		(stroke
			(width 0.08255)
			(type default)
		)
		(layer "In5.Cu")
	)
	(gr_line
		(start 8.915908 -311.10301)
		(end 8.951976 -311.09666)
		(stroke
			(width 0.08255)
			(type default)
		)
		(layer "In5.Cu")
	)
	(gr_line
		(start 8.927846 -353.584002)
		(end 8.96366 -353.590352)
		(stroke
			(width 0.08255)
			(type default)
		)
		(layer "In5.Cu")
	)
	(gr_line
		(start 8.93572 -347.80601)
		(end 8.93572 -347.806264)
		(stroke
			(width 0.08255)
			(type default)
		)
		(layer "In5.Cu")
	)
	(gr_line
		(start 8.93572 -347.80601)
		(end 8.935974 -347.806264)
		(stroke
			(width 0.08255)
			(type default)
		)
		(layer "In5.Cu")
	)
	(gr_line
		(start 8.948166 -443.997588)
		(end 8.966454 -444.010288)
		(stroke
			(width 0.08255)
			(type default)
		)
		(layer "In5.Cu")
	)
	(gr_line
		(start 8.948928 -447.531998)
		(end 8.97001 -447.562224)
		(stroke
			(width 0.08255)
			(type default)
		)
		(layer "In5.Cu")
	)
	(gr_line
		(start 8.951976 -311.09666)
		(end 8.982202 -311.075578)
		(stroke
			(width 0.08255)
			(type default)
		)
		(layer "In5.Cu")
	)
	(gr_line
		(start 8.96366 -353.590352)
		(end 8.963914 -353.590352)
		(stroke
			(width 0.08255)
			(type default)
		)
		(layer "In5.Cu")
	)
	(gr_line
		(start 8.963914 -353.590352)
		(end 8.995156 -353.612196)
		(stroke
			(width 0.08255)
			(type default)
		)
		(layer "In5.Cu")
	)
	(gr_line
		(start 8.966454 -444.010288)
		(end 8.979408 -444.028576)
		(stroke
			(width 0.08255)
			(type default)
		)
		(layer "In5.Cu")
	)
	(gr_line
		(start 8.97001 -447.562224)
		(end 8.97636 -447.598038)
		(stroke
			(width 0.08255)
			(type default)
		)
		(layer "In5.Cu")
	)
	(gr_line
		(start 9.04748 -205.079854)
		(end 9.083548 -205.073504)
		(stroke
			(width 0.08255)
			(type default)
		)
		(layer "In5.Cu")
	)
	(gr_line
		(start 9.053068 -298.259246)
		(end 9.089136 -298.252896)
		(stroke
			(width 0.08255)
			(type default)
		)
		(layer "In5.Cu")
	)
	(gr_line
		(start 9.071102 -350.409002)
		(end 9.10717 -350.415352)
		(stroke
			(width 0.08255)
			(type default)
		)
		(layer "In5.Cu")
	)
	(gr_line
		(start 9.083548 -205.073504)
		(end 9.113774 -205.052422)
		(stroke
			(width 0.08255)
			(type default)
		)
		(layer "In5.Cu")
	)
	(gr_line
		(start 9.089136 -298.252896)
		(end 9.119362 -298.231814)
		(stroke
			(width 0.08255)
			(type default)
		)
		(layer "In5.Cu")
	)
	(gr_line
		(start 9.106662 -334.420972)
		(end 9.14273 -334.427322)
		(stroke
			(width 0.08255)
			(type default)
		)
		(layer "In5.Cu")
	)
	(gr_line
		(start 9.10717 -350.415352)
		(end 9.137396 -350.436434)
		(stroke
			(width 0.08255)
			(type default)
		)
		(layer "In5.Cu")
	)
	(gr_line
		(start 9.133078 -347.5101)
		(end 9.147302 -347.52026)
		(stroke
			(width 0.08255)
			(type default)
		)
		(layer "In5.Cu")
	)
	(gr_line
		(start 9.14273 -334.427322)
		(end 9.172956 -334.448404)
		(stroke
			(width 0.08255)
			(type default)
		)
		(layer "In5.Cu")
	)
	(gr_line
		(start 9.148572 -217.810842)
		(end 9.18464 -217.804492)
		(stroke
			(width 0.08255)
			(type default)
		)
		(layer "In5.Cu")
	)
	(gr_line
		(start 9.15162 -356.829106)
		(end 9.187434 -356.835456)
		(stroke
			(width 0.08255)
			(type default)
		)
		(layer "In5.Cu")
	)
	(gr_line
		(start 9.154922 -295.652952)
		(end 9.1821 -295.658794)
		(stroke
			(width 0.08255)
			(type default)
		)
		(layer "In5.Cu")
	)
	(gr_line
		(start 9.167368 -171.889166)
		(end 9.317736 -171.674282)
		(stroke
			(width 0.08255)
			(type default)
		)
		(layer "In5.Cu")
	)
	(gr_line
		(start 9.167622 -175.088804)
		(end 9.318244 -174.87392)
		(stroke
			(width 0.08255)
			(type default)
		)
		(layer "In5.Cu")
	)
	(gr_line
		(start 9.175242 -347.539564)
		(end 9.190228 -347.550232)
		(stroke
			(width 0.08255)
			(type default)
		)
		(layer "In5.Cu")
	)
	(gr_line
		(start 9.1821 -295.658794)
		(end 9.209532 -295.653968)
		(stroke
			(width 0.08255)
			(type default)
		)
		(layer "In5.Cu")
	)
	(gr_line
		(start 9.183624 -228.02977)
		(end 9.200642 -228.041708)
		(stroke
			(width 0.08255)
			(type default)
		)
		(layer "In5.Cu")
	)
	(gr_line
		(start 9.18464 -217.804492)
		(end 9.214104 -217.783664)
		(stroke
			(width 0.08255)
			(type default)
		)
		(layer "In5.Cu")
	)
	(gr_line
		(start 9.187434 -356.835456)
		(end 9.21766 -356.856538)
		(stroke
			(width 0.08255)
			(type default)
		)
		(layer "In5.Cu")
	)
	(gr_line
		(start 9.190228 -347.550232)
		(end 9.19099 -347.550232)
		(stroke
			(width 0.08255)
			(type default)
		)
		(layer "In5.Cu")
	)
	(gr_line
		(start 9.19099 -347.550232)
		(end 9.203436 -347.568012)
		(stroke
			(width 0.08255)
			(type default)
		)
		(layer "In5.Cu")
	)
	(gr_line
		(start 9.200642 -228.041708)
		(end 9.21258 -228.058726)
		(stroke
			(width 0.08255)
			(type default)
		)
		(layer "In5.Cu")
	)
	(gr_line
		(start 9.235186 -158.277814)
		(end 9.280906 -158.019242)
		(stroke
			(width 0.08255)
			(type default)
		)
		(layer "In5.Cu")
	)
	(gr_line
		(start 9.236456 -201.845926)
		(end 9.272524 -201.839576)
		(stroke
			(width 0.08255)
			(type default)
		)
		(layer "In5.Cu")
	)
	(gr_line
		(start 9.266936 -87.667338)
		(end 9.273286 -87.63127)
		(stroke
			(width 0.08255)
			(type default)
		)
		(layer "In5.Cu")
	)
	(gr_line
		(start 9.267444 -340.860126)
		(end 9.280398 -340.862412)
		(stroke
			(width 0.08255)
			(type default)
		)
		(layer "In5.Cu")
	)
	(gr_line
		(start 9.26846 -172.23486)
		(end 10.043414 -172.098462)
		(stroke
			(width 0.08255)
			(type default)
		)
		(layer "In5.Cu")
	)
	(gr_line
		(start 9.269222 -175.434498)
		(end 10.044938 -175.297592)
		(stroke
			(width 0.08255)
			(type default)
		)
		(layer "In5.Cu")
	)
	(gr_line
		(start 9.272524 -201.839576)
		(end 9.30275 -201.818494)
		(stroke
			(width 0.08255)
			(type default)
		)
		(layer "In5.Cu")
	)
	(gr_line
		(start 9.272778 -391.264648)
		(end 9.291066 -391.277348)
		(stroke
			(width 0.08255)
			(type default)
		)
		(layer "In5.Cu")
	)
	(gr_line
		(start 9.273286 -87.63127)
		(end 9.294368 -87.601044)
		(stroke
			(width 0.08255)
			(type default)
		)
		(layer "In5.Cu")
	)
	(gr_line
		(start 9.280398 -340.862412)
		(end 9.29259 -340.868762)
		(stroke
			(width 0.08255)
			(type default)
		)
		(layer "In5.Cu")
	)
	(gr_line
		(start 9.280906 -158.019242)
		(end 9.686798 -157.73527)
		(stroke
			(width 0.08255)
			(type default)
		)
		(layer "In5.Cu")
	)
	(gr_line
		(start 9.291066 -391.277348)
		(end 9.303766 -391.295636)
		(stroke
			(width 0.08255)
			(type default)
		)
		(layer "In5.Cu")
	)
	(gr_line
		(start 9.309608 -388.16407)
		(end 9.327896 -388.17677)
		(stroke
			(width 0.08255)
			(type default)
		)
		(layer "In5.Cu")
	)
	(gr_line
		(start 9.317736 -171.674282)
		(end 9.805416 -171.58843)
		(stroke
			(width 0.08255)
			(type default)
		)
		(layer "In5.Cu")
	)
	(gr_line
		(start 9.318244 -174.87392)
		(end 9.805924 -174.787814)
		(stroke
			(width 0.08255)
			(type default)
		)
		(layer "In5.Cu")
	)
	(gr_line
		(start 9.327896 -388.17677)
		(end 9.340596 -388.195058)
		(stroke
			(width 0.08255)
			(type default)
		)
		(layer "In5.Cu")
	)
	(gr_line
		(start 9.352788 -155.971494)
		(end 9.371076 -155.958794)
		(stroke
			(width 0.08255)
			(type default)
		)
		(layer "In5.Cu")
	)
	(gr_line
		(start 9.35355 -155.035758)
		(end 9.39927 -155.29433)
		(stroke
			(width 0.08255)
			(type default)
		)
		(layer "In5.Cu")
	)
	(gr_line
		(start 9.35355 -155.035758)
		(end 9.637776 -154.63012)
		(stroke
			(width 0.08255)
			(type default)
		)
		(layer "In5.Cu")
	)
	(gr_line
		(start 9.360662 -437.715152)
		(end 9.37768 -437.72709)
		(stroke
			(width 0.08255)
			(type default)
		)
		(layer "In5.Cu")
	)
	(gr_line
		(start 9.364472 -307.823616)
		(end 9.40054 -307.817266)
		(stroke
			(width 0.08255)
			(type default)
		)
		(layer "In5.Cu")
	)
	(gr_line
		(start 9.371076 -155.958794)
		(end 9.383776 -155.940506)
		(stroke
			(width 0.08255)
			(type default)
		)
		(layer "In5.Cu")
	)
	(gr_line
		(start 9.37768 -437.72709)
		(end 9.389618 -437.744108)
		(stroke
			(width 0.08255)
			(type default)
		)
		(layer "In5.Cu")
	)
	(gr_line
		(start 9.378696 -335.026762)
		(end 10.02284 -335.477612)
		(stroke
			(width 0.08255)
			(type default)
		)
		(layer "In5.Cu")
	)
	(gr_line
		(start 9.40054 -307.817266)
		(end 9.430766 -307.796184)
		(stroke
			(width 0.08255)
			(type default)
		)
		(layer "In5.Cu")
	)
	(gr_line
		(start 9.409938 -207.827372)
		(end 9.428226 -207.814418)
		(stroke
			(width 0.08255)
			(type default)
		)
		(layer "In5.Cu")
	)
	(gr_line
		(start 9.422384 -444.661798)
		(end 9.443466 -444.692024)
		(stroke
			(width 0.08255)
			(type default)
		)
		(layer "In5.Cu")
	)
	(gr_line
		(start 9.428226 -207.814418)
		(end 9.440926 -207.79613)
		(stroke
			(width 0.08255)
			(type default)
		)
		(layer "In5.Cu")
	)
	(gr_line
		(start 9.443466 -444.692024)
		(end 9.449816 -444.727838)
		(stroke
			(width 0.08255)
			(type default)
		)
		(layer "In5.Cu")
	)
	(gr_line
		(start 9.454896 -169.649394)
		(end 9.47547 -169.65295)
		(stroke
			(width 0.08255)
			(type default)
		)
		(layer "In5.Cu")
	)
	(gr_line
		(start 9.472422 -158.549086)
		(end 10.11936 -158.096204)
		(stroke
			(width 0.08255)
			(type default)
		)
		(layer "In5.Cu")
	)
	(gr_line
		(start 9.47547 -169.65295)
		(end 9.496044 -169.649394)
		(stroke
			(width 0.08255)
			(type default)
		)
		(layer "In5.Cu")
	)
	(gr_line
		(start 9.488678 -152.427686)
		(end 9.506966 -152.414986)
		(stroke
			(width 0.08255)
			(type default)
		)
		(layer "In5.Cu")
	)
	(gr_line
		(start 9.506966 -152.414986)
		(end 9.51992 -152.396698)
		(stroke
			(width 0.08255)
			(type default)
		)
		(layer "In5.Cu")
	)
	(gr_line
		(start 9.55167 -334.710786)
		(end 9.810242 -334.66532)
		(stroke
			(width 0.08255)
			(type default)
		)
		(layer "In5.Cu")
	)
	(gr_line
		(start 9.597136 -224.144586)
		(end 9.63295 -224.138236)
		(stroke
			(width 0.08255)
			(type default)
		)
		(layer "In5.Cu")
	)
	(gr_line
		(start 9.625838 -341.044784)
		(end 9.664192 -341.065104)
		(stroke
			(width 0.08255)
			(type default)
		)
		(layer "In5.Cu")
	)
	(gr_line
		(start 9.63295 -224.138236)
		(end 9.662414 -224.117408)
		(stroke
			(width 0.08255)
			(type default)
		)
		(layer "In5.Cu")
	)
	(gr_line
		(start 9.637776 -154.63012)
		(end 9.896348 -154.5844)
		(stroke
			(width 0.08255)
			(type default)
		)
		(layer "In5.Cu")
	)
	(gr_line
		(start 9.664192 -341.065104)
		(end 9.689084 -341.100664)
		(stroke
			(width 0.08255)
			(type default)
		)
		(layer "In5.Cu")
	)
	(gr_line
		(start 9.680956 -341.709248)
		(end 10.133076 -342.35517)
		(stroke
			(width 0.08255)
			(type default)
		)
		(layer "In5.Cu")
	)
	(gr_line
		(start 9.686798 -157.73527)
		(end 9.945116 -157.78099)
		(stroke
			(width 0.08255)
			(type default)
		)
		(layer "In5.Cu")
	)
	(gr_line
		(start 9.695942 -224.09404)
		(end 9.702292 -224.089468)
		(stroke
			(width 0.08255)
			(type default)
		)
		(layer "In5.Cu")
	)
	(gr_line
		(start 9.700006 -220.913706)
		(end 9.737344 -220.907102)
		(stroke
			(width 0.08255)
			(type default)
		)
		(layer "In5.Cu")
	)
	(gr_line
		(start 9.706102 -204.638148)
		(end 9.72439 -204.625194)
		(stroke
			(width 0.08255)
			(type default)
		)
		(layer "In5.Cu")
	)
	(gr_line
		(start 9.710674 -425.184824)
		(end 9.746488 -425.191174)
		(stroke
			(width 0.08255)
			(type default)
		)
		(layer "In5.Cu")
	)
	(gr_line
		(start 9.713468 -231.591866)
		(end 9.731756 -231.604566)
		(stroke
			(width 0.08255)
			(type default)
		)
		(layer "In5.Cu")
	)
	(gr_line
		(start 9.7155 -155.466796)
		(end 10.16762 -154.821382)
		(stroke
			(width 0.08255)
			(type default)
		)
		(layer "In5.Cu")
	)
	(gr_line
		(start 9.72439 -204.625194)
		(end 9.73709 -204.606906)
		(stroke
			(width 0.08255)
			(type default)
		)
		(layer "In5.Cu")
	)
	(gr_line
		(start 9.731756 -231.604566)
		(end 9.732518 -231.605328)
		(stroke
			(width 0.08255)
			(type default)
		)
		(layer "In5.Cu")
	)
	(gr_line
		(start 9.732518 -231.605328)
		(end 9.745218 -231.623616)
		(stroke
			(width 0.08255)
			(type default)
		)
		(layer "In5.Cu")
	)
	(gr_line
		(start 9.737344 -220.907102)
		(end 9.768586 -220.885258)
		(stroke
			(width 0.08255)
			(type default)
		)
		(layer "In5.Cu")
	)
	(gr_line
		(start 9.746488 -425.191174)
		(end 9.775952 -425.212002)
		(stroke
			(width 0.08255)
			(type default)
		)
		(layer "In5.Cu")
	)
	(gr_line
		(start 9.79297 -344.71102)
		(end 9.811258 -344.72372)
		(stroke
			(width 0.08255)
			(type default)
		)
		(layer "In5.Cu")
	)
	(gr_line
		(start 9.805416 -171.58843)
		(end 10.0203 -171.738798)
		(stroke
			(width 0.08255)
			(type default)
		)
		(layer "In5.Cu")
	)
	(gr_line
		(start 9.805924 -174.787814)
		(end 10.020808 -174.938182)
		(stroke
			(width 0.08255)
			(type default)
		)
		(layer "In5.Cu")
	)
	(gr_line
		(start 9.810242 -334.66532)
		(end 10.21588 -334.949292)
		(stroke
			(width 0.08255)
			(type default)
		)
		(layer "In5.Cu")
	)
	(gr_line
		(start 9.811258 -344.72372)
		(end 9.823958 -344.742008)
		(stroke
			(width 0.08255)
			(type default)
		)
		(layer "In5.Cu")
	)
	(gr_line
		(start 9.826498 -345.365832)
		(end 10.280396 -346.014294)
		(stroke
			(width 0.08255)
			(type default)
		)
		(layer "In5.Cu")
	)
	(gr_line
		(start 9.835134 -210.602576)
		(end 9.853422 -210.589876)
		(stroke
			(width 0.08255)
			(type default)
		)
		(layer "In5.Cu")
	)
	(gr_line
		(start 9.853422 -210.589876)
		(end 9.866122 -210.571588)
		(stroke
			(width 0.08255)
			(type default)
		)
		(layer "In5.Cu")
	)
	(gr_line
		(start 9.948672 -310.398922)
		(end 9.967214 -310.385968)
		(stroke
			(width 0.08255)
			(type default)
		)
		(layer "In5.Cu")
	)
	(gr_line
		(start 9.95172 -341.47125)
		(end 10.210038 -341.51697)
		(stroke
			(width 0.08255)
			(type default)
		)
		(layer "In5.Cu")
	)
	(gr_line
		(start 9.956292 -442.385704)
		(end 9.977374 -442.41593)
		(stroke
			(width 0.08255)
			(type default)
		)
		(layer "In5.Cu")
	)
	(gr_line
		(start 9.957308 -301.31893)
		(end 9.994138 -301.312326)
		(stroke
			(width 0.08255)
			(type default)
		)
		(layer "In5.Cu")
	)
	(gr_line
		(start 9.967214 -310.385968)
		(end 9.97966 -310.368188)
		(stroke
			(width 0.08255)
			(type default)
		)
		(layer "In5.Cu")
	)
	(gr_line
		(start 9.977374 -442.41593)
		(end 9.983724 -442.451998)
		(stroke
			(width 0.08255)
			(type default)
		)
		(layer "In5.Cu")
	)
	(gr_line
		(start 9.989312 -432.452526)
		(end 10.0076 -432.46548)
		(stroke
			(width 0.08255)
			(type default)
		)
		(layer "In5.Cu")
	)
	(gr_line
		(start 9.994138 -301.312326)
		(end 10.025126 -301.290736)
		(stroke
			(width 0.08255)
			(type default)
		)
		(layer "In5.Cu")
	)
	(gr_line
		(start 10.0076 -432.46548)
		(end 10.0203 -432.483768)
		(stroke
			(width 0.08255)
			(type default)
		)
		(layer "In5.Cu")
	)
	(gr_line
		(start 10.098532 -345.129866)
		(end 10.357104 -345.175586)
		(stroke
			(width 0.08255)
			(type default)
		)
		(layer "In5.Cu")
	)
	(gr_line
		(start 10.117582 -149.385274)
		(end 10.203434 -148.897594)
		(stroke
			(width 0.08255)
			(type default)
		)
		(layer "In5.Cu")
	)
	(gr_line
		(start 10.117582 -149.385274)
		(end 10.26795 -149.600412)
		(stroke
			(width 0.08255)
			(type default)
		)
		(layer "In5.Cu")
	)
	(gr_line
		(start 10.137394 -153.91638)
		(end 10.183114 -154.174952)
		(stroke
			(width 0.08255)
			(type default)
		)
		(layer "In5.Cu")
	)
	(gr_line
		(start 10.137394 -153.91638)
		(end 10.42162 -153.510742)
		(stroke
			(width 0.08255)
			(type default)
		)
		(layer "In5.Cu")
	)
	(gr_line
		(start 10.145776 -192.885822)
		(end 10.181844 -192.879472)
		(stroke
			(width 0.08255)
			(type default)
		)
		(layer "In5.Cu")
	)
	(gr_line
		(start 10.181844 -192.879472)
		(end 10.21207 -192.85839)
		(stroke
			(width 0.08255)
			(type default)
		)
		(layer "In5.Cu")
	)
	(gr_line
		(start 10.203434 -148.897594)
		(end 10.418318 -148.747226)
		(stroke
			(width 0.08255)
			(type default)
		)
		(layer "In5.Cu")
	)
	(gr_line
		(start 10.210038 -341.51697)
		(end 10.49401 -341.922862)
		(stroke
			(width 0.08255)
			(type default)
		)
		(layer "In5.Cu")
	)
	(gr_line
		(start 10.213086 -116.183918)
		(end 10.216642 -116.204746)
		(stroke
			(width 0.08255)
			(type default)
		)
		(layer "In5.Cu")
	)
	(gr_line
		(start 10.213086 -116.183918)
		(end 10.216642 -116.163344)
		(stroke
			(width 0.08255)
			(type default)
		)
		(layer "In5.Cu")
	)
	(gr_line
		(start 10.21588 -334.949292)
		(end 10.2616 -335.20761)
		(stroke
			(width 0.08255)
			(type default)
		)
		(layer "In5.Cu")
	)
	(gr_line
		(start 10.216642 -116.204492)
		(end 10.216642 -116.205254)
		(stroke
			(width 0.08255)
			(type default)
		)
		(layer "In5.Cu")
	)
	(gr_line
		(start 10.223754 -412.066486)
		(end 10.260584 -412.059882)
		(stroke
			(width 0.08255)
			(type default)
		)
		(layer "In5.Cu")
	)
	(gr_line
		(start 10.260584 -412.059882)
		(end 10.291572 -412.038292)
		(stroke
			(width 0.08255)
			(type default)
		)
		(layer "In5.Cu")
	)
	(gr_line
		(start 10.262616 -429.352964)
		(end 10.280904 -429.365664)
		(stroke
			(width 0.08255)
			(type default)
		)
		(layer "In5.Cu")
	)
	(gr_line
		(start 10.280904 -429.365664)
		(end 10.293604 -429.383952)
		(stroke
			(width 0.08255)
			(type default)
		)
		(layer "In5.Cu")
	)
	(gr_line
		(start 10.30859 -439.056526)
		(end 10.329672 -439.086752)
		(stroke
			(width 0.08255)
			(type default)
		)
		(layer "In5.Cu")
	)
	(gr_line
		(start 10.326116 -151.2443)
		(end 10.347198 -151.214074)
		(stroke
			(width 0.08255)
			(type default)
		)
		(layer "In5.Cu")
	)
	(gr_line
		(start 10.328656 -288.453576)
		(end 10.364724 -288.447226)
		(stroke
			(width 0.08255)
			(type default)
		)
		(layer "In5.Cu")
	)
	(gr_line
		(start 10.329672 -439.086752)
		(end 10.336022 -439.12282)
		(stroke
			(width 0.08255)
			(type default)
		)
		(layer "In5.Cu")
	)
	(gr_line
		(start 10.347198 -151.214074)
		(end 10.353548 -151.178006)
		(stroke
			(width 0.08255)
			(type default)
		)
		(layer "In5.Cu")
	)
	(gr_line
		(start 10.354564 -148.039582)
		(end 10.44067 -147.551902)
		(stroke
			(width 0.08255)
			(type default)
		)
		(layer "In5.Cu")
	)
	(gr_line
		(start 10.354564 -148.039582)
		(end 10.505186 -148.254466)
		(stroke
			(width 0.08255)
			(type default)
		)
		(layer "In5.Cu")
	)
	(gr_line
		(start 10.357104 -345.175586)
		(end 10.64133 -345.581224)
		(stroke
			(width 0.08255)
			(type default)
		)
		(layer "In5.Cu")
	)
	(gr_line
		(start 10.364724 -288.447226)
		(end 10.39495 -288.426144)
		(stroke
			(width 0.08255)
			(type default)
		)
		(layer "In5.Cu")
	)
	(gr_line
		(start 10.414 -204.892402)
		(end 10.42035 -204.856334)
		(stroke
			(width 0.08255)
			(type default)
		)
		(layer "In5.Cu")
	)
	(gr_line
		(start 10.417556 -216.941146)
		(end 10.434574 -216.929208)
		(stroke
			(width 0.08255)
			(type default)
		)
		(layer "In5.Cu")
	)
	(gr_line
		(start 10.417556 -196.037962)
		(end 10.453624 -196.031612)
		(stroke
			(width 0.08255)
			(type default)
		)
		(layer "In5.Cu")
	)
	(gr_line
		(start 10.42035 -204.856334)
		(end 10.441432 -204.826108)
		(stroke
			(width 0.08255)
			(type default)
		)
		(layer "In5.Cu")
	)
	(gr_line
		(start 10.42162 -153.510742)
		(end 10.680192 -153.465022)
		(stroke
			(width 0.08255)
			(type default)
		)
		(layer "In5.Cu")
	)
	(gr_line
		(start 10.42416 -317.79845)
		(end 10.442448 -317.78575)
		(stroke
			(width 0.08255)
			(type default)
		)
		(layer "In5.Cu")
	)
	(gr_line
		(start 10.434574 -216.929208)
		(end 10.446766 -216.911936)
		(stroke
			(width 0.08255)
			(type default)
		)
		(layer "In5.Cu")
	)
	(gr_line
		(start 10.44067 -147.551902)
		(end 10.655554 -147.401026)
		(stroke
			(width 0.08255)
			(type default)
		)
		(layer "In5.Cu")
	)
	(gr_line
		(start 10.442448 -317.78575)
		(end 10.455148 -317.767462)
		(stroke
			(width 0.08255)
			(type default)
		)
		(layer "In5.Cu")
	)
	(gr_line
		(start 10.448544 -342.18118)
		(end 10.49401 -341.922862)
		(stroke
			(width 0.08255)
			(type default)
		)
		(layer "In5.Cu")
	)
	(gr_line
		(start 10.453624 -196.031612)
		(end 10.48385 -196.01053)
		(stroke
			(width 0.08255)
			(type default)
		)
		(layer "In5.Cu")
	)
	(gr_line
		(start 10.4648 -342.828626)
		(end 10.91692 -343.474548)
		(stroke
			(width 0.08255)
			(type default)
		)
		(layer "In5.Cu")
	)
	(gr_line
		(start 10.476738 -320.952114)
		(end 10.49528 -320.93916)
		(stroke
			(width 0.08255)
			(type default)
		)
		(layer "In5.Cu")
	)
	(gr_line
		(start 10.483342 -351.379028)
		(end 10.50163 -351.391728)
		(stroke
			(width 0.08255)
			(type default)
		)
		(layer "In5.Cu")
	)
	(gr_line
		(start 10.49528 -320.93916)
		(end 10.495788 -320.938652)
		(stroke
			(width 0.08255)
			(type default)
		)
		(layer "In5.Cu")
	)
	(gr_line
		(start 10.495788 -320.938652)
		(end 10.508742 -320.92011)
		(stroke
			(width 0.08255)
			(type default)
		)
		(layer "In5.Cu")
	)
	(gr_line
		(start 10.498074 -335.810606)
		(end 11.142726 -336.261964)
		(stroke
			(width 0.08255)
			(type default)
		)
		(layer "In5.Cu")
	)
	(gr_line
		(start 10.499344 -154.347418)
		(end 10.951972 -153.701242)
		(stroke
			(width 0.08255)
			(type default)
		)
		(layer "In5.Cu")
	)
	(gr_line
		(start 10.50163 -351.391728)
		(end 10.51433 -351.410016)
		(stroke
			(width 0.08255)
			(type default)
		)
		(layer "In5.Cu")
	)
	(gr_line
		(start 10.51306 -171.65193)
		(end 10.663428 -171.437046)
		(stroke
			(width 0.08255)
			(type default)
		)
		(layer "In5.Cu")
	)
	(gr_line
		(start 10.513568 -174.851314)
		(end 10.663936 -174.63643)
		(stroke
			(width 0.08255)
			(type default)
		)
		(layer "In5.Cu")
	)
	(gr_line
		(start 10.519156 -206.256128)
		(end 10.540238 -206.225902)
		(stroke
			(width 0.08255)
			(type default)
		)
		(layer "In5.Cu")
	)
	(gr_line
		(start 10.529062 -161.546794)
		(end 10.54735 -161.534094)
		(stroke
			(width 0.08255)
			(type default)
		)
		(layer "In5.Cu")
	)
	(gr_line
		(start 10.529824 -160.611058)
		(end 10.57529 -160.869884)
		(stroke
			(width 0.08255)
			(type default)
		)
		(layer "In5.Cu")
	)
	(gr_line
		(start 10.529824 -160.611058)
		(end 10.813796 -160.20542)
		(stroke
			(width 0.08255)
			(type default)
		)
		(layer "In5.Cu")
	)
	(gr_line
		(start 10.531602 -354.68814)
		(end 10.54989 -354.70084)
		(stroke
			(width 0.08255)
			(type default)
		)
		(layer "In5.Cu")
	)
	(gr_line
		(start 10.540238 -206.225902)
		(end 10.546588 -206.189834)
		(stroke
			(width 0.08255)
			(type default)
		)
		(layer "In5.Cu")
	)
	(gr_line
		(start 10.54735 -161.534094)
		(end 10.56005 -161.515806)
		(stroke
			(width 0.08255)
			(type default)
		)
		(layer "In5.Cu")
	)
	(gr_line
		(start 10.54989 -354.70084)
		(end 10.56259 -354.719128)
		(stroke
			(width 0.08255)
			(type default)
		)
		(layer "In5.Cu")
	)
	(gr_line
		(start 10.571988 -213.406736)
		(end 10.590784 -213.393528)
		(stroke
			(width 0.08255)
			(type default)
		)
		(layer "In5.Cu")
	)
	(gr_line
		(start 10.590784 -213.393528)
		(end 10.602976 -213.376002)
		(stroke
			(width 0.08255)
			(type default)
		)
		(layer "In5.Cu")
	)
	(gr_line
		(start 10.59561 -345.84005)
		(end 10.64133 -345.581224)
		(stroke
			(width 0.08255)
			(type default)
		)
		(layer "In5.Cu")
	)
	(gr_line
		(start 10.608056 -433.32273)
		(end 10.628884 -433.352194)
		(stroke
			(width 0.08255)
			(type default)
		)
		(layer "In5.Cu")
	)
	(gr_line
		(start 10.610342 -346.485718)
		(end 11.064748 -347.134434)
		(stroke
			(width 0.08255)
			(type default)
		)
		(layer "In5.Cu")
	)
	(gr_line
		(start 10.612882 -171.998132)
		(end 11.389614 -171.861226)
		(stroke
			(width 0.08255)
			(type default)
		)
		(layer "In5.Cu")
	)
	(gr_line
		(start 10.614152 -175.197262)
		(end 11.390122 -175.060356)
		(stroke
			(width 0.08255)
			(type default)
		)
		(layer "In5.Cu")
	)
	(gr_line
		(start 10.627614 -149.624288)
		(end 10.76452 -148.847048)
		(stroke
			(width 0.08255)
			(type default)
		)
		(layer "In5.Cu")
	)
	(gr_line
		(start 10.628884 -433.352194)
		(end 10.635234 -433.388262)
		(stroke
			(width 0.08255)
			(type default)
		)
		(layer "In5.Cu")
	)
	(gr_line
		(start 10.663428 -171.437046)
		(end 11.151362 -171.351194)
		(stroke
			(width 0.08255)
			(type default)
		)
		(layer "In5.Cu")
	)
	(gr_line
		(start 10.663936 -174.63643)
		(end 11.151616 -174.550324)
		(stroke
			(width 0.08255)
			(type default)
		)
		(layer "In5.Cu")
	)
	(gr_line
		(start 10.671048 -335.49463)
		(end 10.92962 -335.44891)
		(stroke
			(width 0.08255)
			(type default)
		)
		(layer "In5.Cu")
	)
	(gr_line
		(start 10.674604 -425.841414)
		(end 10.691622 -425.853352)
		(stroke
			(width 0.08255)
			(type default)
		)
		(layer "In5.Cu")
	)
	(gr_line
		(start 10.691622 -425.853352)
		(end 10.703052 -425.869862)
		(stroke
			(width 0.08255)
			(type default)
		)
		(layer "In5.Cu")
	)
	(gr_line
		(start 10.718546 -292.746938)
		(end 10.752328 -292.75405)
		(stroke
			(width 0.08255)
			(type default)
		)
		(layer "In5.Cu")
	)
	(gr_line
		(start 10.73531 -342.590628)
		(end 10.993882 -342.636348)
		(stroke
			(width 0.08255)
			(type default)
		)
		(layer "In5.Cu")
	)
	(gr_line
		(start 10.752328 -292.75405)
		(end 10.78611 -292.746938)
		(stroke
			(width 0.08255)
			(type default)
		)
		(layer "In5.Cu")
	)
	(gr_line
		(start 10.76071 -212.53069)
		(end 11.213592 -211.884006)
		(stroke
			(width 0.08255)
			(type default)
		)
		(layer "In5.Cu")
	)
	(gr_line
		(start 10.813796 -160.20542)
		(end 11.072368 -160.1597)
		(stroke
			(width 0.08255)
			(type default)
		)
		(layer "In5.Cu")
	)
	(gr_line
		(start 10.850626 -357.99903)
		(end 10.868914 -358.011984)
		(stroke
			(width 0.08255)
			(type default)
		)
		(layer "In5.Cu")
	)
	(gr_line
		(start 10.86485 -148.278342)
		(end 11.001756 -147.501102)
		(stroke
			(width 0.08255)
			(type default)
		)
		(layer "In5.Cu")
	)
	(gr_line
		(start 10.868914 -358.011984)
		(end 10.881614 -358.030272)
		(stroke
			(width 0.08255)
			(type default)
		)
		(layer "In5.Cu")
	)
	(gr_line
		(start 10.882376 -346.249244)
		(end 11.140948 -346.294964)
		(stroke
			(width 0.08255)
			(type default)
		)
		(layer "In5.Cu")
	)
	(gr_line
		(start 10.890758 -161.043366)
		(end 11.343132 -160.397444)
		(stroke
			(width 0.08255)
			(type default)
		)
		(layer "In5.Cu")
	)
	(gr_line
		(start 10.92962 -335.44891)
		(end 11.335258 -335.733136)
		(stroke
			(width 0.08255)
			(type default)
		)
		(layer "In5.Cu")
	)
	(gr_line
		(start 10.97026 -144.545558)
		(end 11.056366 -144.057878)
		(stroke
			(width 0.08255)
			(type default)
		)
		(layer "In5.Cu")
	)
	(gr_line
		(start 10.97026 -144.545558)
		(end 11.121136 -144.760696)
		(stroke
			(width 0.08255)
			(type default)
		)
		(layer "In5.Cu")
	)
	(gr_line
		(start 10.993882 -342.636348)
		(end 11.277854 -343.04224)
		(stroke
			(width 0.08255)
			(type default)
		)
		(layer "In5.Cu")
	)
	(gr_line
		(start 11.03249 -212.76691)
		(end 11.291062 -212.72119)
		(stroke
			(width 0.08255)
			(type default)
		)
		(layer "In5.Cu")
	)
	(gr_line
		(start 11.045698 -323.896228)
		(end 11.062462 -323.884544)
		(stroke
			(width 0.08255)
			(type default)
		)
		(layer "In5.Cu")
	)
	(gr_line
		(start 11.046714 -430.459642)
		(end 11.067796 -430.489868)
		(stroke
			(width 0.08255)
			(type default)
		)
		(layer "In5.Cu")
	)
	(gr_line
		(start 11.056366 -144.057878)
		(end 11.271504 -143.907002)
		(stroke
			(width 0.08255)
			(type default)
		)
		(layer "In5.Cu")
	)
	(gr_line
		(start 11.062462 -323.884544)
		(end 11.06297 -323.88429)
		(stroke
			(width 0.08255)
			(type default)
		)
		(layer "In5.Cu")
	)
	(gr_line
		(start 11.06297 -323.88429)
		(end 11.07567 -323.866256)
		(stroke
			(width 0.08255)
			(type default)
		)
		(layer "In5.Cu")
	)
	(gr_line
		(start 11.067796 -430.489868)
		(end 11.074146 -430.525936)
		(stroke
			(width 0.08255)
			(type default)
		)
		(layer "In5.Cu")
	)
	(gr_line
		(start 11.133836 -338.745576)
		(end 11.152124 -338.758276)
		(stroke
			(width 0.08255)
			(type default)
		)
		(layer "In5.Cu")
	)
	(gr_line
		(start 11.135106 -326.851772)
		(end 11.153394 -326.839072)
		(stroke
			(width 0.08255)
			(type default)
		)
		(layer "In5.Cu")
	)
	(gr_line
		(start 11.140948 -346.294964)
		(end 11.425174 -346.700602)
		(stroke
			(width 0.08255)
			(type default)
		)
		(layer "In5.Cu")
	)
	(gr_line
		(start 11.151362 -171.351194)
		(end 11.366246 -171.501562)
		(stroke
			(width 0.08255)
			(type default)
		)
		(layer "In5.Cu")
	)
	(gr_line
		(start 11.151616 -174.550324)
		(end 11.3665 -174.700692)
		(stroke
			(width 0.08255)
			(type default)
		)
		(layer "In5.Cu")
	)
	(gr_line
		(start 11.152124 -338.758276)
		(end 11.164824 -338.776564)
		(stroke
			(width 0.08255)
			(type default)
		)
		(layer "In5.Cu")
	)
	(gr_line
		(start 11.153394 -326.839072)
		(end 11.166094 -326.820784)
		(stroke
			(width 0.08255)
			(type default)
		)
		(layer "In5.Cu")
	)
	(gr_line
		(start 11.175238 -419.662356)
		(end 11.197082 -419.693344)
		(stroke
			(width 0.08255)
			(type default)
		)
		(layer "In5.Cu")
	)
	(gr_line
		(start 11.197082 -419.693344)
		(end 11.20394 -419.731698)
		(stroke
			(width 0.08255)
			(type default)
		)
		(layer "In5.Cu")
	)
	(gr_line
		(start 11.207496 -143.199612)
		(end 11.293602 -142.711932)
		(stroke
			(width 0.08255)
			(type default)
		)
		(layer "In5.Cu")
	)
	(gr_line
		(start 11.207496 -143.199612)
		(end 11.358372 -143.415004)
		(stroke
			(width 0.08255)
			(type default)
		)
		(layer "In5.Cu")
	)
	(gr_line
		(start 11.232388 -343.300812)
		(end 11.277854 -343.04224)
		(stroke
			(width 0.08255)
			(type default)
		)
		(layer "In5.Cu")
	)
	(gr_line
		(start 11.247628 -343.946734)
		(end 11.700256 -344.593418)
		(stroke
			(width 0.08255)
			(type default)
		)
		(layer "In5.Cu")
	)
	(gr_line
		(start 11.277346 -157.28569)
		(end 11.295634 -157.27299)
		(stroke
			(width 0.08255)
			(type default)
		)
		(layer "In5.Cu")
	)
	(gr_line
		(start 11.291062 -212.72119)
		(end 11.575288 -212.315552)
		(stroke
			(width 0.08255)
			(type default)
		)
		(layer "In5.Cu")
	)
	(gr_line
		(start 11.293602 -142.711932)
		(end 11.50874 -142.56131)
		(stroke
			(width 0.08255)
			(type default)
		)
		(layer "In5.Cu")
	)
	(gr_line
		(start 11.295634 -157.27299)
		(end 11.308334 -157.254702)
		(stroke
			(width 0.08255)
			(type default)
		)
		(layer "In5.Cu")
	)
	(gr_line
		(start 11.335258 -335.733136)
		(end 11.380978 -335.991454)
		(stroke
			(width 0.08255)
			(type default)
		)
		(layer "In5.Cu")
	)
	(gr_line
		(start 11.379454 -346.959428)
		(end 11.425174 -346.700602)
		(stroke
			(width 0.08255)
			(type default)
		)
		(layer "In5.Cu")
	)
	(gr_line
		(start 11.394186 -347.604842)
		(end 11.848592 -348.253812)
		(stroke
			(width 0.08255)
			(type default)
		)
		(layer "In5.Cu")
	)
	(gr_line
		(start 11.395456 -409.991052)
		(end 11.41603 -409.994608)
		(stroke
			(width 0.08255)
			(type default)
		)
		(layer "In5.Cu")
	)
	(gr_line
		(start 11.41603 -409.994608)
		(end 11.436604 -409.991052)
		(stroke
			(width 0.08255)
			(type default)
		)
		(layer "In5.Cu")
	)
	(gr_line
		(start 11.420856 -87.16645)
		(end 11.427206 -87.130636)
		(stroke
			(width 0.08255)
			(type default)
		)
		(layer "In5.Cu")
	)
	(gr_line
		(start 11.427206 -87.130636)
		(end 11.448288 -87.10041)
		(stroke
			(width 0.08255)
			(type default)
		)
		(layer "In5.Cu")
	)
	(gr_line
		(start 11.438382 -426.920406)
		(end 11.460226 -426.951394)
		(stroke
			(width 0.08255)
			(type default)
		)
		(layer "In5.Cu")
	)
	(gr_line
		(start 11.444732 -141.85392)
		(end 11.530838 -141.36624)
		(stroke
			(width 0.08255)
			(type default)
		)
		(layer "In5.Cu")
	)
	(gr_line
		(start 11.444732 -141.85392)
		(end 11.595608 -142.069058)
		(stroke
			(width 0.08255)
			(type default)
		)
		(layer "In5.Cu")
	)
	(gr_line
		(start 11.460226 -426.951394)
		(end 11.467084 -426.989494)
		(stroke
			(width 0.08255)
			(type default)
		)
		(layer "In5.Cu")
	)
	(gr_line
		(start 11.480546 -144.784318)
		(end 11.617706 -144.006062)
		(stroke
			(width 0.08255)
			(type default)
		)
		(layer "In5.Cu")
	)
	(gr_line
		(start 11.506962 -306.342796)
		(end 11.52525 -306.330096)
		(stroke
			(width 0.08255)
			(type default)
		)
		(layer "In5.Cu")
	)
	(gr_line
		(start 11.519154 -343.710006)
		(end 11.777726 -343.755726)
		(stroke
			(width 0.08255)
			(type default)
		)
		(layer "In5.Cu")
	)
	(gr_line
		(start 11.52525 -306.330096)
		(end 11.53795 -306.312062)
		(stroke
			(width 0.08255)
			(type default)
		)
		(layer "In5.Cu")
	)
	(gr_line
		(start 11.529568 -212.05698)
		(end 11.575288 -212.315552)
		(stroke
			(width 0.08255)
			(type default)
		)
		(layer "In5.Cu")
	)
	(gr_line
		(start 11.530838 -141.36624)
		(end 11.745976 -141.215618)
		(stroke
			(width 0.08255)
			(type default)
		)
		(layer "In5.Cu")
	)
	(gr_line
		(start 11.57859 -208.12633)
		(end 11.599672 -208.096104)
		(stroke
			(width 0.08255)
			(type default)
		)
		(layer "In5.Cu")
	)
	(gr_line
		(start 11.599418 -219.60332)
		(end 11.617706 -219.59062)
		(stroke
			(width 0.08255)
			(type default)
		)
		(layer "In5.Cu")
	)
	(gr_line
		(start 11.599672 -208.096104)
		(end 11.606022 -208.060036)
		(stroke
			(width 0.08255)
			(type default)
		)
		(layer "In5.Cu")
	)
	(gr_line
		(start 11.617706 -219.59062)
		(end 11.630406 -219.572332)
		(stroke
			(width 0.08255)
			(type default)
		)
		(layer "In5.Cu")
	)
	(gr_line
		(start 11.665966 -347.368622)
		(end 11.924792 -347.414342)
		(stroke
			(width 0.08255)
			(type default)
		)
		(layer "In5.Cu")
	)
	(gr_line
		(start 11.669014 -200.161652)
		(end 11.687556 -200.148698)
		(stroke
			(width 0.08255)
			(type default)
		)
		(layer "In5.Cu")
	)
	(gr_line
		(start 11.687556 -200.148698)
		(end 11.68781 -200.148444)
		(stroke
			(width 0.08255)
			(type default)
		)
		(layer "In5.Cu")
	)
	(gr_line
		(start 11.68781 -200.148444)
		(end 11.70051 -200.130156)
		(stroke
			(width 0.08255)
			(type default)
		)
		(layer "In5.Cu")
	)
	(gr_line
		(start 11.717528 -143.43888)
		(end 11.854942 -142.660624)
		(stroke
			(width 0.08255)
			(type default)
		)
		(layer "In5.Cu")
	)
	(gr_line
		(start 11.770868 -119.081296)
		(end 11.774424 -119.060722)
		(stroke
			(width 0.08255)
			(type default)
		)
		(layer "In5.Cu")
	)
	(gr_line
		(start 11.770868 -119.081296)
		(end 11.774678 -119.102886)
		(stroke
			(width 0.08255)
			(type default)
		)
		(layer "In5.Cu")
	)
	(gr_line
		(start 11.777726 -343.755726)
		(end 12.061698 -344.161618)
		(stroke
			(width 0.08255)
			(type default)
		)
		(layer "In5.Cu")
	)
	(gr_line
		(start 11.836146 -359.39349)
		(end 11.857228 -359.423716)
		(stroke
			(width 0.08255)
			(type default)
		)
		(layer "In5.Cu")
	)
	(gr_line
		(start 11.839194 -204.687424)
		(end 11.845544 -204.651356)
		(stroke
			(width 0.08255)
			(type default)
		)
		(layer "In5.Cu")
	)
	(gr_line
		(start 11.84275 -295.189402)
		(end 11.878564 -295.183052)
		(stroke
			(width 0.08255)
			(type default)
		)
		(layer "In5.Cu")
	)
	(gr_line
		(start 11.845544 -204.651356)
		(end 11.866626 -204.62113)
		(stroke
			(width 0.08255)
			(type default)
		)
		(layer "In5.Cu")
	)
	(gr_line
		(start 11.857228 -410.507688)
		(end 11.887454 -410.486606)
		(stroke
			(width 0.08255)
			(type default)
		)
		(layer "In5.Cu")
	)
	(gr_line
		(start 11.857228 -359.423716)
		(end 11.863578 -359.459784)
		(stroke
			(width 0.08255)
			(type default)
		)
		(layer "In5.Cu")
	)
	(gr_line
		(start 11.861292 -152.402794)
		(end 11.882374 -152.372568)
		(stroke
			(width 0.08255)
			(type default)
		)
		(layer "In5.Cu")
	)
	(gr_line
		(start 11.878564 -295.183052)
		(end 11.90879 -295.16197)
		(stroke
			(width 0.08255)
			(type default)
		)
		(layer "In5.Cu")
	)
	(gr_line
		(start 11.882374 -152.372568)
		(end 11.888724 -152.3365)
		(stroke
			(width 0.08255)
			(type default)
		)
		(layer "In5.Cu")
	)
	(gr_line
		(start 11.887454 -410.486606)
		(end 11.923268 -410.480256)
		(stroke
			(width 0.08255)
			(type default)
		)
		(layer "In5.Cu")
	)
	(gr_line
		(start 11.924792 -347.414342)
		(end 12.208764 -347.81998)
		(stroke
			(width 0.08255)
			(type default)
		)
		(layer "In5.Cu")
	)
	(gr_line
		(start 11.947398 -234.768644)
		(end 11.96848 -234.79887)
		(stroke
			(width 0.08255)
			(type default)
		)
		(layer "In5.Cu")
	)
	(gr_line
		(start 11.955018 -142.09268)
		(end 12.091924 -141.31544)
		(stroke
			(width 0.08255)
			(type default)
		)
		(layer "In5.Cu")
	)
	(gr_line
		(start 11.96848 -234.79887)
		(end 11.97483 -234.834938)
		(stroke
			(width 0.08255)
			(type default)
		)
		(layer "In5.Cu")
	)
	(gr_line
		(start 12.015978 -344.419936)
		(end 12.061698 -344.161618)
		(stroke
			(width 0.08255)
			(type default)
		)
		(layer "In5.Cu")
	)
	(gr_line
		(start 12.11961 -395.936724)
		(end 12.13231 -395.955012)
		(stroke
			(width 0.08255)
			(type default)
		)
		(layer "In5.Cu")
	)
	(gr_line
		(start 12.13231 -395.955012)
		(end 12.150598 -395.967712)
		(stroke
			(width 0.08255)
			(type default)
		)
		(layer "In5.Cu")
	)
	(gr_line
		(start 12.163298 -348.078806)
		(end 12.208764 -347.81998)
		(stroke
			(width 0.08255)
			(type default)
		)
		(layer "In5.Cu")
	)
	(gr_line
		(start 12.255246 -155.902406)
		(end 12.276328 -155.87218)
		(stroke
			(width 0.08255)
			(type default)
		)
		(layer "In5.Cu")
	)
	(gr_line
		(start 12.276328 -155.87218)
		(end 12.282678 -155.836112)
		(stroke
			(width 0.08255)
			(type default)
		)
		(layer "In5.Cu")
	)
	(gr_line
		(start 12.33551 -340.448392)
		(end 12.356592 -340.478618)
		(stroke
			(width 0.08255)
			(type default)
		)
		(layer "In5.Cu")
	)
	(gr_line
		(start 12.356592 -340.478618)
		(end 12.362942 -340.514686)
		(stroke
			(width 0.08255)
			(type default)
		)
		(layer "In5.Cu")
	)
	(gr_line
		(start 12.365736 -315.038486)
		(end 12.386818 -315.00826)
		(stroke
			(width 0.08255)
			(type default)
		)
		(layer "In5.Cu")
	)
	(gr_line
		(start 12.386818 -315.00826)
		(end 12.393168 -314.972192)
		(stroke
			(width 0.08255)
			(type default)
		)
		(layer "In5.Cu")
	)
	(gr_line
		(start 12.474702 -357.450136)
		(end 12.495784 -357.480362)
		(stroke
			(width 0.08255)
			(type default)
		)
		(layer "In5.Cu")
	)
	(gr_line
		(start 12.495784 -357.480362)
		(end 12.502134 -357.516176)
		(stroke
			(width 0.08255)
			(type default)
		)
		(layer "In5.Cu")
	)
	(gr_line
		(start 12.498578 -210.669378)
		(end 12.51966 -210.639152)
		(stroke
			(width 0.08255)
			(type default)
		)
		(layer "In5.Cu")
	)
	(gr_line
		(start 12.51966 -210.639152)
		(end 12.52601 -210.603084)
		(stroke
			(width 0.08255)
			(type default)
		)
		(layer "In5.Cu")
	)
	(gr_line
		(start 12.561316 -343.687908)
		(end 12.567666 -343.723976)
		(stroke
			(width 0.08255)
			(type default)
		)
		(layer "In5.Cu")
	)
	(gr_line
		(start 12.567666 -343.723976)
		(end 12.588748 -343.754202)
		(stroke
			(width 0.08255)
			(type default)
		)
		(layer "In5.Cu")
	)
	(gr_line
		(start 12.609576 -138.379962)
		(end 12.613132 -138.359134)
		(stroke
			(width 0.08255)
			(type default)
		)
		(layer "In5.Cu")
	)
	(gr_line
		(start 12.609576 -138.379708)
		(end 12.609576 -138.38047)
		(stroke
			(width 0.08255)
			(type default)
		)
		(layer "In5.Cu")
	)
	(gr_line
		(start 12.609576 -138.33856)
		(end 12.613132 -138.359134)
		(stroke
			(width 0.08255)
			(type default)
		)
		(layer "In5.Cu")
	)
	(gr_line
		(start 12.650724 -177.67554)
		(end 12.801092 -177.460656)
		(stroke
			(width 0.08255)
			(type default)
		)
		(layer "In5.Cu")
	)
	(gr_line
		(start 12.753086 -178.02098)
		(end 13.52804 -177.884328)
		(stroke
			(width 0.08255)
			(type default)
		)
		(layer "In5.Cu")
	)
	(gr_line
		(start 12.782296 -144.13611)
		(end 12.868148 -143.64843)
		(stroke
			(width 0.08255)
			(type default)
		)
		(layer "In5.Cu")
	)
	(gr_line
		(start 12.782296 -144.13611)
		(end 12.932664 -144.351248)
		(stroke
			(width 0.08255)
			(type default)
		)
		(layer "In5.Cu")
	)
	(gr_line
		(start 12.797282 -471.304366)
		(end 12.803632 -471.34018)
		(stroke
			(width 0.08255)
			(type default)
		)
		(layer "In5.Cu")
	)
	(gr_line
		(start 12.801092 -177.460656)
		(end 13.288772 -177.37455)
		(stroke
			(width 0.08255)
			(type default)
		)
		(layer "In5.Cu")
	)
	(gr_line
		(start 12.803632 -471.34018)
		(end 12.824714 -471.370406)
		(stroke
			(width 0.08255)
			(type default)
		)
		(layer "In5.Cu")
	)
	(gr_line
		(start 12.818364 -292.315138)
		(end 12.849352 -292.308534)
		(stroke
			(width 0.08255)
			(type default)
		)
		(layer "In5.Cu")
	)
	(gr_line
		(start 12.849352 -292.308534)
		(end 12.87526 -292.2905)
		(stroke
			(width 0.08255)
			(type default)
		)
		(layer "In5.Cu")
	)
	(gr_line
		(start 12.851638 -158.242762)
		(end 12.873482 -158.21152)
		(stroke
			(width 0.08255)
			(type default)
		)
		(layer "In5.Cu")
	)
	(gr_line
		(start 12.867132 -337.03514)
		(end 12.88542 -337.04784)
		(stroke
			(width 0.08255)
			(type default)
		)
		(layer "In5.Cu")
	)
	(gr_line
		(start 12.868148 -143.64843)
		(end 13.083032 -143.498062)
		(stroke
			(width 0.08255)
			(type default)
		)
		(layer "In5.Cu")
	)
	(gr_line
		(start 12.872974 -158.21152)
		(end 12.873482 -158.21152)
		(stroke
			(width 0.08255)
			(type default)
		)
		(layer "In5.Cu")
	)
	(gr_line
		(start 12.872974 -158.21152)
		(end 12.879324 -158.175706)
		(stroke
			(width 0.08255)
			(type default)
		)
		(layer "In5.Cu")
	)
	(gr_line
		(start 12.88542 -337.04784)
		(end 12.89812 -337.066128)
		(stroke
			(width 0.08255)
			(type default)
		)
		(layer "In5.Cu")
	)
	(gr_line
		(start 12.902184 -337.691984)
		(end 13.354304 -338.337652)
		(stroke
			(width 0.08255)
			(type default)
		)
		(layer "In5.Cu")
	)
	(gr_line
		(start 12.91336 -206.356712)
		(end 12.91971 -206.320644)
		(stroke
			(width 0.08255)
			(type default)
		)
		(layer "In5.Cu")
	)
	(gr_line
		(start 12.91971 -206.320644)
		(end 12.940792 -206.290418)
		(stroke
			(width 0.08255)
			(type default)
		)
		(layer "In5.Cu")
	)
	(gr_line
		(start 12.92098 -344.228674)
		(end 13.372846 -344.874088)
		(stroke
			(width 0.08255)
			(type default)
		)
		(layer "In5.Cu")
	)
	(gr_line
		(start 12.92352 -221.821756)
		(end 12.933934 -221.813882)
		(stroke
			(width 0.08255)
			(type default)
		)
		(layer "In5.Cu")
	)
	(gr_line
		(start 12.933934 -221.813882)
		(end 12.940792 -221.803722)
		(stroke
			(width 0.08255)
			(type default)
		)
		(layer "In5.Cu")
	)
	(gr_line
		(start 12.963398 -317.41491)
		(end 12.98448 -317.384684)
		(stroke
			(width 0.08255)
			(type default)
		)
		(layer "In5.Cu")
	)
	(gr_line
		(start 12.963906 -403.501352)
		(end 12.99972 -403.507702)
		(stroke
			(width 0.08255)
			(type default)
		)
		(layer "In5.Cu")
	)
	(gr_line
		(start 12.98448 -317.384684)
		(end 12.99083 -317.348616)
		(stroke
			(width 0.08255)
			(type default)
		)
		(layer "In5.Cu")
	)
	(gr_line
		(start 12.99972 -403.507702)
		(end 13.029946 -403.528784)
		(stroke
			(width 0.08255)
			(type default)
		)
		(layer "In5.Cu")
	)
	(gr_line
		(start 13.019278 -142.790418)
		(end 13.105384 -142.302738)
		(stroke
			(width 0.08255)
			(type default)
		)
		(layer "In5.Cu")
	)
	(gr_line
		(start 13.019278 -142.790418)
		(end 13.1699 -143.005556)
		(stroke
			(width 0.08255)
			(type default)
		)
		(layer "In5.Cu")
	)
	(gr_line
		(start 13.047472 -355.027738)
		(end 13.068554 -355.057964)
		(stroke
			(width 0.08255)
			(type default)
		)
		(layer "In5.Cu")
	)
	(gr_line
		(start 13.062966 -281.566366)
		(end 13.099034 -281.560016)
		(stroke
			(width 0.08255)
			(type default)
		)
		(layer "In5.Cu")
	)
	(gr_line
		(start 13.068554 -355.057964)
		(end 13.074904 -355.094032)
		(stroke
			(width 0.08255)
			(type default)
		)
		(layer "In5.Cu")
	)
	(gr_line
		(start 13.096494 -213.12759)
		(end 13.117576 -213.097364)
		(stroke
			(width 0.08255)
			(type default)
		)
		(layer "In5.Cu")
	)
	(gr_line
		(start 13.099034 -281.560016)
		(end 13.12926 -281.538934)
		(stroke
			(width 0.08255)
			(type default)
		)
		(layer "In5.Cu")
	)
	(gr_line
		(start 13.105384 -142.302738)
		(end 13.320268 -142.15237)
		(stroke
			(width 0.08255)
			(type default)
		)
		(layer "In5.Cu")
	)
	(gr_line
		(start 13.117576 -213.097364)
		(end 13.123926 -213.061296)
		(stroke
			(width 0.08255)
			(type default)
		)
		(layer "In5.Cu")
	)
	(gr_line
		(start 13.162026 -278.348694)
		(end 13.198094 -278.342344)
		(stroke
			(width 0.08255)
			(type default)
		)
		(layer "In5.Cu")
	)
	(gr_line
		(start 13.172694 -337.453986)
		(end 13.431266 -337.499706)
		(stroke
			(width 0.08255)
			(type default)
		)
		(layer "In5.Cu")
	)
	(gr_line
		(start 13.191744 -343.990676)
		(end 13.450062 -344.036396)
		(stroke
			(width 0.08255)
			(type default)
		)
		(layer "In5.Cu")
	)
	(gr_line
		(start 13.198094 -278.342344)
		(end 13.22832 -278.321262)
		(stroke
			(width 0.08255)
			(type default)
		)
		(layer "In5.Cu")
	)
	(gr_line
		(start 13.288772 -177.37455)
		(end 13.50391 -177.525172)
		(stroke
			(width 0.08255)
			(type default)
		)
		(layer "In5.Cu")
	)
	(gr_line
		(start 13.292328 -144.375124)
		(end 13.429234 -143.597884)
		(stroke
			(width 0.08255)
			(type default)
		)
		(layer "In5.Cu")
	)
	(gr_line
		(start 13.36167 -307.429662)
		(end 13.36802 -307.393594)
		(stroke
			(width 0.08255)
			(type default)
		)
		(layer "In5.Cu")
	)
	(gr_line
		(start 13.36802 -307.393594)
		(end 13.389102 -307.363368)
		(stroke
			(width 0.08255)
			(type default)
		)
		(layer "In5.Cu")
	)
	(gr_line
		(start 13.380212 -320.574416)
		(end 13.401294 -320.54419)
		(stroke
			(width 0.08255)
			(type default)
		)
		(layer "In5.Cu")
	)
	(gr_line
		(start 13.399008 -301.43958)
		(end 13.41755 -301.426626)
		(stroke
			(width 0.08255)
			(type default)
		)
		(layer "In5.Cu")
	)
	(gr_line
		(start 13.401294 -320.54419)
		(end 13.407644 -320.508376)
		(stroke
			(width 0.08255)
			(type default)
		)
		(layer "In5.Cu")
	)
	(gr_line
		(start 13.41755 -301.426626)
		(end 13.417804 -301.426372)
		(stroke
			(width 0.08255)
			(type default)
		)
		(layer "In5.Cu")
	)
	(gr_line
		(start 13.417804 -301.426372)
		(end 13.430504 -301.408084)
		(stroke
			(width 0.08255)
			(type default)
		)
		(layer "In5.Cu")
	)
	(gr_line
		(start 13.422376 -217.012012)
		(end 13.443458 -216.981786)
		(stroke
			(width 0.08255)
			(type default)
		)
		(layer "In5.Cu")
	)
	(gr_line
		(start 13.431266 -337.499706)
		(end 13.715238 -337.905598)
		(stroke
			(width 0.08255)
			(type default)
		)
		(layer "In5.Cu")
	)
	(gr_line
		(start 13.443458 -216.981786)
		(end 13.449808 -216.945718)
		(stroke
			(width 0.08255)
			(type default)
		)
		(layer "In5.Cu")
	)
	(gr_line
		(start 13.450062 -344.036396)
		(end 13.734288 -344.442034)
		(stroke
			(width 0.08255)
			(type default)
		)
		(layer "In5.Cu")
	)
	(gr_line
		(start 13.529564 -143.029432)
		(end 13.66647 -142.252192)
		(stroke
			(width 0.08255)
			(type default)
		)
		(layer "In5.Cu")
	)
	(gr_line
		(start 13.669772 -338.16417)
		(end 13.715238 -337.905598)
		(stroke
			(width 0.08255)
			(type default)
		)
		(layer "In5.Cu")
	)
	(gr_line
		(start 13.686282 -338.81187)
		(end 14.137386 -339.456268)
		(stroke
			(width 0.08255)
			(type default)
		)
		(layer "In5.Cu")
	)
	(gr_line
		(start 13.688568 -344.700606)
		(end 13.734288 -344.442034)
		(stroke
			(width 0.08255)
			(type default)
		)
		(layer "In5.Cu")
	)
	(gr_line
		(start 13.704062 -345.34729)
		(end 14.157198 -345.994482)
		(stroke
			(width 0.08255)
			(type default)
		)
		(layer "In5.Cu")
	)
	(gr_line
		(start 13.713206 -470.944448)
		(end 13.719556 -470.980262)
		(stroke
			(width 0.08255)
			(type default)
		)
		(layer "In5.Cu")
	)
	(gr_line
		(start 13.719556 -470.980262)
		(end 13.740638 -471.010488)
		(stroke
			(width 0.08255)
			(type default)
		)
		(layer "In5.Cu")
	)
	(gr_line
		(start 13.861796 -298.604178)
		(end 13.880084 -298.591478)
		(stroke
			(width 0.08255)
			(type default)
		)
		(layer "In5.Cu")
	)
	(gr_line
		(start 13.880084 -298.591478)
		(end 13.892784 -298.57319)
		(stroke
			(width 0.08255)
			(type default)
		)
		(layer "In5.Cu")
	)
	(gr_line
		(start 13.898118 -206.62392)
		(end 13.904468 -206.587852)
		(stroke
			(width 0.08255)
			(type default)
		)
		(layer "In5.Cu")
	)
	(gr_line
		(start 13.904468 -206.587852)
		(end 13.92555 -206.557626)
		(stroke
			(width 0.08255)
			(type default)
		)
		(layer "In5.Cu")
	)
	(gr_line
		(start 13.908278 -322.904866)
		(end 13.92936 -322.87464)
		(stroke
			(width 0.08255)
			(type default)
		)
		(layer "In5.Cu")
	)
	(gr_line
		(start 13.92936 -322.87464)
		(end 13.93571 -322.838572)
		(stroke
			(width 0.08255)
			(type default)
		)
		(layer "In5.Cu")
	)
	(gr_line
		(start 13.934948 -461.596994)
		(end 13.941298 -461.633062)
		(stroke
			(width 0.08255)
			(type default)
		)
		(layer "In5.Cu")
	)
	(gr_line
		(start 13.941298 -461.633062)
		(end 13.96238 -461.663288)
		(stroke
			(width 0.08255)
			(type default)
		)
		(layer "In5.Cu")
	)
	(gr_line
		(start 13.956538 -338.573618)
		(end 14.21511 -338.619084)
		(stroke
			(width 0.08255)
			(type default)
		)
		(layer "In5.Cu")
	)
	(gr_line
		(start 13.957554 -140.600938)
		(end 13.96111 -140.58011)
		(stroke
			(width 0.08255)
			(type default)
		)
		(layer "In5.Cu")
	)
	(gr_line
		(start 13.957554 -140.600684)
		(end 13.957554 -140.601446)
		(stroke
			(width 0.08255)
			(type default)
		)
		(layer "In5.Cu")
	)
	(gr_line
		(start 13.957554 -140.559536)
		(end 13.96111 -140.58011)
		(stroke
			(width 0.08255)
			(type default)
		)
		(layer "In5.Cu")
	)
	(gr_line
		(start 13.975334 -345.110054)
		(end 14.233906 -345.155774)
		(stroke
			(width 0.08255)
			(type default)
		)
		(layer "In5.Cu")
	)
	(gr_line
		(start 13.996416 -177.438304)
		(end 14.147038 -177.22342)
		(stroke
			(width 0.08255)
			(type default)
		)
		(layer "In5.Cu")
	)
	(gr_line
		(start 14.096492 -177.784252)
		(end 14.873224 -177.6476)
		(stroke
			(width 0.08255)
			(type default)
		)
		(layer "In5.Cu")
	)
	(gr_line
		(start 14.1097 -354.574348)
		(end 14.130782 -354.604574)
		(stroke
			(width 0.08255)
			(type default)
		)
		(layer "In5.Cu")
	)
	(gr_line
		(start 14.130782 -354.604574)
		(end 14.137132 -354.640642)
		(stroke
			(width 0.08255)
			(type default)
		)
		(layer "In5.Cu")
	)
	(gr_line
		(start 14.147038 -177.22342)
		(end 14.634718 -177.137568)
		(stroke
			(width 0.08255)
			(type default)
		)
		(layer "In5.Cu")
	)
	(gr_line
		(start 14.21511 -338.619084)
		(end 14.499082 -339.024976)
		(stroke
			(width 0.08255)
			(type default)
		)
		(layer "In5.Cu")
	)
	(gr_line
		(start 14.233906 -345.155774)
		(end 14.517878 -345.561666)
		(stroke
			(width 0.08255)
			(type default)
		)
		(layer "In5.Cu")
	)
	(gr_line
		(start 14.24178 -357.283766)
		(end 14.24813 -357.319834)
		(stroke
			(width 0.08255)
			(type default)
		)
		(layer "In5.Cu")
	)
	(gr_line
		(start 14.24813 -357.319834)
		(end 14.269212 -357.35006)
		(stroke
			(width 0.08255)
			(type default)
		)
		(layer "In5.Cu")
	)
	(gr_line
		(start 14.256512 -235.262166)
		(end 14.277594 -235.292392)
		(stroke
			(width 0.08255)
			(type default)
		)
		(layer "In5.Cu")
	)
	(gr_line
		(start 14.256512 -206.084932)
		(end 14.709902 -205.437232)
		(stroke
			(width 0.08255)
			(type default)
		)
		(layer "In5.Cu")
	)
	(gr_line
		(start 14.272514 -219.80906)
		(end 14.290294 -219.782136)
		(stroke
			(width 0.08255)
			(type default)
		)
		(layer "In5.Cu")
	)
	(gr_line
		(start 14.277594 -235.292392)
		(end 14.283944 -235.32846)
		(stroke
			(width 0.08255)
			(type default)
		)
		(layer "In5.Cu")
	)
	(gr_line
		(start 14.290294 -219.782136)
		(end 14.295882 -219.750386)
		(stroke
			(width 0.08255)
			(type default)
		)
		(layer "In5.Cu")
	)
	(gr_line
		(start 14.326616 -307.723794)
		(end 14.332966 -307.687726)
		(stroke
			(width 0.08255)
			(type default)
		)
		(layer "In5.Cu")
	)
	(gr_line
		(start 14.332966 -307.687726)
		(end 14.354048 -307.6575)
		(stroke
			(width 0.08255)
			(type default)
		)
		(layer "In5.Cu")
	)
	(gr_line
		(start 14.453362 -339.283294)
		(end 14.499082 -339.024976)
		(stroke
			(width 0.08255)
			(type default)
		)
		(layer "In5.Cu")
	)
	(gr_line
		(start 14.472412 -345.820238)
		(end 14.517878 -345.561666)
		(stroke
			(width 0.08255)
			(type default)
		)
		(layer "In5.Cu")
	)
	(gr_line
		(start 14.480032 -293.361618)
		(end 14.49832 -293.348918)
		(stroke
			(width 0.08255)
			(type default)
		)
		(layer "In5.Cu")
	)
	(gr_line
		(start 14.487906 -346.466922)
		(end 14.941042 -347.114114)
		(stroke
			(width 0.08255)
			(type default)
		)
		(layer "In5.Cu")
	)
	(gr_line
		(start 14.49832 -293.348918)
		(end 14.51102 -293.33063)
		(stroke
			(width 0.08255)
			(type default)
		)
		(layer "In5.Cu")
	)
	(gr_line
		(start 14.528546 -206.321152)
		(end 14.786864 -206.275432)
		(stroke
			(width 0.08255)
			(type default)
		)
		(layer "In5.Cu")
	)
	(gr_line
		(start 14.588998 -470.616788)
		(end 14.595348 -470.652856)
		(stroke
			(width 0.08255)
			(type default)
		)
		(layer "In5.Cu")
	)
	(gr_line
		(start 14.595348 -470.652856)
		(end 14.61643 -470.683082)
		(stroke
			(width 0.08255)
			(type default)
		)
		(layer "In5.Cu")
	)
	(gr_line
		(start 14.632178 -208.18983)
		(end 14.638782 -208.152492)
		(stroke
			(width 0.08255)
			(type default)
		)
		(layer "In5.Cu")
	)
	(gr_line
		(start 14.634718 -177.137568)
		(end 14.849602 -177.287936)
		(stroke
			(width 0.08255)
			(type default)
		)
		(layer "In5.Cu")
	)
	(gr_line
		(start 14.638782 -208.152492)
		(end 14.641068 -208.149444)
		(stroke
			(width 0.08255)
			(type default)
		)
		(layer "In5.Cu")
	)
	(gr_line
		(start 14.641068 -208.148682)
		(end 14.641068 -208.149444)
		(stroke
			(width 0.08255)
			(type default)
		)
		(layer "In5.Cu")
	)
	(gr_line
		(start 14.641068 -208.148682)
		(end 14.661642 -208.119218)
		(stroke
			(width 0.08255)
			(type default)
		)
		(layer "In5.Cu")
	)
	(gr_line
		(start 14.729968 -396.51305)
		(end 14.742668 -396.531338)
		(stroke
			(width 0.08255)
			(type default)
		)
		(layer "In5.Cu")
	)
	(gr_line
		(start 14.736826 -352.378264)
		(end 14.746478 -352.392234)
		(stroke
			(width 0.08255)
			(type default)
		)
		(layer "In5.Cu")
	)
	(gr_line
		(start 14.742668 -396.531338)
		(end 14.760956 -396.544038)
		(stroke
			(width 0.08255)
			(type default)
		)
		(layer "In5.Cu")
	)
	(gr_line
		(start 14.759178 -346.229686)
		(end 15.01775 -346.275152)
		(stroke
			(width 0.08255)
			(type default)
		)
		(layer "In5.Cu")
	)
	(gr_line
		(start 14.780006 -453.585834)
		(end 14.786356 -453.621902)
		(stroke
			(width 0.08255)
			(type default)
		)
		(layer "In5.Cu")
	)
	(gr_line
		(start 14.786356 -453.621902)
		(end 14.807692 -453.652636)
		(stroke
			(width 0.08255)
			(type default)
		)
		(layer "In5.Cu")
	)
	(gr_line
		(start 14.786864 -206.275432)
		(end 15.07109 -205.869794)
		(stroke
			(width 0.08255)
			(type default)
		)
		(layer "In5.Cu")
	)
	(gr_line
		(start 14.812772 -378.240036)
		(end 14.819122 -378.276104)
		(stroke
			(width 0.08255)
			(type default)
		)
		(layer "In5.Cu")
	)
	(gr_line
		(start 14.819122 -378.276104)
		(end 14.840204 -378.30633)
		(stroke
			(width 0.08255)
			(type default)
		)
		(layer "In5.Cu")
	)
	(gr_line
		(start 14.861286 -459.402688)
		(end 14.867636 -459.438248)
		(stroke
			(width 0.08255)
			(type default)
		)
		(layer "In5.Cu")
	)
	(gr_line
		(start 14.862556 -192.94475)
		(end 14.879574 -192.932812)
		(stroke
			(width 0.08255)
			(type default)
		)
		(layer "In5.Cu")
	)
	(gr_line
		(start 14.867636 -459.438248)
		(end 14.88821 -459.467458)
		(stroke
			(width 0.08255)
			(type default)
		)
		(layer "In5.Cu")
	)
	(gr_line
		(start 14.879574 -192.932812)
		(end 14.88059 -192.931542)
		(stroke
			(width 0.08255)
			(type default)
		)
		(layer "In5.Cu")
	)
	(gr_line
		(start 14.88059 -192.931542)
		(end 14.89202 -192.915286)
		(stroke
			(width 0.08255)
			(type default)
		)
		(layer "In5.Cu")
	)
	(gr_line
		(start 14.921484 -140.873988)
		(end 14.92504 -140.85316)
		(stroke
			(width 0.08255)
			(type default)
		)
		(layer "In5.Cu")
	)
	(gr_line
		(start 14.921484 -140.873734)
		(end 14.921484 -140.874496)
		(stroke
			(width 0.08255)
			(type default)
		)
		(layer "In5.Cu")
	)
	(gr_line
		(start 14.921484 -140.832586)
		(end 14.92504 -140.85316)
		(stroke
			(width 0.08255)
			(type default)
		)
		(layer "In5.Cu")
	)
	(gr_line
		(start 14.99743 -290.803584)
		(end 15.015718 -290.790884)
		(stroke
			(width 0.08255)
			(type default)
		)
		(layer "In5.Cu")
	)
	(gr_line
		(start 15.010384 -352.144838)
		(end 15.074392 -352.189796)
		(stroke
			(width 0.08255)
			(type default)
		)
		(layer "In5.Cu")
	)
	(gr_line
		(start 15.014956 -305.0413)
		(end 15.027656 -305.023012)
		(stroke
			(width 0.08255)
			(type default)
		)
		(layer "In5.Cu")
	)
	(gr_line
		(start 15.015718 -290.790884)
		(end 15.028418 -290.772596)
		(stroke
			(width 0.08255)
			(type default)
		)
		(layer "In5.Cu")
	)
	(gr_line
		(start 15.01775 -346.275152)
		(end 15.301722 -346.681044)
		(stroke
			(width 0.08255)
			(type default)
		)
		(layer "In5.Cu")
	)
	(gr_line
		(start 15.025116 -254.183642)
		(end 15.031466 -254.21971)
		(stroke
			(width 0.08255)
			(type default)
		)
		(layer "In5.Cu")
	)
	(gr_line
		(start 15.02537 -205.611222)
		(end 15.07109 -205.869794)
		(stroke
			(width 0.08255)
			(type default)
		)
		(layer "In5.Cu")
	)
	(gr_line
		(start 15.027656 -305.023012)
		(end 15.045944 -305.010312)
		(stroke
			(width 0.08255)
			(type default)
		)
		(layer "In5.Cu")
	)
	(gr_line
		(start 15.031466 -254.21971)
		(end 15.052548 -254.249936)
		(stroke
			(width 0.08255)
			(type default)
		)
		(layer "In5.Cu")
	)
	(gr_line
		(start 15.040102 -204.965808)
		(end 15.493746 -204.317854)
		(stroke
			(width 0.08255)
			(type default)
		)
		(layer "In5.Cu")
	)
	(gr_line
		(start 15.074392 -352.189796)
		(end 15.092934 -352.29419)
		(stroke
			(width 0.08255)
			(type default)
		)
		(layer "In5.Cu")
	)
	(gr_line
		(start 15.10665 -449.678552)
		(end 15.113 -449.71462)
		(stroke
			(width 0.08255)
			(type default)
		)
		(layer "In5.Cu")
	)
	(gr_line
		(start 15.113 -449.71462)
		(end 15.134082 -449.744846)
		(stroke
			(width 0.08255)
			(type default)
		)
		(layer "In5.Cu")
	)
	(gr_line
		(start 15.187168 -405.473662)
		(end 15.217394 -405.494744)
		(stroke
			(width 0.08255)
			(type default)
		)
		(layer "In5.Cu")
	)
	(gr_line
		(start 15.217394 -405.494744)
		(end 15.253462 -405.501094)
		(stroke
			(width 0.08255)
			(type default)
		)
		(layer "In5.Cu")
	)
	(gr_line
		(start 15.22984 -180.789326)
		(end 15.265908 -180.782976)
		(stroke
			(width 0.08255)
			(type default)
		)
		(layer "In5.Cu")
	)
	(gr_line
		(start 15.254478 -307.999892)
		(end 15.260828 -307.964078)
		(stroke
			(width 0.08255)
			(type default)
		)
		(layer "In5.Cu")
	)
	(gr_line
		(start 15.256002 -346.939362)
		(end 15.301722 -346.681044)
		(stroke
			(width 0.08255)
			(type default)
		)
		(layer "In5.Cu")
	)
	(gr_line
		(start 15.260828 -307.964078)
		(end 15.28191 -307.933852)
		(stroke
			(width 0.08255)
			(type default)
		)
		(layer "In5.Cu")
	)
	(gr_line
		(start 15.265908 -180.782976)
		(end 15.296134 -180.761894)
		(stroke
			(width 0.08255)
			(type default)
		)
		(layer "In5.Cu")
	)
	(gr_line
		(start 15.312136 -205.201774)
		(end 15.570708 -205.156054)
		(stroke
			(width 0.08255)
			(type default)
		)
		(layer "In5.Cu")
	)
	(gr_line
		(start 15.330678 -355.689408)
		(end 15.467584 -356.465124)
		(stroke
			(width 0.08255)
			(type default)
		)
		(layer "In5.Cu")
	)
	(gr_line
		(start 15.467076 -341.908638)
		(end 15.603982 -342.684354)
		(stroke
			(width 0.08255)
			(type default)
		)
		(layer "In5.Cu")
	)
	(gr_line
		(start 15.47114 -244.110764)
		(end 15.476728 -244.141752)
		(stroke
			(width 0.08255)
			(type default)
		)
		(layer "In5.Cu")
	)
	(gr_line
		(start 15.476728 -244.141752)
		(end 15.493492 -244.167406)
		(stroke
			(width 0.08255)
			(type default)
		)
		(layer "In5.Cu")
	)
	(gr_line
		(start 15.56766 -357.032814)
		(end 15.574518 -357.071168)
		(stroke
			(width 0.08255)
			(type default)
		)
		(layer "In5.Cu")
	)
	(gr_line
		(start 15.570708 -205.156054)
		(end 15.854934 -204.750416)
		(stroke
			(width 0.08255)
			(type default)
		)
		(layer "In5.Cu")
	)
	(gr_line
		(start 15.574518 -357.071168)
		(end 15.59687 -357.103172)
		(stroke
			(width 0.08255)
			(type default)
		)
		(layer "In5.Cu")
	)
	(gr_line
		(start 15.58925 -293.70147)
		(end 15.607538 -293.68877)
		(stroke
			(width 0.08255)
			(type default)
		)
		(layer "In5.Cu")
	)
	(gr_line
		(start 15.607538 -293.68877)
		(end 15.620238 -293.670482)
		(stroke
			(width 0.08255)
			(type default)
		)
		(layer "In5.Cu")
	)
	(gr_line
		(start 15.651988 -340.999064)
		(end 15.67307 -341.02929)
		(stroke
			(width 0.08255)
			(type default)
		)
		(layer "In5.Cu")
	)
	(gr_line
		(start 15.67307 -341.02929)
		(end 15.67942 -341.065104)
		(stroke
			(width 0.08255)
			(type default)
		)
		(layer "In5.Cu")
	)
	(gr_line
		(start 15.676372 -355.588062)
		(end 15.89151 -355.73843)
		(stroke
			(width 0.08255)
			(type default)
		)
		(layer "In5.Cu")
	)
	(gr_line
		(start 15.703804 -343.25179)
		(end 15.840964 -344.029538)
		(stroke
			(width 0.08255)
			(type default)
		)
		(layer "In5.Cu")
	)
	(gr_line
		(start 15.746222 -168.18356)
		(end 15.896844 -167.968422)
		(stroke
			(width 0.08255)
			(type default)
		)
		(layer "In5.Cu")
	)
	(gr_line
		(start 15.746476 -377.936506)
		(end 15.752826 -377.97232)
		(stroke
			(width 0.08255)
			(type default)
		)
		(layer "In5.Cu")
	)
	(gr_line
		(start 15.752826 -377.97232)
		(end 15.773908 -378.002546)
		(stroke
			(width 0.08255)
			(type default)
		)
		(layer "In5.Cu")
	)
	(gr_line
		(start 15.800578 -305.59248)
		(end 15.813278 -305.574192)
		(stroke
			(width 0.08255)
			(type default)
		)
		(layer "In5.Cu")
	)
	(gr_line
		(start 15.809214 -204.491844)
		(end 15.854934 -204.750416)
		(stroke
			(width 0.08255)
			(type default)
		)
		(layer "In5.Cu")
	)
	(gr_line
		(start 15.81277 -341.807038)
		(end 16.027654 -341.957406)
		(stroke
			(width 0.08255)
			(type default)
		)
		(layer "In5.Cu")
	)
	(gr_line
		(start 15.813278 -305.574192)
		(end 15.831566 -305.561492)
		(stroke
			(width 0.08255)
			(type default)
		)
		(layer "In5.Cu")
	)
	(gr_line
		(start 15.826994 -356.441502)
		(end 15.977616 -356.22611)
		(stroke
			(width 0.08255)
			(type default)
		)
		(layer "In5.Cu")
	)
	(gr_line
		(start 15.84452 -168.530016)
		(end 16.623792 -168.392602)
		(stroke
			(width 0.08255)
			(type default)
		)
		(layer "In5.Cu")
	)
	(gr_line
		(start 15.846806 -464.35518)
		(end 15.859506 -464.373468)
		(stroke
			(width 0.08255)
			(type default)
		)
		(layer "In5.Cu")
	)
	(gr_line
		(start 15.859506 -464.373468)
		(end 15.877794 -464.386168)
		(stroke
			(width 0.08255)
			(type default)
		)
		(layer "In5.Cu")
	)
	(gr_line
		(start 15.89151 -355.73843)
		(end 15.977616 -356.22611)
		(stroke
			(width 0.08255)
			(type default)
		)
		(layer "In5.Cu")
	)
	(gr_line
		(start 15.896844 -167.968422)
		(end 16.384524 -167.882316)
		(stroke
			(width 0.08255)
			(type default)
		)
		(layer "In5.Cu")
	)
	(gr_line
		(start 15.909036 -348.496382)
		(end 15.921736 -348.51467)
		(stroke
			(width 0.08255)
			(type default)
		)
		(layer "In5.Cu")
	)
	(gr_line
		(start 15.921736 -348.51467)
		(end 15.940024 -348.52737)
		(stroke
			(width 0.08255)
			(type default)
		)
		(layer "In5.Cu")
	)
	(gr_line
		(start 15.931896 -448.593718)
		(end 15.938246 -448.629786)
		(stroke
			(width 0.08255)
			(type default)
		)
		(layer "In5.Cu")
	)
	(gr_line
		(start 15.938246 -448.629786)
		(end 15.959328 -448.660012)
		(stroke
			(width 0.08255)
			(type default)
		)
		(layer "In5.Cu")
	)
	(gr_line
		(start 15.941548 -344.599006)
		(end 16.078454 -345.374976)
		(stroke
			(width 0.08255)
			(type default)
		)
		(layer "In5.Cu")
	)
	(gr_line
		(start 15.946374 -140.782294)
		(end 15.94993 -140.761466)
		(stroke
			(width 0.08255)
			(type default)
		)
		(layer "In5.Cu")
	)
	(gr_line
		(start 15.946374 -140.78204)
		(end 15.946374 -140.782802)
		(stroke
			(width 0.08255)
			(type default)
		)
		(layer "In5.Cu")
	)
	(gr_line
		(start 15.946374 -140.740638)
		(end 15.94993 -140.761466)
		(stroke
			(width 0.08255)
			(type default)
		)
		(layer "In5.Cu")
	)
	(gr_line
		(start 15.960598 -177.45583)
		(end 15.996666 -177.44948)
		(stroke
			(width 0.08255)
			(type default)
		)
		(layer "In5.Cu")
	)
	(gr_line
		(start 15.963392 -342.660224)
		(end 16.11376 -342.44534)
		(stroke
			(width 0.08255)
			(type default)
		)
		(layer "In5.Cu")
	)
	(gr_line
		(start 15.992856 -208.068418)
		(end 15.999206 -208.03235)
		(stroke
			(width 0.08255)
			(type default)
		)
		(layer "In5.Cu")
	)
	(gr_line
		(start 15.996666 -177.44948)
		(end 16.026892 -177.428398)
		(stroke
			(width 0.08255)
			(type default)
		)
		(layer "In5.Cu")
	)
	(gr_line
		(start 15.999206 -208.03235)
		(end 16.020288 -208.002124)
		(stroke
			(width 0.08255)
			(type default)
		)
		(layer "In5.Cu")
	)
	(gr_line
		(start 16.027654 -341.957406)
		(end 16.11376 -342.44534)
		(stroke
			(width 0.08255)
			(type default)
		)
		(layer "In5.Cu")
	)
	(gr_line
		(start 16.028924 -359.863136)
		(end 16.041624 -359.881424)
		(stroke
			(width 0.08255)
			(type default)
		)
		(layer "In5.Cu")
	)
	(gr_line
		(start 16.029178 -183.848756)
		(end 16.065246 -183.842406)
		(stroke
			(width 0.08255)
			(type default)
		)
		(layer "In5.Cu")
	)
	(gr_line
		(start 16.041624 -359.881424)
		(end 16.059912 -359.894124)
		(stroke
			(width 0.08255)
			(type default)
		)
		(layer "In5.Cu")
	)
	(gr_line
		(start 16.050006 -343.152476)
		(end 16.265144 -343.303352)
		(stroke
			(width 0.08255)
			(type default)
		)
		(layer "In5.Cu")
	)
	(gr_line
		(start 16.065246 -183.842406)
		(end 16.095472 -183.821324)
		(stroke
			(width 0.08255)
			(type default)
		)
		(layer "In5.Cu")
	)
	(gr_line
		(start 16.087852 -351.57156)
		(end 16.094202 -351.607628)
		(stroke
			(width 0.08255)
			(type default)
		)
		(layer "In5.Cu")
	)
	(gr_line
		(start 16.094202 -351.607628)
		(end 16.115284 -351.637854)
		(stroke
			(width 0.08255)
			(type default)
		)
		(layer "In5.Cu")
	)
	(gr_line
		(start 16.109188 -308.464458)
		(end 16.115538 -308.42839)
		(stroke
			(width 0.08255)
			(type default)
		)
		(layer "In5.Cu")
	)
	(gr_line
		(start 16.115538 -308.42839)
		(end 16.13662 -308.398164)
		(stroke
			(width 0.08255)
			(type default)
		)
		(layer "In5.Cu")
	)
	(gr_line
		(start 16.188944 -82.294222)
		(end 16.195294 -82.258154)
		(stroke
			(width 0.08255)
			(type default)
		)
		(layer "In5.Cu")
	)
	(gr_line
		(start 16.195294 -82.258154)
		(end 16.216376 -82.227928)
		(stroke
			(width 0.08255)
			(type default)
		)
		(layer "In5.Cu")
	)
	(gr_line
		(start 16.200628 -344.005916)
		(end 16.35125 -343.791032)
		(stroke
			(width 0.08255)
			(type default)
		)
		(layer "In5.Cu")
	)
	(gr_line
		(start 16.23568 -350.451166)
		(end 16.256762 -350.481392)
		(stroke
			(width 0.08255)
			(type default)
		)
		(layer "In5.Cu")
	)
	(gr_line
		(start 16.256762 -350.481392)
		(end 16.263112 -350.51746)
		(stroke
			(width 0.08255)
			(type default)
		)
		(layer "In5.Cu")
	)
	(gr_line
		(start 16.265144 -343.303352)
		(end 16.35125 -343.791032)
		(stroke
			(width 0.08255)
			(type default)
		)
		(layer "In5.Cu")
	)
	(gr_line
		(start 16.287496 -344.498422)
		(end 16.50238 -344.649044)
		(stroke
			(width 0.08255)
			(type default)
		)
		(layer "In5.Cu")
	)
	(gr_line
		(start 16.31442 -346.712794)
		(end 16.32077 -346.748608)
		(stroke
			(width 0.08255)
			(type default)
		)
		(layer "In5.Cu")
	)
	(gr_line
		(start 16.32077 -346.748608)
		(end 16.341852 -346.778834)
		(stroke
			(width 0.08255)
			(type default)
		)
		(layer "In5.Cu")
	)
	(gr_line
		(start 16.373856 -170.618658)
		(end 16.524224 -170.403774)
		(stroke
			(width 0.08255)
			(type default)
		)
		(layer "In5.Cu")
	)
	(gr_line
		(start 16.384524 -167.882316)
		(end 16.599662 -168.032938)
		(stroke
			(width 0.08255)
			(type default)
		)
		(layer "In5.Cu")
	)
	(gr_line
		(start 16.420084 -176.715674)
		(end 16.46555 -176.457356)
		(stroke
			(width 0.08255)
			(type default)
		)
		(layer "In5.Cu")
	)
	(gr_line
		(start 16.438118 -345.351608)
		(end 16.588486 -345.136724)
		(stroke
			(width 0.08255)
			(type default)
		)
		(layer "In5.Cu")
	)
	(gr_line
		(start 16.46555 -176.457356)
		(end 16.871442 -176.173384)
		(stroke
			(width 0.08255)
			(type default)
		)
		(layer "In5.Cu")
	)
	(gr_line
		(start 16.475456 -170.964606)
		(end 17.251934 -170.8277)
		(stroke
			(width 0.08255)
			(type default)
		)
		(layer "In5.Cu")
	)
	(gr_line
		(start 16.476726 -306.227988)
		(end 16.489426 -306.2097)
		(stroke
			(width 0.08255)
			(type default)
		)
		(layer "In5.Cu")
	)
	(gr_line
		(start 16.489426 -306.2097)
		(end 16.507714 -306.197)
		(stroke
			(width 0.08255)
			(type default)
		)
		(layer "In5.Cu")
	)
	(gr_line
		(start 16.50238 -344.649044)
		(end 16.588486 -345.136724)
		(stroke
			(width 0.08255)
			(type default)
		)
		(layer "In5.Cu")
	)
	(gr_line
		(start 16.524224 -170.403774)
		(end 17.012158 -170.317922)
		(stroke
			(width 0.08255)
			(type default)
		)
		(layer "In5.Cu")
	)
	(gr_line
		(start 16.658844 -176.98593)
		(end 17.301972 -176.535334)
		(stroke
			(width 0.08255)
			(type default)
		)
		(layer "In5.Cu")
	)
	(gr_line
		(start 16.668496 -358.635808)
		(end 16.68145 -358.654096)
		(stroke
			(width 0.08255)
			(type default)
		)
		(layer "In5.Cu")
	)
	(gr_line
		(start 16.68145 -377.601226)
		(end 16.6878 -377.637294)
		(stroke
			(width 0.08255)
			(type default)
		)
		(layer "In5.Cu")
	)
	(gr_line
		(start 16.68145 -358.654096)
		(end 16.699738 -358.66705)
		(stroke
			(width 0.08255)
			(type default)
		)
		(layer "In5.Cu")
	)
	(gr_line
		(start 16.6878 -377.637294)
		(end 16.708882 -377.66752)
		(stroke
			(width 0.08255)
			(type default)
		)
		(layer "In5.Cu")
	)
	(gr_line
		(start 16.730472 -462.107788)
		(end 16.74241 -462.124806)
		(stroke
			(width 0.08255)
			(type default)
		)
		(layer "In5.Cu")
	)
	(gr_line
		(start 16.74241 -462.124806)
		(end 16.759428 -462.136744)
		(stroke
			(width 0.08255)
			(type default)
		)
		(layer "In5.Cu")
	)
	(gr_line
		(start 16.76527 -256.224278)
		(end 16.795496 -256.24536)
		(stroke
			(width 0.08255)
			(type default)
		)
		(layer "In5.Cu")
	)
	(gr_line
		(start 16.795496 -256.24536)
		(end 16.83131 -256.25171)
		(stroke
			(width 0.08255)
			(type default)
		)
		(layer "In5.Cu")
	)
	(gr_line
		(start 16.821404 -200.748646)
		(end 16.834104 -200.730358)
		(stroke
			(width 0.08255)
			(type default)
		)
		(layer "In5.Cu")
	)
	(gr_line
		(start 16.834104 -200.730358)
		(end 16.852392 -200.717658)
		(stroke
			(width 0.08255)
			(type default)
		)
		(layer "In5.Cu")
	)
	(gr_line
		(start 16.869664 -381.203454)
		(end 16.882364 -381.221742)
		(stroke
			(width 0.08255)
			(type default)
		)
		(layer "In5.Cu")
	)
	(gr_line
		(start 16.871442 -176.173384)
		(end 17.129506 -176.219104)
		(stroke
			(width 0.08255)
			(type default)
		)
		(layer "In5.Cu")
	)
	(gr_line
		(start 16.872712 -452.228204)
		(end 16.885412 -452.246492)
		(stroke
			(width 0.08255)
			(type default)
		)
		(layer "In5.Cu")
	)
	(gr_line
		(start 16.882364 -381.221742)
		(end 16.900652 -381.234442)
		(stroke
			(width 0.08255)
			(type default)
		)
		(layer "In5.Cu")
	)
	(gr_line
		(start 16.885412 -452.246492)
		(end 16.9037 -452.259192)
		(stroke
			(width 0.08255)
			(type default)
		)
		(layer "In5.Cu")
	)
	(gr_line
		(start 17.007586 -188.100208)
		(end 17.025874 -188.087508)
		(stroke
			(width 0.08255)
			(type default)
		)
		(layer "In5.Cu")
	)
	(gr_line
		(start 17.012158 -170.317922)
		(end 17.227042 -170.46829)
		(stroke
			(width 0.08255)
			(type default)
		)
		(layer "In5.Cu")
	)
	(gr_line
		(start 17.025874 -188.087508)
		(end 17.038574 -188.06922)
		(stroke
			(width 0.08255)
			(type default)
		)
		(layer "In5.Cu")
	)
	(gr_line
		(start 17.079722 -246.60987)
		(end 17.099026 -246.639588)
		(stroke
			(width 0.08255)
			(type default)
		)
		(layer "In5.Cu")
	)
	(gr_line
		(start 17.091914 -167.94607)
		(end 17.24279 -167.731186)
		(stroke
			(width 0.08255)
			(type default)
		)
		(layer "In5.Cu")
	)
	(gr_line
		(start 17.099026 -246.639588)
		(end 17.128744 -246.658892)
		(stroke
			(width 0.08255)
			(type default)
		)
		(layer "In5.Cu")
	)
	(gr_line
		(start 17.190974 -168.292526)
		(end 17.968722 -168.155366)
		(stroke
			(width 0.08255)
			(type default)
		)
		(layer "In5.Cu")
	)
	(gr_line
		(start 17.24279 -167.731186)
		(end 17.73047 -167.645334)
		(stroke
			(width 0.08255)
			(type default)
		)
		(layer "In5.Cu")
	)
	(gr_line
		(start 17.256506 -306.79898)
		(end 17.269206 -306.780692)
		(stroke
			(width 0.08255)
			(type default)
		)
		(layer "In5.Cu")
	)
	(gr_line
		(start 17.2593 -348.088712)
		(end 17.272 -348.107)
		(stroke
			(width 0.08255)
			(type default)
		)
		(layer "In5.Cu")
	)
	(gr_line
		(start 17.269206 -306.780692)
		(end 17.287494 -306.767992)
		(stroke
			(width 0.08255)
			(type default)
		)
		(layer "In5.Cu")
	)
	(gr_line
		(start 17.272 -348.107)
		(end 17.290288 -348.1197)
		(stroke
			(width 0.08255)
			(type default)
		)
		(layer "In5.Cu")
	)
	(gr_line
		(start 17.273778 -359.068116)
		(end 17.304004 -359.089198)
		(stroke
			(width 0.08255)
			(type default)
		)
		(layer "In5.Cu")
	)
	(gr_line
		(start 17.304004 -359.089198)
		(end 17.339818 -359.095548)
		(stroke
			(width 0.08255)
			(type default)
		)
		(layer "In5.Cu")
	)
	(gr_line
		(start 17.31772 -457.237338)
		(end 17.33042 -457.255626)
		(stroke
			(width 0.08255)
			(type default)
		)
		(layer "In5.Cu")
	)
	(gr_line
		(start 17.33042 -457.255626)
		(end 17.348708 -457.268326)
		(stroke
			(width 0.08255)
			(type default)
		)
		(layer "In5.Cu")
	)
	(gr_line
		(start 17.373854 -353.435666)
		(end 17.82572 -354.08108)
		(stroke
			(width 0.08255)
			(type default)
		)
		(layer "In5.Cu")
	)
	(gr_line
		(start 17.45488 -380.402846)
		(end 17.46758 -380.421134)
		(stroke
			(width 0.08255)
			(type default)
		)
		(layer "In5.Cu")
	)
	(gr_line
		(start 17.46758 -380.421134)
		(end 17.485868 -380.433834)
		(stroke
			(width 0.08255)
			(type default)
		)
		(layer "In5.Cu")
	)
	(gr_line
		(start 17.539208 -175.932084)
		(end 17.584928 -175.673766)
		(stroke
			(width 0.08255)
			(type default)
		)
		(layer "In5.Cu")
	)
	(gr_line
		(start 17.558512 -201.369422)
		(end 17.571212 -201.351134)
		(stroke
			(width 0.08255)
			(type default)
		)
		(layer "In5.Cu")
	)
	(gr_line
		(start 17.571212 -201.351134)
		(end 17.5895 -201.338434)
		(stroke
			(width 0.08255)
			(type default)
		)
		(layer "In5.Cu")
	)
	(gr_line
		(start 17.584928 -175.673766)
		(end 17.990566 -175.38954)
		(stroke
			(width 0.08255)
			(type default)
		)
		(layer "In5.Cu")
	)
	(gr_line
		(start 17.644364 -353.197668)
		(end 17.902936 -353.243388)
		(stroke
			(width 0.08255)
			(type default)
		)
		(layer "In5.Cu")
	)
	(gr_line
		(start 17.719548 -170.381676)
		(end 17.87017 -170.166538)
		(stroke
			(width 0.08255)
			(type default)
		)
		(layer "In5.Cu")
	)
	(gr_line
		(start 17.730216 -451.18909)
		(end 17.742916 -451.207378)
		(stroke
			(width 0.08255)
			(type default)
		)
		(layer "In5.Cu")
	)
	(gr_line
		(start 17.73047 -167.645334)
		(end 17.945354 -167.795702)
		(stroke
			(width 0.08255)
			(type default)
		)
		(layer "In5.Cu")
	)
	(gr_line
		(start 17.742916 -451.207378)
		(end 17.761204 -451.220078)
		(stroke
			(width 0.08255)
			(type default)
		)
		(layer "In5.Cu")
	)
	(gr_line
		(start 17.776698 -176.203102)
		(end 18.421858 -175.751236)
		(stroke
			(width 0.08255)
			(type default)
		)
		(layer "In5.Cu")
	)
	(gr_line
		(start 17.820132 -170.727624)
		(end 18.59661 -170.590718)
		(stroke
			(width 0.08255)
			(type default)
		)
		(layer "In5.Cu")
	)
	(gr_line
		(start 17.87017 -170.166538)
		(end 18.35785 -170.080686)
		(stroke
			(width 0.08255)
			(type default)
		)
		(layer "In5.Cu")
	)
	(gr_line
		(start 17.880076 -407.92908)
		(end 17.90065 -407.932636)
		(stroke
			(width 0.08255)
			(type default)
		)
		(layer "In5.Cu")
	)
	(gr_line
		(start 17.88668 -462.925922)
		(end 17.916906 -462.947004)
		(stroke
			(width 0.08255)
			(type default)
		)
		(layer "In5.Cu")
	)
	(gr_line
		(start 17.90065 -407.932636)
		(end 17.900904 -407.932636)
		(stroke
			(width 0.08255)
			(type default)
		)
		(layer "In5.Cu")
	)
	(gr_line
		(start 17.900904 -407.932636)
		(end 17.921732 -407.92908)
		(stroke
			(width 0.08255)
			(type default)
		)
		(layer "In5.Cu")
	)
	(gr_line
		(start 17.902936 -353.243388)
		(end 18.186908 -353.64928)
		(stroke
			(width 0.08255)
			(type default)
		)
		(layer "In5.Cu")
	)
	(gr_line
		(start 17.916906 -462.947004)
		(end 17.952974 -462.953354)
		(stroke
			(width 0.08255)
			(type default)
		)
		(layer "In5.Cu")
	)
	(gr_line
		(start 17.990566 -175.38954)
		(end 18.248884 -175.43526)
		(stroke
			(width 0.08255)
			(type default)
		)
		(layer "In5.Cu")
	)
	(gr_line
		(start 18.065242 -379.605032)
		(end 18.077942 -379.62332)
		(stroke
			(width 0.08255)
			(type default)
		)
		(layer "In5.Cu")
	)
	(gr_line
		(start 18.077942 -379.62332)
		(end 18.09623 -379.63602)
		(stroke
			(width 0.08255)
			(type default)
		)
		(layer "In5.Cu")
	)
	(gr_line
		(start 18.091404 -173.877732)
		(end 18.127218 -173.871382)
		(stroke
			(width 0.08255)
			(type default)
		)
		(layer "In5.Cu")
	)
	(gr_line
		(start 18.127218 -173.871382)
		(end 18.157444 -173.8503)
		(stroke
			(width 0.08255)
			(type default)
		)
		(layer "In5.Cu")
	)
	(gr_line
		(start 18.141188 -353.907598)
		(end 18.186908 -353.64928)
		(stroke
			(width 0.08255)
			(type default)
		)
		(layer "In5.Cu")
	)
	(gr_line
		(start 18.146522 -475.724728)
		(end 18.159222 -475.743016)
		(stroke
			(width 0.08255)
			(type default)
		)
		(layer "In5.Cu")
	)
	(gr_line
		(start 18.159222 -475.743016)
		(end 18.17751 -475.755716)
		(stroke
			(width 0.08255)
			(type default)
		)
		(layer "In5.Cu")
	)
	(gr_line
		(start 18.189194 -361.384596)
		(end 18.21942 -361.405678)
		(stroke
			(width 0.08255)
			(type default)
		)
		(layer "In5.Cu")
	)
	(gr_line
		(start 18.21942 -361.405678)
		(end 18.255488 -361.412028)
		(stroke
			(width 0.08255)
			(type default)
		)
		(layer "In5.Cu")
	)
	(gr_line
		(start 18.319242 -81.91373)
		(end 18.325592 -81.877662)
		(stroke
			(width 0.08255)
			(type default)
		)
		(layer "In5.Cu")
	)
	(gr_line
		(start 18.325592 -81.877662)
		(end 18.346674 -81.847436)
		(stroke
			(width 0.08255)
			(type default)
		)
		(layer "In5.Cu")
	)
	(gr_line
		(start 18.35785 -170.080686)
		(end 18.572734 -170.231054)
		(stroke
			(width 0.08255)
			(type default)
		)
		(layer "In5.Cu")
	)
	(gr_line
		(start 18.393918 -173.247304)
		(end 18.439638 -172.988986)
		(stroke
			(width 0.08255)
			(type default)
		)
		(layer "In5.Cu")
	)
	(gr_line
		(start 18.439638 -172.988986)
		(end 18.84553 -172.705014)
		(stroke
			(width 0.08255)
			(type default)
		)
		(layer "In5.Cu")
	)
	(gr_line
		(start 18.54327 -202.57389)
		(end 18.55597 -202.555602)
		(stroke
			(width 0.08255)
			(type default)
		)
		(layer "In5.Cu")
	)
	(gr_line
		(start 18.55597 -202.555602)
		(end 18.574258 -202.542902)
		(stroke
			(width 0.08255)
			(type default)
		)
		(layer "In5.Cu")
	)
	(gr_line
		(start 18.558256 -355.127814)
		(end 18.570956 -355.146102)
		(stroke
			(width 0.08255)
			(type default)
		)
		(layer "In5.Cu")
	)
	(gr_line
		(start 18.570956 -355.146102)
		(end 18.589244 -355.158802)
		(stroke
			(width 0.08255)
			(type default)
		)
		(layer "In5.Cu")
	)
	(gr_line
		(start 18.63217 -173.517814)
		(end 19.276822 -173.066456)
		(stroke
			(width 0.08255)
			(type default)
		)
		(layer "In5.Cu")
	)
	(gr_line
		(start 18.645124 -282.649422)
		(end 18.663412 -282.636722)
		(stroke
			(width 0.08255)
			(type default)
		)
		(layer "In5.Cu")
	)
	(gr_line
		(start 18.663412 -282.636722)
		(end 18.676112 -282.618434)
		(stroke
			(width 0.08255)
			(type default)
		)
		(layer "In5.Cu")
	)
	(gr_line
		(start 18.69567 -404.701502)
		(end 18.725896 -404.722584)
		(stroke
			(width 0.08255)
			(type default)
		)
		(layer "In5.Cu")
	)
	(gr_line
		(start 18.725896 -404.722584)
		(end 18.761964 -404.728934)
		(stroke
			(width 0.08255)
			(type default)
		)
		(layer "In5.Cu")
	)
	(gr_line
		(start 18.774156 -89.1921)
		(end 18.777712 -89.21242)
		(stroke
			(width 0.08255)
			(type default)
		)
		(layer "In5.Cu")
	)
	(gr_line
		(start 18.774156 -89.1921)
		(end 18.777712 -89.171526)
		(stroke
			(width 0.08255)
			(type default)
		)
		(layer "In5.Cu")
	)
	(gr_line
		(start 18.777712 -89.212674)
		(end 18.777712 -89.213436)
		(stroke
			(width 0.08255)
			(type default)
		)
		(layer "In5.Cu")
	)
	(gr_line
		(start 18.77822 -359.35031)
		(end 18.798794 -359.353866)
		(stroke
			(width 0.08255)
			(type default)
		)
		(layer "In5.Cu")
	)
	(gr_line
		(start 18.798794 -359.353866)
		(end 18.819368 -359.35031)
		(stroke
			(width 0.08255)
			(type default)
		)
		(layer "In5.Cu")
	)
	(gr_line
		(start 18.84553 -172.705014)
		(end 19.103848 -172.75048)
		(stroke
			(width 0.08255)
			(type default)
		)
		(layer "In5.Cu")
	)
	(gr_line
		(start 19.082766 -478.64014)
		(end 19.095466 -478.658428)
		(stroke
			(width 0.08255)
			(type default)
		)
		(layer "In5.Cu")
	)
	(gr_line
		(start 19.095466 -478.658428)
		(end 19.113754 -478.671128)
		(stroke
			(width 0.08255)
			(type default)
		)
		(layer "In5.Cu")
	)
	(gr_line
		(start 19.287744 -453.493886)
		(end 19.306032 -453.506586)
		(stroke
			(width 0.08255)
			(type default)
		)
		(layer "In5.Cu")
	)
	(gr_line
		(start 19.306032 -453.506586)
		(end 19.318732 -453.524874)
		(stroke
			(width 0.08255)
			(type default)
		)
		(layer "In5.Cu")
	)
	(gr_line
		(start 19.373088 -200.090024)
		(end 19.403314 -200.068942)
		(stroke
			(width 0.08255)
			(type default)
		)
		(layer "In5.Cu")
	)
	(gr_line
		(start 19.403314 -200.068942)
		(end 19.439382 -200.062592)
		(stroke
			(width 0.08255)
			(type default)
		)
		(layer "In5.Cu")
	)
	(gr_line
		(start 19.490182 -454.389744)
		(end 19.502882 -454.408032)
		(stroke
			(width 0.08255)
			(type default)
		)
		(layer "In5.Cu")
	)
	(gr_line
		(start 19.502882 -454.408032)
		(end 19.52117 -454.420732)
		(stroke
			(width 0.08255)
			(type default)
		)
		(layer "In5.Cu")
	)
	(gr_line
		(start 19.51355 -172.463714)
		(end 19.559016 -172.205142)
		(stroke
			(width 0.08255)
			(type default)
		)
		(layer "In5.Cu")
	)
	(gr_line
		(start 19.535902 -202.980036)
		(end 19.548602 -202.961748)
		(stroke
			(width 0.08255)
			(type default)
		)
		(layer "In5.Cu")
	)
	(gr_line
		(start 19.548602 -202.961748)
		(end 19.56689 -202.949048)
		(stroke
			(width 0.08255)
			(type default)
		)
		(layer "In5.Cu")
	)
	(gr_line
		(start 19.559016 -172.205142)
		(end 19.964908 -171.92117)
		(stroke
			(width 0.08255)
			(type default)
		)
		(layer "In5.Cu")
	)
	(gr_line
		(start 19.584162 -466.981286)
		(end 19.614388 -467.002368)
		(stroke
			(width 0.08255)
			(type default)
		)
		(layer "In5.Cu")
	)
	(gr_line
		(start 19.591528 -84.557616)
		(end 19.597878 -84.521802)
		(stroke
			(width 0.08255)
			(type default)
		)
		(layer "In5.Cu")
	)
	(gr_line
		(start 19.597878 -84.521802)
		(end 19.61896 -84.491576)
		(stroke
			(width 0.08255)
			(type default)
		)
		(layer "In5.Cu")
	)
	(gr_line
		(start 19.614388 -467.002368)
		(end 19.650456 -467.008718)
		(stroke
			(width 0.08255)
			(type default)
		)
		(layer "In5.Cu")
	)
	(gr_line
		(start 19.659092 -94.207838)
		(end 19.665442 -94.243652)
		(stroke
			(width 0.08255)
			(type default)
		)
		(layer "In5.Cu")
	)
	(gr_line
		(start 19.665442 -94.243652)
		(end 19.686524 -94.273878)
		(stroke
			(width 0.08255)
			(type default)
		)
		(layer "In5.Cu")
	)
	(gr_line
		(start 19.69389 -89.177114)
		(end 19.697446 -89.197942)
		(stroke
			(width 0.08255)
			(type default)
		)
		(layer "In5.Cu")
	)
	(gr_line
		(start 19.69389 -89.177114)
		(end 19.697446 -89.15654)
		(stroke
			(width 0.08255)
			(type default)
		)
		(layer "In5.Cu")
	)
	(gr_line
		(start 19.697446 -89.197688)
		(end 19.697446 -89.19845)
		(stroke
			(width 0.08255)
			(type default)
		)
		(layer "In5.Cu")
	)
	(gr_line
		(start 19.751802 -172.73397)
		(end 20.395692 -172.28312)
		(stroke
			(width 0.08255)
			(type default)
		)
		(layer "In5.Cu")
	)
	(gr_line
		(start 19.775932 -198.670672)
		(end 19.806158 -198.64959)
		(stroke
			(width 0.08255)
			(type default)
		)
		(layer "In5.Cu")
	)
	(gr_line
		(start 19.806158 -198.64959)
		(end 19.841972 -198.64324)
		(stroke
			(width 0.08255)
			(type default)
		)
		(layer "In5.Cu")
	)
	(gr_line
		(start 19.94027 -170.353736)
		(end 19.976338 -170.347386)
		(stroke
			(width 0.08255)
			(type default)
		)
		(layer "In5.Cu")
	)
	(gr_line
		(start 19.964908 -171.92117)
		(end 20.223226 -171.96689)
		(stroke
			(width 0.08255)
			(type default)
		)
		(layer "In5.Cu")
	)
	(gr_line
		(start 19.976084 -201.561192)
		(end 20.00631 -201.54011)
		(stroke
			(width 0.08255)
			(type default)
		)
		(layer "In5.Cu")
	)
	(gr_line
		(start 19.976338 -170.347386)
		(end 20.006564 -170.326304)
		(stroke
			(width 0.08255)
			(type default)
		)
		(layer "In5.Cu")
	)
	(gr_line
		(start 20.00631 -201.54011)
		(end 20.042378 -201.53376)
		(stroke
			(width 0.08255)
			(type default)
		)
		(layer "In5.Cu")
	)
	(gr_line
		(start 20.01012 -199.962008)
		(end 20.785074 -199.82561)
		(stroke
			(width 0.08255)
			(type default)
		)
		(layer "In5.Cu")
	)
	(gr_line
		(start 20.033234 -200.321672)
		(end 20.248372 -200.47204)
		(stroke
			(width 0.08255)
			(type default)
		)
		(layer "In5.Cu")
	)
	(gr_line
		(start 20.121626 -301.45609)
		(end 20.151852 -301.435008)
		(stroke
			(width 0.08255)
			(type default)
		)
		(layer "In5.Cu")
	)
	(gr_line
		(start 20.151852 -301.435008)
		(end 20.18792 -301.428658)
		(stroke
			(width 0.08255)
			(type default)
		)
		(layer "In5.Cu")
	)
	(gr_line
		(start 20.243038 -459.294992)
		(end 20.273264 -459.316074)
		(stroke
			(width 0.08255)
			(type default)
		)
		(layer "In5.Cu")
	)
	(gr_line
		(start 20.247864 -382.368298)
		(end 20.27809 -382.38938)
		(stroke
			(width 0.08255)
			(type default)
		)
		(layer "In5.Cu")
	)
	(gr_line
		(start 20.248372 -200.47204)
		(end 20.736052 -200.386188)
		(stroke
			(width 0.08255)
			(type default)
		)
		(layer "In5.Cu")
	)
	(gr_line
		(start 20.262596 -351.119186)
		(end 20.280884 -351.131886)
		(stroke
			(width 0.08255)
			(type default)
		)
		(layer "In5.Cu")
	)
	(gr_line
		(start 20.273264 -459.316074)
		(end 20.309078 -459.322424)
		(stroke
			(width 0.08255)
			(type default)
		)
		(layer "In5.Cu")
	)
	(gr_line
		(start 20.27809 -382.38938)
		(end 20.314158 -382.39573)
		(stroke
			(width 0.08255)
			(type default)
		)
		(layer "In5.Cu")
	)
	(gr_line
		(start 20.280884 -351.131886)
		(end 20.293584 -351.150174)
		(stroke
			(width 0.08255)
			(type default)
		)
		(layer "In5.Cu")
	)
	(gr_line
		(start 20.296632 -356.354888)
		(end 20.326858 -356.37597)
		(stroke
			(width 0.08255)
			(type default)
		)
		(layer "In5.Cu")
	)
	(gr_line
		(start 20.306284 -452.567802)
		(end 20.324572 -452.580502)
		(stroke
			(width 0.08255)
			(type default)
		)
		(layer "In5.Cu")
	)
	(gr_line
		(start 20.324572 -452.580502)
		(end 20.337272 -452.59879)
		(stroke
			(width 0.08255)
			(type default)
		)
		(layer "In5.Cu")
	)
	(gr_line
		(start 20.326858 -356.37597)
		(end 20.362672 -356.38232)
		(stroke
			(width 0.08255)
			(type default)
		)
		(layer "In5.Cu")
	)
	(gr_line
		(start 20.329144 -202.41514)
		(end 20.35937 -202.394058)
		(stroke
			(width 0.08255)
			(type default)
		)
		(layer "In5.Cu")
	)
	(gr_line
		(start 20.35302 -302.395382)
		(end 20.384008 -302.373792)
		(stroke
			(width 0.08255)
			(type default)
		)
		(layer "In5.Cu")
	)
	(gr_line
		(start 20.357084 -256.265934)
		(end 20.394422 -256.25933)
		(stroke
			(width 0.08255)
			(type default)
		)
		(layer "In5.Cu")
	)
	(gr_line
		(start 20.35937 -202.394058)
		(end 20.395184 -202.387708)
		(stroke
			(width 0.08255)
			(type default)
		)
		(layer "In5.Cu")
	)
	(gr_line
		(start 20.384008 -302.373792)
		(end 20.421346 -302.367188)
		(stroke
			(width 0.08255)
			(type default)
		)
		(layer "In5.Cu")
	)
	(gr_line
		(start 20.394422 -256.25933)
		(end 20.42541 -256.23774)
		(stroke
			(width 0.08255)
			(type default)
		)
		(layer "In5.Cu")
	)
	(gr_line
		(start 20.429982 -85.003386)
		(end 20.436332 -84.967318)
		(stroke
			(width 0.08255)
			(type default)
		)
		(layer "In5.Cu")
	)
	(gr_line
		(start 20.436332 -84.967318)
		(end 20.457414 -84.937092)
		(stroke
			(width 0.08255)
			(type default)
		)
		(layer "In5.Cu")
	)
	(gr_line
		(start 20.48002 -93.636592)
		(end 20.486624 -93.67393)
		(stroke
			(width 0.08255)
			(type default)
		)
		(layer "In5.Cu")
	)
	(gr_line
		(start 20.486624 -93.67393)
		(end 20.508468 -93.704918)
		(stroke
			(width 0.08255)
			(type default)
		)
		(layer "In5.Cu")
	)
	(gr_line
		(start 20.520152 -276.363938)
		(end 20.53844 -276.351238)
		(stroke
			(width 0.08255)
			(type default)
		)
		(layer "In5.Cu")
	)
	(gr_line
		(start 20.53844 -276.351238)
		(end 20.55114 -276.33295)
		(stroke
			(width 0.08255)
			(type default)
		)
		(layer "In5.Cu")
	)
	(gr_line
		(start 20.557744 -167.698674)
		(end 20.593812 -167.692324)
		(stroke
			(width 0.08255)
			(type default)
		)
		(layer "In5.Cu")
	)
	(gr_line
		(start 20.5613 -352.152712)
		(end 20.574 -352.171)
		(stroke
			(width 0.08255)
			(type default)
		)
		(layer "In5.Cu")
	)
	(gr_line
		(start 20.574 -352.171)
		(end 20.592288 -352.1837)
		(stroke
			(width 0.08255)
			(type default)
		)
		(layer "In5.Cu")
	)
	(gr_line
		(start 20.593812 -167.692324)
		(end 20.624038 -167.671242)
		(stroke
			(width 0.08255)
			(type default)
		)
		(layer "In5.Cu")
	)
	(gr_line
		(start 20.607782 -381.394462)
		(end 20.638008 -381.415544)
		(stroke
			(width 0.08255)
			(type default)
		)
		(layer "In5.Cu")
	)
	(gr_line
		(start 20.632928 -171.67987)
		(end 20.678648 -171.421552)
		(stroke
			(width 0.08255)
			(type default)
		)
		(layer "In5.Cu")
	)
	(gr_line
		(start 20.638008 -381.415544)
		(end 20.674076 -381.421894)
		(stroke
			(width 0.08255)
			(type default)
		)
		(layer "In5.Cu")
	)
	(gr_line
		(start 20.656296 -303.292002)
		(end 20.686522 -303.27092)
		(stroke
			(width 0.08255)
			(type default)
		)
		(layer "In5.Cu")
	)
	(gr_line
		(start 20.678648 -171.421552)
		(end 21.084286 -171.13758)
		(stroke
			(width 0.08255)
			(type default)
		)
		(layer "In5.Cu")
	)
	(gr_line
		(start 20.686522 -303.27092)
		(end 20.72259 -303.26457)
		(stroke
			(width 0.08255)
			(type default)
		)
		(layer "In5.Cu")
	)
	(gr_arc
		(start 20.702778 -350.075246)
		(mid 20.702524 -350.075119)
		(end 20.70227 -350.074992)
		(stroke
			(width 0.08255)
			(type default)
		)
		(layer "In5.Cu")
	)
	(gr_line
		(start 20.736052 -200.386188)
		(end 20.88642 -200.171304)
		(stroke
			(width 0.08255)
			(type default)
		)
		(layer "In5.Cu")
	)
	(gr_line
		(start 20.785328 -407.981404)
		(end 20.805902 -407.977848)
		(stroke
			(width 0.08255)
			(type default)
		)
		(layer "In5.Cu")
	)
	(gr_line
		(start 20.805902 -407.977848)
		(end 20.826476 -407.981404)
		(stroke
			(width 0.08255)
			(type default)
		)
		(layer "In5.Cu")
	)
	(gr_line
		(start 20.806918 -407.058622)
		(end 20.827492 -407.055066)
		(stroke
			(width 0.08255)
			(type default)
		)
		(layer "In5.Cu")
	)
	(gr_line
		(start 20.80768 -249.047762)
		(end 20.827492 -249.060716)
		(stroke
			(width 0.08255)
			(type default)
		)
		(layer "In5.Cu")
	)
	(gr_line
		(start 20.822412 -408.909266)
		(end 20.842986 -408.90571)
		(stroke
			(width 0.08255)
			(type default)
		)
		(layer "In5.Cu")
	)
	(gr_line
		(start 20.827492 -407.055066)
		(end 20.848066 -407.058622)
		(stroke
			(width 0.08255)
			(type default)
		)
		(layer "In5.Cu")
	)
	(gr_line
		(start 20.827492 -249.060716)
		(end 20.851114 -249.065796)
		(stroke
			(width 0.08255)
			(type default)
		)
		(layer "In5.Cu")
	)
	(gr_line
		(start 20.842986 -408.90571)
		(end 20.86356 -408.909266)
		(stroke
			(width 0.08255)
			(type default)
		)
		(layer "In5.Cu")
	)
	(gr_line
		(start 20.87118 -171.95038)
		(end 21.516594 -171.498514)
		(stroke
			(width 0.08255)
			(type default)
		)
		(layer "In5.Cu")
	)
	(gr_line
		(start 20.971256 -90.614754)
		(end 20.974812 -90.635582)
		(stroke
			(width 0.08255)
			(type default)
		)
		(layer "In5.Cu")
	)
	(gr_line
		(start 20.971256 -90.614754)
		(end 20.974812 -90.59418)
		(stroke
			(width 0.08255)
			(type default)
		)
		(layer "In5.Cu")
	)
	(gr_line
		(start 20.974812 -90.635328)
		(end 20.974812 -90.63609)
		(stroke
			(width 0.08255)
			(type default)
		)
		(layer "In5.Cu")
	)
	(gr_line
		(start 21.040598 -304.140362)
		(end 21.070824 -304.11928)
		(stroke
			(width 0.08255)
			(type default)
		)
		(layer "In5.Cu")
	)
	(gr_line
		(start 21.068792 -454.263506)
		(end 21.08073 -454.280524)
		(stroke
			(width 0.08255)
			(type default)
		)
		(layer "In5.Cu")
	)
	(gr_line
		(start 21.070824 -304.11928)
		(end 21.106638 -304.11293)
		(stroke
			(width 0.08255)
			(type default)
		)
		(layer "In5.Cu")
	)
	(gr_line
		(start 21.08073 -454.280524)
		(end 21.09724 -454.291954)
		(stroke
			(width 0.08255)
			(type default)
		)
		(layer "In5.Cu")
	)
	(gr_line
		(start 21.084286 -171.13758)
		(end 21.342858 -171.183046)
		(stroke
			(width 0.08255)
			(type default)
		)
		(layer "In5.Cu")
	)
	(gr_line
		(start 21.290788 -384.308858)
		(end 21.321014 -384.32994)
		(stroke
			(width 0.08255)
			(type default)
		)
		(layer "In5.Cu")
	)
	(gr_line
		(start 21.321014 -384.32994)
		(end 21.357082 -384.33629)
		(stroke
			(width 0.08255)
			(type default)
		)
		(layer "In5.Cu")
	)
	(gr_line
		(start 21.3233 -351.517712)
		(end 21.336 -351.536)
		(stroke
			(width 0.08255)
			(type default)
		)
		(layer "In5.Cu")
	)
	(gr_line
		(start 21.331682 -198.380604)
		(end 22.109176 -198.24319)
		(stroke
			(width 0.08255)
			(type default)
		)
		(layer "In5.Cu")
	)
	(gr_line
		(start 21.336 -351.536)
		(end 21.354288 -351.5487)
		(stroke
			(width 0.08255)
			(type default)
		)
		(layer "In5.Cu")
	)
	(gr_line
		(start 21.355304 -199.725026)
		(end 22.131782 -199.588374)
		(stroke
			(width 0.08255)
			(type default)
		)
		(layer "In5.Cu")
	)
	(gr_line
		(start 21.355812 -198.740014)
		(end 21.570696 -198.890382)
		(stroke
			(width 0.08255)
			(type default)
		)
		(layer "In5.Cu")
	)
	(gr_line
		(start 21.37918 -200.08469)
		(end 21.594064 -200.235058)
		(stroke
			(width 0.08255)
			(type default)
		)
		(layer "In5.Cu")
	)
	(gr_line
		(start 21.437346 -180.081174)
		(end 21.456396 -180.067712)
		(stroke
			(width 0.08255)
			(type default)
		)
		(layer "In5.Cu")
	)
	(gr_line
		(start 21.456396 -180.067712)
		(end 21.468588 -180.050186)
		(stroke
			(width 0.08255)
			(type default)
		)
		(layer "In5.Cu")
	)
	(gr_line
		(start 21.47824 -93.489018)
		(end 21.48459 -93.524832)
		(stroke
			(width 0.08255)
			(type default)
		)
		(layer "In5.Cu")
	)
	(gr_line
		(start 21.48459 -93.524832)
		(end 21.505672 -93.555058)
		(stroke
			(width 0.08255)
			(type default)
		)
		(layer "In5.Cu")
	)
	(gr_line
		(start 21.541232 -454.603104)
		(end 21.571458 -454.624186)
		(stroke
			(width 0.08255)
			(type default)
		)
		(layer "In5.Cu")
	)
	(gr_line
		(start 21.570696 -198.890382)
		(end 22.058376 -198.804276)
		(stroke
			(width 0.08255)
			(type default)
		)
		(layer "In5.Cu")
	)
	(gr_line
		(start 21.571458 -454.624186)
		(end 21.607526 -454.630536)
		(stroke
			(width 0.08255)
			(type default)
		)
		(layer "In5.Cu")
	)
	(gr_line
		(start 21.594064 -200.235058)
		(end 22.081998 -200.149206)
		(stroke
			(width 0.08255)
			(type default)
		)
		(layer "In5.Cu")
	)
	(gr_line
		(start 21.698966 -356.61854)
		(end 21.71954 -356.622096)
		(stroke
			(width 0.08255)
			(type default)
		)
		(layer "In5.Cu")
	)
	(gr_line
		(start 21.71954 -356.622096)
		(end 21.740114 -356.61854)
		(stroke
			(width 0.08255)
			(type default)
		)
		(layer "In5.Cu")
	)
	(gr_line
		(start 21.757132 -352.99904)
		(end 21.787358 -353.020122)
		(stroke
			(width 0.08255)
			(type default)
		)
		(layer "In5.Cu")
	)
	(gr_line
		(start 21.774658 -272.338038)
		(end 21.792946 -272.325338)
		(stroke
			(width 0.08255)
			(type default)
		)
		(layer "In5.Cu")
	)
	(gr_line
		(start 21.787358 -353.020122)
		(end 21.823172 -353.026472)
		(stroke
			(width 0.08255)
			(type default)
		)
		(layer "In5.Cu")
	)
	(gr_line
		(start 21.792946 -272.325338)
		(end 21.805646 -272.30705)
		(stroke
			(width 0.08255)
			(type default)
		)
		(layer "In5.Cu")
	)
	(gr_line
		(start 21.807678 -456.021186)
		(end 21.837904 -456.042268)
		(stroke
			(width 0.08255)
			(type default)
		)
		(layer "In5.Cu")
	)
	(gr_line
		(start 21.837904 -456.042268)
		(end 21.873718 -456.048618)
		(stroke
			(width 0.08255)
			(type default)
		)
		(layer "In5.Cu")
	)
	(gr_line
		(start 21.844254 -358.816656)
		(end 21.880068 -358.810306)
		(stroke
			(width 0.08255)
			(type default)
		)
		(layer "In5.Cu")
	)
	(gr_line
		(start 21.880068 -358.810306)
		(end 21.910294 -358.789224)
		(stroke
			(width 0.08255)
			(type default)
		)
		(layer "In5.Cu")
	)
	(gr_line
		(start 21.951188 -459.612238)
		(end 21.971762 -459.615794)
		(stroke
			(width 0.08255)
			(type default)
		)
		(layer "In5.Cu")
	)
	(gr_line
		(start 21.961856 -351.974404)
		(end 21.992082 -351.995486)
		(stroke
			(width 0.08255)
			(type default)
		)
		(layer "In5.Cu")
	)
	(gr_line
		(start 21.971762 -459.615794)
		(end 21.992336 -459.612238)
		(stroke
			(width 0.08255)
			(type default)
		)
		(layer "In5.Cu")
	)
	(gr_line
		(start 21.992082 -351.995486)
		(end 22.027896 -352.001836)
		(stroke
			(width 0.08255)
			(type default)
		)
		(layer "In5.Cu")
	)
	(gr_line
		(start 22.03323 -84.59216)
		(end 22.039834 -84.55533)
		(stroke
			(width 0.08255)
			(type default)
		)
		(layer "In5.Cu")
	)
	(gr_line
		(start 22.039834 -84.55533)
		(end 22.061424 -84.524342)
		(stroke
			(width 0.08255)
			(type default)
		)
		(layer "In5.Cu")
	)
	(gr_line
		(start 22.043644 -89.776046)
		(end 22.0472 -89.796366)
		(stroke
			(width 0.08255)
			(type default)
		)
		(layer "In5.Cu")
	)
	(gr_line
		(start 22.043644 -89.776046)
		(end 22.0472 -89.755472)
		(stroke
			(width 0.08255)
			(type default)
		)
		(layer "In5.Cu")
	)
	(gr_line
		(start 22.0472 -89.79662)
		(end 22.0472 -89.797382)
		(stroke
			(width 0.08255)
			(type default)
		)
		(layer "In5.Cu")
	)
	(gr_line
		(start 22.058376 -198.804276)
		(end 22.208998 -198.589392)
		(stroke
			(width 0.08255)
			(type default)
		)
		(layer "In5.Cu")
	)
	(gr_line
		(start 22.081998 -200.149206)
		(end 22.232366 -199.934322)
		(stroke
			(width 0.08255)
			(type default)
		)
		(layer "In5.Cu")
	)
	(gr_line
		(start 22.210268 -97.878138)
		(end 22.222968 -97.896426)
		(stroke
			(width 0.08255)
			(type default)
		)
		(layer "In5.Cu")
	)
	(gr_line
		(start 22.222968 -97.896426)
		(end 22.241256 -97.909126)
		(stroke
			(width 0.08255)
			(type default)
		)
		(layer "In5.Cu")
	)
	(gr_line
		(start 22.418294 -172.515784)
		(end 22.464014 -172.257212)
		(stroke
			(width 0.08255)
			(type default)
		)
		(layer "In5.Cu")
	)
	(gr_line
		(start 22.462236 -166.384224)
		(end 22.480524 -166.371524)
		(stroke
			(width 0.08255)
			(type default)
		)
		(layer "In5.Cu")
	)
	(gr_line
		(start 22.464014 -172.257212)
		(end 22.869652 -171.97324)
		(stroke
			(width 0.08255)
			(type default)
		)
		(layer "In5.Cu")
	)
	(gr_line
		(start 22.464776 -96.498664)
		(end 22.477476 -96.516952)
		(stroke
			(width 0.08255)
			(type default)
		)
		(layer "In5.Cu")
	)
	(gr_line
		(start 22.477476 -96.516952)
		(end 22.495764 -96.529652)
		(stroke
			(width 0.08255)
			(type default)
		)
		(layer "In5.Cu")
	)
	(gr_line
		(start 22.480524 -166.371524)
		(end 22.493224 -166.353236)
		(stroke
			(width 0.08255)
			(type default)
		)
		(layer "In5.Cu")
	)
	(gr_line
		(start 22.568154 -485.283764)
		(end 22.580854 -485.302052)
		(stroke
			(width 0.08255)
			(type default)
		)
		(layer "In5.Cu")
	)
	(gr_line
		(start 22.580854 -485.302052)
		(end 22.599142 -485.314752)
		(stroke
			(width 0.08255)
			(type default)
		)
		(layer "In5.Cu")
	)
	(gr_line
		(start 22.65807 -172.78477)
		(end 23.300436 -172.334936)
		(stroke
			(width 0.08255)
			(type default)
		)
		(layer "In5.Cu")
	)
	(gr_line
		(start 22.661118 -86.272878)
		(end 22.667468 -86.23681)
		(stroke
			(width 0.08255)
			(type default)
		)
		(layer "In5.Cu")
	)
	(gr_line
		(start 22.664166 -404.44039)
		(end 22.694392 -404.461472)
		(stroke
			(width 0.08255)
			(type default)
		)
		(layer "In5.Cu")
	)
	(gr_line
		(start 22.667468 -86.23681)
		(end 22.68855 -86.206584)
		(stroke
			(width 0.08255)
			(type default)
		)
		(layer "In5.Cu")
	)
	(gr_line
		(start 22.678136 -198.14286)
		(end 22.69871 -198.139304)
		(stroke
			(width 0.08255)
			(type default)
		)
		(layer "In5.Cu")
	)
	(gr_line
		(start 22.694392 -404.461472)
		(end 22.73046 -404.467822)
		(stroke
			(width 0.08255)
			(type default)
		)
		(layer "In5.Cu")
	)
	(gr_line
		(start 22.69871 -198.139304)
		(end 22.719284 -198.14286)
		(stroke
			(width 0.08255)
			(type default)
		)
		(layer "In5.Cu")
	)
	(gr_line
		(start 22.721316 -93.617034)
		(end 22.727666 -93.652848)
		(stroke
			(width 0.08255)
			(type default)
		)
		(layer "In5.Cu")
	)
	(gr_line
		(start 22.727666 -93.652848)
		(end 22.748748 -93.683074)
		(stroke
			(width 0.08255)
			(type default)
		)
		(layer "In5.Cu")
	)
	(gr_line
		(start 22.762464 -381.790448)
		(end 22.783038 -381.794004)
		(stroke
			(width 0.08255)
			(type default)
		)
		(layer "In5.Cu")
	)
	(gr_line
		(start 22.783038 -381.794004)
		(end 22.803612 -381.790448)
		(stroke
			(width 0.08255)
			(type default)
		)
		(layer "In5.Cu")
	)
	(gr_line
		(start 22.826472 -382.838706)
		(end 22.847046 -382.842262)
		(stroke
			(width 0.08255)
			(type default)
		)
		(layer "In5.Cu")
	)
	(gr_line
		(start 22.847046 -382.842262)
		(end 22.86762 -382.838706)
		(stroke
			(width 0.08255)
			(type default)
		)
		(layer "In5.Cu")
	)
	(gr_line
		(start 22.869652 -171.97324)
		(end 23.128478 -172.018706)
		(stroke
			(width 0.08255)
			(type default)
		)
		(layer "In5.Cu")
	)
	(gr_line
		(start 22.882606 -403.48281)
		(end 22.912832 -403.503892)
		(stroke
			(width 0.08255)
			(type default)
		)
		(layer "In5.Cu")
	)
	(gr_line
		(start 22.912832 -403.503892)
		(end 22.9489 -403.510242)
		(stroke
			(width 0.08255)
			(type default)
		)
		(layer "In5.Cu")
	)
	(gr_line
		(start 22.95906 -303.786032)
		(end 22.979634 -303.782476)
		(stroke
			(width 0.08255)
			(type default)
		)
		(layer "In5.Cu")
	)
	(gr_line
		(start 22.979634 -303.782476)
		(end 23.000208 -303.786032)
		(stroke
			(width 0.08255)
			(type default)
		)
		(layer "In5.Cu")
	)
	(gr_line
		(start 23.055072 -300.923198)
		(end 23.075646 -300.919642)
		(stroke
			(width 0.08255)
			(type default)
		)
		(layer "In5.Cu")
	)
	(gr_line
		(start 23.055326 -95.76816)
		(end 23.068026 -95.786448)
		(stroke
			(width 0.08255)
			(type default)
		)
		(layer "In5.Cu")
	)
	(gr_line
		(start 23.068026 -95.786448)
		(end 23.086314 -95.799148)
		(stroke
			(width 0.08255)
			(type default)
		)
		(layer "In5.Cu")
	)
	(gr_line
		(start 23.075646 -300.919642)
		(end 23.09622 -300.923198)
		(stroke
			(width 0.08255)
			(type default)
		)
		(layer "In5.Cu")
	)
	(gr_line
		(start 23.097236 -168.162224)
		(end 23.115524 -168.149524)
		(stroke
			(width 0.08255)
			(type default)
		)
		(layer "In5.Cu")
	)
	(gr_line
		(start 23.115524 -168.149524)
		(end 23.128224 -168.131236)
		(stroke
			(width 0.08255)
			(type default)
		)
		(layer "In5.Cu")
	)
	(gr_line
		(start 23.155402 -301.884842)
		(end 23.175976 -301.881286)
		(stroke
			(width 0.08255)
			(type default)
		)
		(layer "In5.Cu")
	)
	(gr_line
		(start 23.175976 -301.881286)
		(end 23.19655 -301.884842)
		(stroke
			(width 0.08255)
			(type default)
		)
		(layer "In5.Cu")
	)
	(gr_line
		(start 23.223474 -302.823626)
		(end 23.244048 -302.82007)
		(stroke
			(width 0.08255)
			(type default)
		)
		(layer "In5.Cu")
	)
	(gr_line
		(start 23.23465 -454.917556)
		(end 23.255224 -454.921112)
		(stroke
			(width 0.08255)
			(type default)
		)
		(layer "In5.Cu")
	)
	(gr_line
		(start 23.244048 -302.82007)
		(end 23.264622 -302.823626)
		(stroke
			(width 0.08255)
			(type default)
		)
		(layer "In5.Cu")
	)
	(gr_line
		(start 23.255224 -454.921112)
		(end 23.275798 -454.917556)
		(stroke
			(width 0.08255)
			(type default)
		)
		(layer "In5.Cu")
	)
	(gr_line
		(start 23.276814 -163.813744)
		(end 23.36292 -163.326064)
		(stroke
			(width 0.08255)
			(type default)
		)
		(layer "In5.Cu")
	)
	(gr_line
		(start 23.276814 -163.813744)
		(end 23.427436 -164.029136)
		(stroke
			(width 0.08255)
			(type default)
		)
		(layer "In5.Cu")
	)
	(gr_line
		(start 23.338028 -456.306936)
		(end 23.358602 -456.310492)
		(stroke
			(width 0.08255)
			(type default)
		)
		(layer "In5.Cu")
	)
	(gr_line
		(start 23.358602 -456.310492)
		(end 23.379176 -456.306936)
		(stroke
			(width 0.08255)
			(type default)
		)
		(layer "In5.Cu")
	)
	(gr_line
		(start 23.36292 -163.326064)
		(end 23.578058 -163.175442)
		(stroke
			(width 0.08255)
			(type default)
		)
		(layer "In5.Cu")
	)
	(gr_line
		(start 23.390352 -352.24212)
		(end 23.410926 -352.245676)
		(stroke
			(width 0.08255)
			(type default)
		)
		(layer "In5.Cu")
	)
	(gr_line
		(start 23.410926 -352.245676)
		(end 23.4315 -352.24212)
		(stroke
			(width 0.08255)
			(type default)
		)
		(layer "In5.Cu")
	)
	(gr_line
		(start 23.465536 -269.93723)
		(end 23.486618 -269.907004)
		(stroke
			(width 0.08255)
			(type default)
		)
		(layer "In5.Cu")
	)
	(gr_line
		(start 23.476458 -402.64588)
		(end 23.506684 -402.666962)
		(stroke
			(width 0.08255)
			(type default)
		)
		(layer "In5.Cu")
	)
	(gr_line
		(start 23.486618 -269.907004)
		(end 23.492968 -269.870936)
		(stroke
			(width 0.08255)
			(type default)
		)
		(layer "In5.Cu")
	)
	(gr_line
		(start 23.506684 -402.666962)
		(end 23.542498 -402.673312)
		(stroke
			(width 0.08255)
			(type default)
		)
		(layer "In5.Cu")
	)
	(gr_line
		(start 23.514304 -162.468052)
		(end 23.60041 -161.980372)
		(stroke
			(width 0.08255)
			(type default)
		)
		(layer "In5.Cu")
	)
	(gr_line
		(start 23.514304 -162.468052)
		(end 23.664926 -162.683444)
		(stroke
			(width 0.08255)
			(type default)
		)
		(layer "In5.Cu")
	)
	(gr_line
		(start 23.537672 -171.73194)
		(end 23.583392 -171.473368)
		(stroke
			(width 0.08255)
			(type default)
		)
		(layer "In5.Cu")
	)
	(gr_line
		(start 23.583392 -171.473368)
		(end 23.98903 -171.189396)
		(stroke
			(width 0.08255)
			(type default)
		)
		(layer "In5.Cu")
	)
	(gr_line
		(start 23.60041 -161.980372)
		(end 23.815548 -161.82975)
		(stroke
			(width 0.08255)
			(type default)
		)
		(layer "In5.Cu")
	)
	(gr_line
		(start 23.636224 -356.283768)
		(end 23.672038 -356.277418)
		(stroke
			(width 0.08255)
			(type default)
		)
		(layer "In5.Cu")
	)
	(gr_line
		(start 23.65883 -164.688266)
		(end 23.680166 -164.65804)
		(stroke
			(width 0.08255)
			(type default)
		)
		(layer "In5.Cu")
	)
	(gr_line
		(start 23.672038 -356.277418)
		(end 23.702264 -356.256336)
		(stroke
			(width 0.08255)
			(type default)
		)
		(layer "In5.Cu")
	)
	(gr_line
		(start 23.680166 -164.65804)
		(end 23.687024 -164.619432)
		(stroke
			(width 0.08255)
			(type default)
		)
		(layer "In5.Cu")
	)
	(gr_line
		(start 23.7236 -169.953432)
		(end 23.741888 -169.940732)
		(stroke
			(width 0.08255)
			(type default)
		)
		(layer "In5.Cu")
	)
	(gr_line
		(start 23.741888 -169.940732)
		(end 23.754588 -169.922444)
		(stroke
			(width 0.08255)
			(type default)
		)
		(layer "In5.Cu")
	)
	(gr_line
		(start 23.751794 -161.12236)
		(end 23.8379 -160.63468)
		(stroke
			(width 0.08255)
			(type default)
		)
		(layer "In5.Cu")
	)
	(gr_line
		(start 23.751794 -161.12236)
		(end 23.902416 -161.337752)
		(stroke
			(width 0.08255)
			(type default)
		)
		(layer "In5.Cu")
	)
	(gr_line
		(start 23.77567 -172.00245)
		(end 24.420576 -171.550838)
		(stroke
			(width 0.08255)
			(type default)
		)
		(layer "In5.Cu")
	)
	(gr_line
		(start 23.785068 -95.16364)
		(end 23.797768 -95.181928)
		(stroke
			(width 0.08255)
			(type default)
		)
		(layer "In5.Cu")
	)
	(gr_line
		(start 23.786592 -164.055044)
		(end 23.924514 -163.27374)
		(stroke
			(width 0.08255)
			(type default)
		)
		(layer "In5.Cu")
	)
	(gr_line
		(start 23.797514 -98.998786)
		(end 23.82774 -99.019868)
		(stroke
			(width 0.08255)
			(type default)
		)
		(layer "In5.Cu")
	)
	(gr_line
		(start 23.797768 -95.181928)
		(end 23.816056 -95.194628)
		(stroke
			(width 0.08255)
			(type default)
		)
		(layer "In5.Cu")
	)
	(gr_line
		(start 23.82774 -99.019868)
		(end 23.863808 -99.026218)
		(stroke
			(width 0.08255)
			(type default)
		)
		(layer "In5.Cu")
	)
	(gr_line
		(start 23.8379 -160.63468)
		(end 24.053038 -160.484058)
		(stroke
			(width 0.08255)
			(type default)
		)
		(layer "In5.Cu")
	)
	(gr_line
		(start 23.879556 -199.280526)
		(end 23.900384 -199.27697)
		(stroke
			(width 0.08255)
			(type default)
		)
		(layer "In5.Cu")
	)
	(gr_line
		(start 23.900384 -199.27697)
		(end 23.920958 -199.280526)
		(stroke
			(width 0.08255)
			(type default)
		)
		(layer "In5.Cu")
	)
	(gr_line
		(start 23.960328 -166.317168)
		(end 23.96109 -166.313104)
		(stroke
			(width 0.08255)
			(type default)
		)
		(layer "In5.Cu")
	)
	(gr_line
		(start 23.98903 -171.189396)
		(end 24.247602 -171.235116)
		(stroke
			(width 0.08255)
			(type default)
		)
		(layer "In5.Cu")
	)
	(gr_line
		(start 24.024082 -162.70986)
		(end 24.162004 -161.928302)
		(stroke
			(width 0.08255)
			(type default)
		)
		(layer "In5.Cu")
	)
	(gr_line
		(start 24.026114 -174.64913)
		(end 24.044402 -174.63643)
		(stroke
			(width 0.08255)
			(type default)
		)
		(layer "In5.Cu")
	)
	(gr_line
		(start 24.044402 -174.63643)
		(end 24.057102 -174.618142)
		(stroke
			(width 0.08255)
			(type default)
		)
		(layer "In5.Cu")
	)
	(gr_line
		(start 24.10206 -353.428808)
		(end 24.122634 -353.432364)
		(stroke
			(width 0.08255)
			(type default)
		)
		(layer "In5.Cu")
	)
	(gr_line
		(start 24.122634 -353.432364)
		(end 24.143208 -353.428808)
		(stroke
			(width 0.08255)
			(type default)
		)
		(layer "In5.Cu")
	)
	(gr_line
		(start 24.228298 -271.0815)
		(end 24.24938 -271.051274)
		(stroke
			(width 0.08255)
			(type default)
		)
		(layer "In5.Cu")
	)
	(gr_line
		(start 24.24938 -271.051274)
		(end 24.25573 -271.015206)
		(stroke
			(width 0.08255)
			(type default)
		)
		(layer "In5.Cu")
	)
	(gr_line
		(start 24.261572 -161.362898)
		(end 24.398986 -160.584642)
		(stroke
			(width 0.08255)
			(type default)
		)
		(layer "In5.Cu")
	)
	(gr_line
		(start 24.27351 -166.496238)
		(end 24.291036 -166.471092)
		(stroke
			(width 0.08255)
			(type default)
		)
		(layer "In5.Cu")
	)
	(gr_line
		(start 24.291036 -166.471092)
		(end 24.297386 -166.44239)
		(stroke
			(width 0.08255)
			(type default)
		)
		(layer "In5.Cu")
	)
	(gr_line
		(start 24.311864 -166.371778)
		(end 24.312372 -166.367714)
		(stroke
			(width 0.08255)
			(type default)
		)
		(layer "In5.Cu")
	)
	(gr_line
		(start 24.312372 -166.367714)
		(end 24.313134 -166.363904)
		(stroke
			(width 0.08255)
			(type default)
		)
		(layer "In5.Cu")
	)
	(gr_line
		(start 24.370284 -249.814588)
		(end 24.404066 -249.8217)
		(stroke
			(width 0.08255)
			(type default)
		)
		(layer "In5.Cu")
	)
	(gr_line
		(start 24.404066 -249.8217)
		(end 24.437848 -249.814588)
		(stroke
			(width 0.08255)
			(type default)
		)
		(layer "In5.Cu")
	)
	(gr_line
		(start 24.567388 -480.229164)
		(end 24.597614 -480.2505)
		(stroke
			(width 0.08255)
			(type default)
		)
		(layer "In5.Cu")
	)
	(gr_line
		(start 24.597614 -480.2505)
		(end 24.63419 -480.25685)
		(stroke
			(width 0.08255)
			(type default)
		)
		(layer "In5.Cu")
	)
	(gr_line
		(start 24.600408 -95.743776)
		(end 24.630634 -95.764858)
		(stroke
			(width 0.08255)
			(type default)
		)
		(layer "In5.Cu")
	)
	(gr_line
		(start 24.630634 -95.764858)
		(end 24.666702 -95.771208)
		(stroke
			(width 0.08255)
			(type default)
		)
		(layer "In5.Cu")
	)
	(gr_line
		(start 24.893778 -171.219622)
		(end 24.912066 -171.206922)
		(stroke
			(width 0.08255)
			(type default)
		)
		(layer "In5.Cu")
	)
	(gr_line
		(start 24.912066 -171.206922)
		(end 24.924766 -171.188634)
		(stroke
			(width 0.08255)
			(type default)
		)
		(layer "In5.Cu")
	)
	(gr_line
		(start 24.95042 -98.247708)
		(end 24.980646 -98.26879)
		(stroke
			(width 0.08255)
			(type default)
		)
		(layer "In5.Cu")
	)
	(gr_line
		(start 24.975312 -168.178226)
		(end 24.996394 -168.148508)
		(stroke
			(width 0.08255)
			(type default)
		)
		(layer "In5.Cu")
	)
	(gr_line
		(start 24.980646 -98.26879)
		(end 25.01646 -98.27514)
		(stroke
			(width 0.08255)
			(type default)
		)
		(layer "In5.Cu")
	)
	(gr_line
		(start 24.996394 -168.148508)
		(end 25.003252 -168.110154)
		(stroke
			(width 0.08255)
			(type default)
		)
		(layer "In5.Cu")
	)
	(gr_line
		(start 25.169876 -288.054542)
		(end 25.182576 -288.036254)
		(stroke
			(width 0.08255)
			(type default)
		)
		(layer "In5.Cu")
	)
	(gr_line
		(start 25.182576 -288.036254)
		(end 25.200864 -288.023554)
		(stroke
			(width 0.08255)
			(type default)
		)
		(layer "In5.Cu")
	)
	(gr_line
		(start 25.234138 -97.303844)
		(end 25.264364 -97.324926)
		(stroke
			(width 0.08255)
			(type default)
		)
		(layer "In5.Cu")
	)
	(gr_line
		(start 25.264364 -97.324926)
		(end 25.300432 -97.331276)
		(stroke
			(width 0.08255)
			(type default)
		)
		(layer "In5.Cu")
	)
	(gr_line
		(start 25.36571 -381.338328)
		(end 25.401524 -381.331978)
		(stroke
			(width 0.08255)
			(type default)
		)
		(layer "In5.Cu")
	)
	(gr_line
		(start 25.375616 -257.147822)
		(end 25.381966 -257.111754)
		(stroke
			(width 0.08255)
			(type default)
		)
		(layer "In5.Cu")
	)
	(gr_line
		(start 25.381966 -257.111754)
		(end 25.403048 -257.081528)
		(stroke
			(width 0.08255)
			(type default)
		)
		(layer "In5.Cu")
	)
	(gr_line
		(start 25.401524 -381.331978)
		(end 25.43175 -381.310896)
		(stroke
			(width 0.08255)
			(type default)
		)
		(layer "In5.Cu")
	)
	(gr_line
		(start 25.519126 -201.483722)
		(end 25.5397 -201.480166)
		(stroke
			(width 0.08255)
			(type default)
		)
		(layer "In5.Cu")
	)
	(gr_line
		(start 25.5397 -201.480166)
		(end 25.560274 -201.483722)
		(stroke
			(width 0.08255)
			(type default)
		)
		(layer "In5.Cu")
	)
	(gr_line
		(start 25.615646 -170.202352)
		(end 25.636728 -170.172126)
		(stroke
			(width 0.08255)
			(type default)
		)
		(layer "In5.Cu")
	)
	(gr_line
		(start 25.636728 -170.172126)
		(end 25.643078 -170.136058)
		(stroke
			(width 0.08255)
			(type default)
		)
		(layer "In5.Cu")
	)
	(gr_line
		(start 25.739852 -483.310692)
		(end 25.770078 -483.331774)
		(stroke
			(width 0.08255)
			(type default)
		)
		(layer "In5.Cu")
	)
	(gr_line
		(start 25.770078 -483.331774)
		(end 25.806146 -483.338124)
		(stroke
			(width 0.08255)
			(type default)
		)
		(layer "In5.Cu")
	)
	(gr_line
		(start 25.908 -64.494156)
		(end 25.929082 -64.46393)
		(stroke
			(width 0.08255)
			(type default)
		)
		(layer "In5.Cu")
	)
	(gr_line
		(start 25.929082 -64.46393)
		(end 25.935432 -64.427862)
		(stroke
			(width 0.08255)
			(type default)
		)
		(layer "In5.Cu")
	)
	(gr_line
		(start 26.255726 -257.62458)
		(end 26.262076 -257.588512)
		(stroke
			(width 0.08255)
			(type default)
		)
		(layer "In5.Cu")
	)
	(gr_line
		(start 26.262076 -257.588512)
		(end 26.283158 -257.558286)
		(stroke
			(width 0.08255)
			(type default)
		)
		(layer "In5.Cu")
	)
	(gr_line
		(start 26.348436 -249.408442)
		(end 26.372312 -249.403362)
		(stroke
			(width 0.08255)
			(type default)
		)
		(layer "In5.Cu")
	)
	(gr_line
		(start 26.372312 -249.403362)
		(end 26.392124 -249.390408)
		(stroke
			(width 0.08255)
			(type default)
		)
		(layer "In5.Cu")
	)
	(gr_line
		(start 26.399744 -271.589246)
		(end 26.420826 -271.55902)
		(stroke
			(width 0.08255)
			(type default)
		)
		(layer "In5.Cu")
	)
	(gr_line
		(start 26.409396 -147.145502)
		(end 26.415746 -147.109688)
		(stroke
			(width 0.08255)
			(type default)
		)
		(layer "In5.Cu")
	)
	(gr_line
		(start 26.415746 -147.109688)
		(end 26.436828 -147.079462)
		(stroke
			(width 0.08255)
			(type default)
		)
		(layer "In5.Cu")
	)
	(gr_line
		(start 26.420826 -271.55902)
		(end 26.427176 -271.522952)
		(stroke
			(width 0.08255)
			(type default)
		)
		(layer "In5.Cu")
	)
	(gr_line
		(start 26.595832 -352.996246)
		(end 26.6319 -352.989896)
		(stroke
			(width 0.08255)
			(type default)
		)
		(layer "In5.Cu")
	)
	(gr_line
		(start 26.6319 -352.989896)
		(end 26.662126 -352.968814)
		(stroke
			(width 0.08255)
			(type default)
		)
		(layer "In5.Cu")
	)
	(gr_line
		(start 26.65349 -146.442176)
		(end 26.69921 -146.700494)
		(stroke
			(width 0.08255)
			(type default)
		)
		(layer "In5.Cu")
	)
	(gr_line
		(start 26.65349 -146.442176)
		(end 26.937716 -146.036284)
		(stroke
			(width 0.08255)
			(type default)
		)
		(layer "In5.Cu")
	)
	(gr_line
		(start 26.67 -451.41642)
		(end 26.823162 -451.263258)
		(stroke
			(width 0.08255)
			(type default)
		)
		(layer "In5.Cu")
	)
	(gr_line
		(start 26.67 -450.60362)
		(end 26.823162 -450.756782)
		(stroke
			(width 0.08255)
			(type default)
		)
		(layer "In5.Cu")
	)
	(gr_line
		(start 26.67 -438.616344)
		(end 26.823162 -438.463182)
		(stroke
			(width 0.08255)
			(type default)
		)
		(layer "In5.Cu")
	)
	(gr_line
		(start 26.67 -437.803544)
		(end 26.823162 -437.956706)
		(stroke
			(width 0.08255)
			(type default)
		)
		(layer "In5.Cu")
	)
	(gr_line
		(start 26.67 -433.816506)
		(end 26.823162 -433.663344)
		(stroke
			(width 0.08255)
			(type default)
		)
		(layer "In5.Cu")
	)
	(gr_line
		(start 26.67 -433.003706)
		(end 26.823162 -433.156868)
		(stroke
			(width 0.08255)
			(type default)
		)
		(layer "In5.Cu")
	)
	(gr_line
		(start 26.67 -429.016414)
		(end 26.823162 -428.863252)
		(stroke
			(width 0.08255)
			(type default)
		)
		(layer "In5.Cu")
	)
	(gr_line
		(start 26.67 -428.203614)
		(end 26.823162 -428.356776)
		(stroke
			(width 0.08255)
			(type default)
		)
		(layer "In5.Cu")
	)
	(gr_line
		(start 26.67 -348.416372)
		(end 26.823162 -348.26321)
		(stroke
			(width 0.08255)
			(type default)
		)
		(layer "In5.Cu")
	)
	(gr_line
		(start 26.67 -347.603572)
		(end 26.823162 -347.756734)
		(stroke
			(width 0.08255)
			(type default)
		)
		(layer "In5.Cu")
	)
	(gr_line
		(start 26.67 -335.616296)
		(end 26.823162 -335.463134)
		(stroke
			(width 0.08255)
			(type default)
		)
		(layer "In5.Cu")
	)
	(gr_line
		(start 26.67 -334.803496)
		(end 26.823162 -334.956658)
		(stroke
			(width 0.08255)
			(type default)
		)
		(layer "In5.Cu")
	)
	(gr_line
		(start 26.67 -330.816458)
		(end 26.823162 -330.663296)
		(stroke
			(width 0.08255)
			(type default)
		)
		(layer "In5.Cu")
	)
	(gr_line
		(start 26.67 -330.003658)
		(end 26.823162 -330.15682)
		(stroke
			(width 0.08255)
			(type default)
		)
		(layer "In5.Cu")
	)
	(gr_line
		(start 26.67 -326.016366)
		(end 26.823162 -325.863204)
		(stroke
			(width 0.08255)
			(type default)
		)
		(layer "In5.Cu")
	)
	(gr_line
		(start 26.67 -325.203566)
		(end 26.823162 -325.356728)
		(stroke
			(width 0.08255)
			(type default)
		)
		(layer "In5.Cu")
	)
	(gr_line
		(start 26.67 -245.416324)
		(end 26.823162 -245.263162)
		(stroke
			(width 0.08255)
			(type default)
		)
		(layer "In5.Cu")
	)
	(gr_line
		(start 26.67 -244.603524)
		(end 26.823162 -244.756686)
		(stroke
			(width 0.08255)
			(type default)
		)
		(layer "In5.Cu")
	)
	(gr_line
		(start 26.67 -232.616248)
		(end 26.823162 -232.463086)
		(stroke
			(width 0.08255)
			(type default)
		)
		(layer "In5.Cu")
	)
	(gr_line
		(start 26.67 -231.803448)
		(end 26.823162 -231.95661)
		(stroke
			(width 0.08255)
			(type default)
		)
		(layer "In5.Cu")
	)
	(gr_line
		(start 26.67 -227.81641)
		(end 26.823162 -227.663248)
		(stroke
			(width 0.08255)
			(type default)
		)
		(layer "In5.Cu")
	)
	(gr_line
		(start 26.67 -227.00361)
		(end 26.823162 -227.156772)
		(stroke
			(width 0.08255)
			(type default)
		)
		(layer "In5.Cu")
	)
	(gr_line
		(start 26.67 -223.016318)
		(end 26.823162 -222.863156)
		(stroke
			(width 0.08255)
			(type default)
		)
		(layer "In5.Cu")
	)
	(gr_line
		(start 26.67 -222.203518)
		(end 26.823162 -222.35668)
		(stroke
			(width 0.08255)
			(type default)
		)
		(layer "In5.Cu")
	)
	(gr_line
		(start 26.67 -142.416276)
		(end 26.823162 -142.263114)
		(stroke
			(width 0.08255)
			(type default)
		)
		(layer "In5.Cu")
	)
	(gr_line
		(start 26.67 -141.603476)
		(end 26.823162 -141.756638)
		(stroke
			(width 0.08255)
			(type default)
		)
		(layer "In5.Cu")
	)
	(gr_line
		(start 26.67 -129.6162)
		(end 26.823162 -129.463038)
		(stroke
			(width 0.08255)
			(type default)
		)
		(layer "In5.Cu")
	)
	(gr_line
		(start 26.67 -128.8034)
		(end 26.823162 -128.956562)
		(stroke
			(width 0.08255)
			(type default)
		)
		(layer "In5.Cu")
	)
	(gr_line
		(start 26.67 -124.816362)
		(end 26.823162 -124.6632)
		(stroke
			(width 0.08255)
			(type default)
		)
		(layer "In5.Cu")
	)
	(gr_line
		(start 26.67 -124.003562)
		(end 26.823162 -124.156724)
		(stroke
			(width 0.08255)
			(type default)
		)
		(layer "In5.Cu")
	)
	(gr_line
		(start 26.67 -120.01627)
		(end 26.823162 -119.863108)
		(stroke
			(width 0.08255)
			(type default)
		)
		(layer "In5.Cu")
	)
	(gr_line
		(start 26.67 -119.20347)
		(end 26.823162 -119.356632)
		(stroke
			(width 0.08255)
			(type default)
		)
		(layer "In5.Cu")
	)
	(gr_line
		(start 26.67 -39.416228)
		(end 26.823162 -39.263066)
		(stroke
			(width 0.08255)
			(type default)
		)
		(layer "In5.Cu")
	)
	(gr_line
		(start 26.67 -38.603428)
		(end 26.823162 -38.75659)
		(stroke
			(width 0.08255)
			(type default)
		)
		(layer "In5.Cu")
	)
	(gr_line
		(start 26.67 -26.616152)
		(end 26.823162 -26.46299)
		(stroke
			(width 0.08255)
			(type default)
		)
		(layer "In5.Cu")
	)
	(gr_line
		(start 26.67 -25.803352)
		(end 26.823162 -25.956514)
		(stroke
			(width 0.08255)
			(type default)
		)
		(layer "In5.Cu")
	)
	(gr_line
		(start 26.67 -21.816314)
		(end 26.823162 -21.663152)
		(stroke
			(width 0.08255)
			(type default)
		)
		(layer "In5.Cu")
	)
	(gr_line
		(start 26.67 -21.003514)
		(end 26.823162 -21.156676)
		(stroke
			(width 0.08255)
			(type default)
		)
		(layer "In5.Cu")
	)
	(gr_line
		(start 26.67 -17.016222)
		(end 26.823162 -16.86306)
		(stroke
			(width 0.08255)
			(type default)
		)
		(layer "In5.Cu")
	)
	(gr_line
		(start 26.67 -16.203422)
		(end 26.823162 -16.356584)
		(stroke
			(width 0.08255)
			(type default)
		)
		(layer "In5.Cu")
	)
	(gr_line
		(start 26.708354 -454.312274)
		(end 26.744422 -454.305924)
		(stroke
			(width 0.08255)
			(type default)
		)
		(layer "In5.Cu")
	)
	(gr_line
		(start 26.744422 -454.305924)
		(end 26.774648 -454.284842)
		(stroke
			(width 0.08255)
			(type default)
		)
		(layer "In5.Cu")
	)
	(gr_line
		(start 26.75001 -351.65665)
		(end 26.788364 -351.649792)
		(stroke
			(width 0.08255)
			(type default)
		)
		(layer "In5.Cu")
	)
	(gr_line
		(start 26.778712 -170.73118)
		(end 26.799794 -170.700954)
		(stroke
			(width 0.08255)
			(type default)
		)
		(layer "In5.Cu")
	)
	(gr_line
		(start 26.788364 -351.649792)
		(end 26.819352 -351.627948)
		(stroke
			(width 0.08255)
			(type default)
		)
		(layer "In5.Cu")
	)
	(gr_line
		(start 26.799794 -170.700954)
		(end 26.806144 -170.664886)
		(stroke
			(width 0.08255)
			(type default)
		)
		(layer "In5.Cu")
	)
	(gr_line
		(start 26.846276 -488.288584)
		(end 26.876502 -488.309666)
		(stroke
			(width 0.08255)
			(type default)
		)
		(layer "In5.Cu")
	)
	(gr_line
		(start 26.876502 -488.309666)
		(end 26.91257 -488.316016)
		(stroke
			(width 0.08255)
			(type default)
		)
		(layer "In5.Cu")
	)
	(gr_line
		(start 26.937716 -146.036284)
		(end 27.196034 -145.990818)
		(stroke
			(width 0.08255)
			(type default)
		)
		(layer "In5.Cu")
	)
	(gr_line
		(start 26.993596 -273.684238)
		(end 27.014678 -273.654012)
		(stroke
			(width 0.08255)
			(type default)
		)
		(layer "In5.Cu")
	)
	(gr_line
		(start 27.014678 -273.654012)
		(end 27.021028 -273.617944)
		(stroke
			(width 0.08255)
			(type default)
		)
		(layer "In5.Cu")
	)
	(gr_line
		(start 27.01544 -146.87296)
		(end 27.466544 -146.228816)
		(stroke
			(width 0.08255)
			(type default)
		)
		(layer "In5.Cu")
	)
	(gr_line
		(start 27.101292 -182.866538)
		(end 27.113992 -182.84825)
		(stroke
			(width 0.08255)
			(type default)
		)
		(layer "In5.Cu")
	)
	(gr_line
		(start 27.113992 -182.84825)
		(end 27.13228 -182.83555)
		(stroke
			(width 0.08255)
			(type default)
		)
		(layer "In5.Cu")
	)
	(gr_line
		(start 27.144472 -148.266658)
		(end 27.150822 -148.230844)
		(stroke
			(width 0.08255)
			(type default)
		)
		(layer "In5.Cu")
	)
	(gr_line
		(start 27.150822 -148.230844)
		(end 27.171904 -148.200618)
		(stroke
			(width 0.08255)
			(type default)
		)
		(layer "In5.Cu")
	)
	(gr_line
		(start 27.177238 -468.335868)
		(end 27.274774 -468.35314)
		(stroke
			(width 0.08255)
			(type default)
		)
		(layer "In5.Cu")
	)
	(gr_arc
		(start 27.19959 -467.97849)
		(mid 27.239519 -467.981018)
		(end 27.279346 -467.97722)
		(stroke
			(width 0.08255)
			(type default)
		)
		(layer "In5.Cu")
	)
	(gr_line
		(start 27.235404 -455.626724)
		(end 27.271218 -455.620374)
		(stroke
			(width 0.08255)
			(type default)
		)
		(layer "In5.Cu")
	)
	(gr_line
		(start 27.271218 -455.620374)
		(end 27.301444 -455.599292)
		(stroke
			(width 0.08255)
			(type default)
		)
		(layer "In5.Cu")
	)
	(gr_line
		(start 27.274774 -468.35314)
		(end 27.301444 -468.334598)
		(stroke
			(width 0.08255)
			(type default)
		)
		(layer "In5.Cu")
	)
	(gr_line
		(start 27.309826 -65.073276)
		(end 27.330908 -65.04305)
		(stroke
			(width 0.08255)
			(type default)
		)
		(layer "In5.Cu")
	)
	(gr_line
		(start 27.330908 -65.04305)
		(end 27.337258 -65.007236)
		(stroke
			(width 0.08255)
			(type default)
		)
		(layer "In5.Cu")
	)
	(gr_line
		(start 27.437334 -145.322798)
		(end 27.483054 -145.580862)
		(stroke
			(width 0.08255)
			(type default)
		)
		(layer "In5.Cu")
	)
	(gr_line
		(start 27.437334 -145.322798)
		(end 27.721306 -144.916906)
		(stroke
			(width 0.08255)
			(type default)
		)
		(layer "In5.Cu")
	)
	(gr_line
		(start 27.683968 -459.39583)
		(end 27.68727 -459.391258)
		(stroke
			(width 0.08255)
			(type default)
		)
		(layer "In5.Cu")
	)
	(gr_line
		(start 27.702764 -171.15155)
		(end 27.723592 -171.122086)
		(stroke
			(width 0.08255)
			(type default)
		)
		(layer "In5.Cu")
	)
	(gr_line
		(start 27.721306 -144.916906)
		(end 27.979878 -144.871186)
		(stroke
			(width 0.08255)
			(type default)
		)
		(layer "In5.Cu")
	)
	(gr_line
		(start 27.723592 -171.122086)
		(end 27.729942 -171.086018)
		(stroke
			(width 0.08255)
			(type default)
		)
		(layer "In5.Cu")
	)
	(gr_line
		(start 27.799538 -145.753074)
		(end 28.24988 -145.109692)
		(stroke
			(width 0.08255)
			(type default)
		)
		(layer "In5.Cu")
	)
	(gr_line
		(start 27.817318 -78.881986)
		(end 27.85237 -78.831948)
		(stroke
			(width 0.08255)
			(type default)
		)
		(layer "In5.Cu")
	)
	(gr_line
		(start 27.82316 -325.429372)
		(end 27.8638 -325.416418)
		(stroke
			(width 0.08255)
			(type default)
		)
		(layer "In5.Cu")
	)
	(gr_line
		(start 27.85237 -78.831948)
		(end 27.908758 -78.80858)
		(stroke
			(width 0.08255)
			(type default)
		)
		(layer "In5.Cu")
	)
	(gr_line
		(start 27.863038 -274.26158)
		(end 27.88412 -274.231354)
		(stroke
			(width 0.08255)
			(type default)
		)
		(layer "In5.Cu")
	)
	(gr_line
		(start 27.8638 -325.416418)
		(end 27.907996 -325.424038)
		(stroke
			(width 0.08255)
			(type default)
		)
		(layer "In5.Cu")
	)
	(gr_line
		(start 27.870912 -325.787512)
		(end 27.88285 -325.783702)
		(stroke
			(width 0.08255)
			(type default)
		)
		(layer "In5.Cu")
	)
	(gr_line
		(start 27.88412 -274.231354)
		(end 27.89047 -274.195286)
		(stroke
			(width 0.08255)
			(type default)
		)
		(layer "In5.Cu")
	)
	(gr_line
		(start 27.916886 -347.889576)
		(end 27.9527 -347.895926)
		(stroke
			(width 0.08255)
			(type default)
		)
		(layer "In5.Cu")
	)
	(gr_line
		(start 27.921204 -459.664308)
		(end 27.94 -459.6511)
		(stroke
			(width 0.08255)
			(type default)
		)
		(layer "In5.Cu")
	)
	(gr_line
		(start 27.94 -459.650084)
		(end 27.94 -459.6511)
		(stroke
			(width 0.08255)
			(type default)
		)
		(layer "In5.Cu")
	)
	(gr_line
		(start 27.94 -459.650084)
		(end 27.949906 -459.635606)
		(stroke
			(width 0.08255)
			(type default)
		)
		(layer "In5.Cu")
	)
	(gr_line
		(start 27.943302 -350.841056)
		(end 27.96032 -350.829118)
		(stroke
			(width 0.08255)
			(type default)
		)
		(layer "In5.Cu")
	)
	(gr_line
		(start 27.9527 -347.895926)
		(end 27.98191 -347.9165)
		(stroke
			(width 0.08255)
			(type default)
		)
		(layer "In5.Cu")
	)
	(gr_line
		(start 27.96032 -350.829118)
		(end 27.972258 -350.8121)
		(stroke
			(width 0.08255)
			(type default)
		)
		(layer "In5.Cu")
	)
	(gr_line
		(start 27.971242 -459.60538)
		(end 27.974544 -459.600808)
		(stroke
			(width 0.08255)
			(type default)
		)
		(layer "In5.Cu")
	)
	(gr_line
		(start 27.98318 -141.901164)
		(end 28.018994 -141.907514)
		(stroke
			(width 0.08255)
			(type default)
		)
		(layer "In5.Cu")
	)
	(gr_line
		(start 27.984196 -340.700868)
		(end 27.987752 -340.721696)
		(stroke
			(width 0.08255)
			(type default)
		)
		(layer "In5.Cu")
	)
	(gr_line
		(start 27.984196 -340.700868)
		(end 27.987752 -340.680294)
		(stroke
			(width 0.08255)
			(type default)
		)
		(layer "In5.Cu")
	)
	(gr_line
		(start 27.987752 -340.721442)
		(end 27.987752 -340.722204)
		(stroke
			(width 0.08255)
			(type default)
		)
		(layer "In5.Cu")
	)
	(gr_line
		(start 28.011628 -341.938356)
		(end 28.09748 -342.426036)
		(stroke
			(width 0.08255)
			(type default)
		)
		(layer "In5.Cu")
	)
	(gr_line
		(start 28.011628 -341.938356)
		(end 28.161996 -341.723472)
		(stroke
			(width 0.08255)
			(type default)
		)
		(layer "In5.Cu")
	)
	(gr_line
		(start 28.018994 -141.907514)
		(end 28.04922 -141.928596)
		(stroke
			(width 0.08255)
			(type default)
		)
		(layer "In5.Cu")
	)
	(gr_line
		(start 28.056332 -148.752814)
		(end 28.062428 -148.717)
		(stroke
			(width 0.08255)
			(type default)
		)
		(layer "In5.Cu")
	)
	(gr_line
		(start 28.062428 -148.717)
		(end 28.083764 -148.686266)
		(stroke
			(width 0.08255)
			(type default)
		)
		(layer "In5.Cu")
	)
	(gr_line
		(start 28.09748 -342.426036)
		(end 28.312618 -342.576912)
		(stroke
			(width 0.08255)
			(type default)
		)
		(layer "In5.Cu")
	)
	(gr_line
		(start 28.104084 -148.657564)
		(end 28.111958 -148.646388)
		(stroke
			(width 0.08255)
			(type default)
		)
		(layer "In5.Cu")
	)
	(gr_line
		(start 28.164282 -438.387744)
		(end 28.221686 -438.347612)
		(stroke
			(width 0.08255)
			(type default)
		)
		(layer "In5.Cu")
	)
	(gr_line
		(start 28.164282 -227.587556)
		(end 28.221686 -227.547424)
		(stroke
			(width 0.08255)
			(type default)
		)
		(layer "In5.Cu")
	)
	(gr_line
		(start 28.164536 -232.387648)
		(end 28.22194 -232.347516)
		(stroke
			(width 0.08255)
			(type default)
		)
		(layer "In5.Cu")
	)
	(gr_line
		(start 28.243784 -335.134966)
		(end 28.279598 -335.141316)
		(stroke
			(width 0.08255)
			(type default)
		)
		(layer "In5.Cu")
	)
	(gr_line
		(start 28.248864 -343.284048)
		(end 28.33497 -343.771728)
		(stroke
			(width 0.08255)
			(type default)
		)
		(layer "In5.Cu")
	)
	(gr_line
		(start 28.248864 -343.284048)
		(end 28.399486 -343.06891)
		(stroke
			(width 0.08255)
			(type default)
		)
		(layer "In5.Cu")
	)
	(gr_line
		(start 28.279598 -335.141316)
		(end 28.309824 -335.162398)
		(stroke
			(width 0.08255)
			(type default)
		)
		(layer "In5.Cu")
	)
	(gr_line
		(start 28.33497 -343.771728)
		(end 28.549854 -343.922604)
		(stroke
			(width 0.08255)
			(type default)
		)
		(layer "In5.Cu")
	)
	(gr_line
		(start 28.337002 -337.617562)
		(end 28.422854 -337.129882)
		(stroke
			(width 0.08255)
			(type default)
		)
		(layer "In5.Cu")
	)
	(gr_line
		(start 28.337002 -337.617562)
		(end 28.48737 -337.832446)
		(stroke
			(width 0.08255)
			(type default)
		)
		(layer "In5.Cu")
	)
	(gr_line
		(start 28.362402 -142.147798)
		(end 28.380944 -142.160752)
		(stroke
			(width 0.08255)
			(type default)
		)
		(layer "In5.Cu")
	)
	(gr_line
		(start 28.380944 -142.160752)
		(end 28.393644 -142.178786)
		(stroke
			(width 0.08255)
			(type default)
		)
		(layer "In5.Cu")
	)
	(gr_line
		(start 28.397962 -348.207076)
		(end 28.41625 -348.22003)
		(stroke
			(width 0.08255)
			(type default)
		)
		(layer "In5.Cu")
	)
	(gr_line
		(start 28.41625 -348.22003)
		(end 28.428696 -348.23781)
		(stroke
			(width 0.08255)
			(type default)
		)
		(layer "In5.Cu")
	)
	(gr_line
		(start 28.422854 -337.129882)
		(end 28.637738 -336.979006)
		(stroke
			(width 0.08255)
			(type default)
		)
		(layer "In5.Cu")
	)
	(gr_line
		(start 28.426664 -245.084854)
		(end 28.462732 -245.078504)
		(stroke
			(width 0.08255)
			(type default)
		)
		(layer "In5.Cu")
	)
	(gr_line
		(start 28.455112 -451.057264)
		(end 28.490926 -451.050914)
		(stroke
			(width 0.08255)
			(type default)
		)
		(layer "In5.Cu")
	)
	(gr_line
		(start 28.45816 -437.744616)
		(end 28.50388 -437.486298)
		(stroke
			(width 0.08255)
			(type default)
		)
		(layer "In5.Cu")
	)
	(gr_line
		(start 28.45816 -226.944428)
		(end 28.50388 -226.68611)
		(stroke
			(width 0.08255)
			(type default)
		)
		(layer "In5.Cu")
	)
	(gr_line
		(start 28.462732 -245.078504)
		(end 28.492958 -245.057422)
		(stroke
			(width 0.08255)
			(type default)
		)
		(layer "In5.Cu")
	)
	(gr_line
		(start 28.485846 -129.102866)
		(end 28.521914 -129.109216)
		(stroke
			(width 0.08255)
			(type default)
		)
		(layer "In5.Cu")
	)
	(gr_line
		(start 28.486354 -344.629994)
		(end 28.57246 -345.117674)
		(stroke
			(width 0.08255)
			(type default)
		)
		(layer "In5.Cu")
	)
	(gr_line
		(start 28.486354 -344.629994)
		(end 28.636722 -344.414856)
		(stroke
			(width 0.08255)
			(type default)
		)
		(layer "In5.Cu")
	)
	(gr_line
		(start 28.490926 -451.050914)
		(end 28.521152 -451.029832)
		(stroke
			(width 0.08255)
			(type default)
		)
		(layer "In5.Cu")
	)
	(gr_line
		(start 28.49626 -480.922076)
		(end 28.517342 -480.925632)
		(stroke
			(width 0.08255)
			(type default)
		)
		(layer "In5.Cu")
	)
	(gr_line
		(start 28.50388 -437.486298)
		(end 28.909518 -437.202072)
		(stroke
			(width 0.08255)
			(type default)
		)
		(layer "In5.Cu")
	)
	(gr_line
		(start 28.50388 -226.68611)
		(end 28.909772 -226.402138)
		(stroke
			(width 0.08255)
			(type default)
		)
		(layer "In5.Cu")
	)
	(gr_line
		(start 28.517342 -480.925632)
		(end 28.537662 -480.922076)
		(stroke
			(width 0.08255)
			(type default)
		)
		(layer "In5.Cu")
	)
	(gr_line
		(start 28.52166 -341.699596)
		(end 28.659074 -342.478614)
		(stroke
			(width 0.08255)
			(type default)
		)
		(layer "In5.Cu")
	)
	(gr_line
		(start 28.521914 -129.109216)
		(end 28.55214 -129.130298)
		(stroke
			(width 0.08255)
			(type default)
		)
		(layer "In5.Cu")
	)
	(gr_line
		(start 28.57246 -345.117674)
		(end 28.787344 -345.268042)
		(stroke
			(width 0.08255)
			(type default)
		)
		(layer "In5.Cu")
	)
	(gr_line
		(start 28.598622 -171.559474)
		(end 28.619704 -171.529248)
		(stroke
			(width 0.08255)
			(type default)
		)
		(layer "In5.Cu")
	)
	(gr_line
		(start 28.619704 -171.529248)
		(end 28.626054 -171.49318)
		(stroke
			(width 0.08255)
			(type default)
		)
		(layer "In5.Cu")
	)
	(gr_line
		(start 28.645866 -349.850202)
		(end 28.666948 -349.819976)
		(stroke
			(width 0.08255)
			(type default)
		)
		(layer "In5.Cu")
	)
	(gr_line
		(start 28.647644 -142.542006)
		(end 28.669996 -142.57401)
		(stroke
			(width 0.08255)
			(type default)
		)
		(layer "In5.Cu")
	)
	(gr_line
		(start 28.64993 -348.554802)
		(end 28.669996 -348.58325)
		(stroke
			(width 0.08255)
			(type default)
		)
		(layer "In5.Cu")
	)
	(gr_line
		(start 28.658312 -65.080642)
		(end 28.679394 -65.050416)
		(stroke
			(width 0.08255)
			(type default)
		)
		(layer "In5.Cu")
	)
	(gr_line
		(start 28.666948 -349.819976)
		(end 28.673298 -349.783908)
		(stroke
			(width 0.08255)
			(type default)
		)
		(layer "In5.Cu")
	)
	(gr_line
		(start 28.669996 -348.58325)
		(end 28.670758 -348.583758)
		(stroke
			(width 0.08255)
			(type default)
		)
		(layer "In5.Cu")
	)
	(gr_line
		(start 28.669996 -142.57401)
		(end 28.676854 -142.612364)
		(stroke
			(width 0.08255)
			(type default)
		)
		(layer "In5.Cu")
	)
	(gr_line
		(start 28.670758 -348.583758)
		(end 28.677108 -348.621096)
		(stroke
			(width 0.08255)
			(type default)
		)
		(layer "In5.Cu")
	)
	(gr_line
		(start 28.679394 -65.050416)
		(end 28.685744 -65.014602)
		(stroke
			(width 0.08255)
			(type default)
		)
		(layer "In5.Cu")
	)
	(gr_line
		(start 28.679902 -335.421732)
		(end 28.69819 -335.434432)
		(stroke
			(width 0.08255)
			(type default)
		)
		(layer "In5.Cu")
	)
	(gr_line
		(start 28.694126 -38.93947)
		(end 28.72994 -38.94582)
		(stroke
			(width 0.08255)
			(type default)
		)
		(layer "In5.Cu")
	)
	(gr_line
		(start 28.695904 -438.015634)
		(end 29.342334 -437.563006)
		(stroke
			(width 0.08255)
			(type default)
		)
		(layer "In5.Cu")
	)
	(gr_line
		(start 28.696412 -227.214938)
		(end 29.341572 -226.763326)
		(stroke
			(width 0.08255)
			(type default)
		)
		(layer "In5.Cu")
	)
	(gr_line
		(start 28.697682 -144.470374)
		(end 28.718764 -144.440148)
		(stroke
			(width 0.08255)
			(type default)
		)
		(layer "In5.Cu")
	)
	(gr_line
		(start 28.69819 -335.434432)
		(end 28.71089 -335.45272)
		(stroke
			(width 0.08255)
			(type default)
		)
		(layer "In5.Cu")
	)
	(gr_line
		(start 28.718764 -144.440148)
		(end 28.725114 -144.404334)
		(stroke
			(width 0.08255)
			(type default)
		)
		(layer "In5.Cu")
	)
	(gr_line
		(start 28.727146 -274.951444)
		(end 28.748228 -274.921218)
		(stroke
			(width 0.08255)
			(type default)
		)
		(layer "In5.Cu")
	)
	(gr_line
		(start 28.72994 -38.94582)
		(end 28.760166 -38.966902)
		(stroke
			(width 0.08255)
			(type default)
		)
		(layer "In5.Cu")
	)
	(gr_line
		(start 28.748228 -274.921218)
		(end 28.754578 -274.88515)
		(stroke
			(width 0.08255)
			(type default)
		)
		(layer "In5.Cu")
	)
	(gr_line
		(start 28.758642 -343.043002)
		(end 28.89631 -343.823544)
		(stroke
			(width 0.08255)
			(type default)
		)
		(layer "In5.Cu")
	)
	(gr_line
		(start 28.769564 -150.360126)
		(end 28.775914 -150.324058)
		(stroke
			(width 0.08255)
			(type default)
		)
		(layer "In5.Cu")
	)
	(gr_line
		(start 28.774136 -349.212408)
		(end 28.777692 -349.19158)
		(stroke
			(width 0.08255)
			(type default)
		)
		(layer "In5.Cu")
	)
	(gr_line
		(start 28.774136 -349.212154)
		(end 28.774136 -349.212916)
		(stroke
			(width 0.08255)
			(type default)
		)
		(layer "In5.Cu")
	)
	(gr_line
		(start 28.774136 -349.170752)
		(end 28.777692 -349.19158)
		(stroke
			(width 0.08255)
			(type default)
		)
		(layer "In5.Cu")
	)
	(gr_line
		(start 28.775914 -150.324058)
		(end 28.796996 -150.293832)
		(stroke
			(width 0.08255)
			(type default)
		)
		(layer "In5.Cu")
	)
	(gr_line
		(start 28.776676 -256.14376)
		(end 28.783026 -256.107692)
		(stroke
			(width 0.08255)
			(type default)
		)
		(layer "In5.Cu")
	)
	(gr_line
		(start 28.783026 -256.107692)
		(end 28.804108 -256.077466)
		(stroke
			(width 0.08255)
			(type default)
		)
		(layer "In5.Cu")
	)
	(gr_line
		(start 28.792678 -74.911712)
		(end 28.805378 -74.893424)
		(stroke
			(width 0.08255)
			(type default)
		)
		(layer "In5.Cu")
	)
	(gr_line
		(start 28.805378 -74.893424)
		(end 28.823666 -74.880724)
		(stroke
			(width 0.08255)
			(type default)
		)
		(layer "In5.Cu")
	)
	(gr_line
		(start 28.847034 -337.854798)
		(end 28.983686 -337.079336)
		(stroke
			(width 0.08255)
			(type default)
		)
		(layer "In5.Cu")
	)
	(gr_line
		(start 28.855416 -143.66621)
		(end 28.858972 -143.645382)
		(stroke
			(width 0.08255)
			(type default)
		)
		(layer "In5.Cu")
	)
	(gr_line
		(start 28.855416 -143.665956)
		(end 28.855416 -143.666718)
		(stroke
			(width 0.08255)
			(type default)
		)
		(layer "In5.Cu")
	)
	(gr_line
		(start 28.855416 -143.624808)
		(end 28.858972 -143.645382)
		(stroke
			(width 0.08255)
			(type default)
		)
		(layer "In5.Cu")
	)
	(gr_line
		(start 28.909518 -437.202072)
		(end 29.16809 -437.247792)
		(stroke
			(width 0.08255)
			(type default)
		)
		(layer "In5.Cu")
	)
	(gr_line
		(start 28.909772 -226.402138)
		(end 29.16809 -226.447604)
		(stroke
			(width 0.08255)
			(type default)
		)
		(layer "In5.Cu")
	)
	(gr_line
		(start 28.941776 -16.600424)
		(end 28.977844 -16.606774)
		(stroke
			(width 0.08255)
			(type default)
		)
		(layer "In5.Cu")
	)
	(gr_line
		(start 28.948634 -335.792572)
		(end 28.970478 -335.82356)
		(stroke
			(width 0.08255)
			(type default)
		)
		(layer "In5.Cu")
	)
	(gr_line
		(start 28.970478 -335.82356)
		(end 28.977336 -335.861914)
		(stroke
			(width 0.08255)
			(type default)
		)
		(layer "In5.Cu")
	)
	(gr_line
		(start 28.977844 -16.606774)
		(end 29.00807 -16.627856)
		(stroke
			(width 0.08255)
			(type default)
		)
		(layer "In5.Cu")
	)
	(gr_line
		(start 28.994608 -124.392436)
		(end 29.031692 -124.39904)
		(stroke
			(width 0.08255)
			(type default)
		)
		(layer "In5.Cu")
	)
	(gr_line
		(start 28.996386 -344.39098)
		(end 29.133546 -345.167966)
		(stroke
			(width 0.08255)
			(type default)
		)
		(layer "In5.Cu")
	)
	(gr_line
		(start 29.004768 -280.746962)
		(end 29.017468 -280.728674)
		(stroke
			(width 0.08255)
			(type default)
		)
		(layer "In5.Cu")
	)
	(gr_line
		(start 29.011372 -244.694456)
		(end 29.02966 -244.681756)
		(stroke
			(width 0.08255)
			(type default)
		)
		(layer "In5.Cu")
	)
	(gr_line
		(start 29.017468 -280.728674)
		(end 29.035756 -280.715974)
		(stroke
			(width 0.08255)
			(type default)
		)
		(layer "In5.Cu")
	)
	(gr_line
		(start 29.02966 -244.681756)
		(end 29.04236 -244.663468)
		(stroke
			(width 0.08255)
			(type default)
		)
		(layer "In5.Cu")
	)
	(gr_line
		(start 29.031692 -124.39904)
		(end 29.061156 -124.419868)
		(stroke
			(width 0.08255)
			(type default)
		)
		(layer "In5.Cu")
	)
	(gr_line
		(start 29.08427 -336.510376)
		(end 29.087826 -336.489548)
		(stroke
			(width 0.08255)
			(type default)
		)
		(layer "In5.Cu")
	)
	(gr_line
		(start 29.08427 -336.510122)
		(end 29.08427 -336.510884)
		(stroke
			(width 0.08255)
			(type default)
		)
		(layer "In5.Cu")
	)
	(gr_line
		(start 29.08427 -336.468974)
		(end 29.087826 -336.489548)
		(stroke
			(width 0.08255)
			(type default)
		)
		(layer "In5.Cu")
	)
	(gr_line
		(start 29.140912 -134.954518)
		(end 29.144468 -134.975346)
		(stroke
			(width 0.08255)
			(type default)
		)
		(layer "In5.Cu")
	)
	(gr_line
		(start 29.140912 -134.954518)
		(end 29.144468 -134.933944)
		(stroke
			(width 0.08255)
			(type default)
		)
		(layer "In5.Cu")
	)
	(gr_line
		(start 29.143198 -449.255388)
		(end 29.229304 -448.767708)
		(stroke
			(width 0.08255)
			(type default)
		)
		(layer "In5.Cu")
	)
	(gr_line
		(start 29.143198 -449.255388)
		(end 29.29382 -449.470526)
		(stroke
			(width 0.08255)
			(type default)
		)
		(layer "In5.Cu")
	)
	(gr_line
		(start 29.144468 -134.975092)
		(end 29.144468 -134.975854)
		(stroke
			(width 0.08255)
			(type default)
		)
		(layer "In5.Cu")
	)
	(gr_line
		(start 29.163264 -276.764496)
		(end 29.184346 -276.73427)
		(stroke
			(width 0.08255)
			(type default)
		)
		(layer "In5.Cu")
	)
	(gr_line
		(start 29.184346 -276.73427)
		(end 29.190696 -276.698456)
		(stroke
			(width 0.08255)
			(type default)
		)
		(layer "In5.Cu")
	)
	(gr_line
		(start 29.20238 -129.585466)
		(end 29.220668 -129.598166)
		(stroke
			(width 0.08255)
			(type default)
		)
		(layer "In5.Cu")
	)
	(gr_line
		(start 29.220668 -129.598166)
		(end 29.233622 -129.616454)
		(stroke
			(width 0.08255)
			(type default)
		)
		(layer "In5.Cu")
	)
	(gr_line
		(start 29.223462 -136.504934)
		(end 29.309314 -136.992614)
		(stroke
			(width 0.08255)
			(type default)
		)
		(layer "In5.Cu")
	)
	(gr_line
		(start 29.223462 -136.504934)
		(end 29.37383 -136.29005)
		(stroke
			(width 0.08255)
			(type default)
		)
		(layer "In5.Cu")
	)
	(gr_line
		(start 29.229304 -448.767708)
		(end 29.444442 -448.617086)
		(stroke
			(width 0.08255)
			(type default)
		)
		(layer "In5.Cu")
	)
	(gr_line
		(start 29.23921 -450.527166)
		(end 29.256228 -450.515228)
		(stroke
			(width 0.08255)
			(type default)
		)
		(layer "In5.Cu")
	)
	(gr_line
		(start 29.256228 -450.515482)
		(end 29.269182 -450.497194)
		(stroke
			(width 0.08255)
			(type default)
		)
		(layer "In5.Cu")
	)
	(gr_line
		(start 29.256228 -450.515228)
		(end 29.256228 -450.515482)
		(stroke
			(width 0.08255)
			(type default)
		)
		(layer "In5.Cu")
	)
	(gr_line
		(start 29.309314 -136.992614)
		(end 29.524198 -137.14349)
		(stroke
			(width 0.08255)
			(type default)
		)
		(layer "In5.Cu")
	)
	(gr_line
		(start 29.3116 -325.665846)
		(end 29.349446 -325.67245)
		(stroke
			(width 0.08255)
			(type default)
		)
		(layer "In5.Cu")
	)
	(gr_line
		(start 29.320236 -330.152502)
		(end 29.34081 -330.148946)
		(stroke
			(width 0.08255)
			(type default)
		)
		(layer "In5.Cu")
	)
	(gr_line
		(start 29.326332 -351.103438)
		(end 29.343604 -351.091246)
		(stroke
			(width 0.08255)
			(type default)
		)
		(layer "In5.Cu")
	)
	(gr_line
		(start 29.34081 -330.148946)
		(end 29.361384 -330.152502)
		(stroke
			(width 0.08255)
			(type default)
		)
		(layer "In5.Cu")
	)
	(gr_line
		(start 29.343604 -351.091246)
		(end 29.35478 -351.07499)
		(stroke
			(width 0.08255)
			(type default)
		)
		(layer "In5.Cu")
	)
	(gr_line
		(start 29.349446 -325.67245)
		(end 29.381196 -325.694548)
		(stroke
			(width 0.08255)
			(type default)
		)
		(layer "In5.Cu")
	)
	(gr_line
		(start 29.380434 -447.909696)
		(end 29.46654 -447.422016)
		(stroke
			(width 0.08255)
			(type default)
		)
		(layer "In5.Cu")
	)
	(gr_line
		(start 29.380434 -447.909696)
		(end 29.53131 -448.12458)
		(stroke
			(width 0.08255)
			(type default)
		)
		(layer "In5.Cu")
	)
	(gr_line
		(start 29.395928 -66.689224)
		(end 29.41701 -66.658998)
		(stroke
			(width 0.08255)
			(type default)
		)
		(layer "In5.Cu")
	)
	(gr_line
		(start 29.41701 -66.658998)
		(end 29.42336 -66.62293)
		(stroke
			(width 0.08255)
			(type default)
		)
		(layer "In5.Cu")
	)
	(gr_line
		(start 29.418788 -451.999096)
		(end 29.419042 -451.999096)
		(stroke
			(width 0.08255)
			(type default)
		)
		(layer "In5.Cu")
	)
	(gr_line
		(start 29.460444 -137.850626)
		(end 29.54655 -138.338306)
		(stroke
			(width 0.08255)
			(type default)
		)
		(layer "In5.Cu")
	)
	(gr_line
		(start 29.460444 -137.850626)
		(end 29.611066 -137.635742)
		(stroke
			(width 0.08255)
			(type default)
		)
		(layer "In5.Cu")
	)
	(gr_line
		(start 29.46654 -447.422016)
		(end 29.681678 -447.27114)
		(stroke
			(width 0.08255)
			(type default)
		)
		(layer "In5.Cu")
	)
	(gr_line
		(start 29.472636 -172.08627)
		(end 29.493718 -172.056044)
		(stroke
			(width 0.08255)
			(type default)
		)
		(layer "In5.Cu")
	)
	(gr_line
		(start 29.484574 -247.384062)
		(end 29.50718 -247.36933)
		(stroke
			(width 0.08255)
			(type default)
		)
		(layer "In5.Cu")
	)
	(gr_line
		(start 29.493718 -172.056044)
		(end 29.500068 -172.019976)
		(stroke
			(width 0.08255)
			(type default)
		)
		(layer "In5.Cu")
	)
	(gr_line
		(start 29.494988 -244.017038)
		(end 29.51607 -243.986812)
		(stroke
			(width 0.08255)
			(type default)
		)
		(layer "In5.Cu")
	)
	(gr_line
		(start 29.506164 -130.00609)
		(end 29.527246 -130.036316)
		(stroke
			(width 0.08255)
			(type default)
		)
		(layer "In5.Cu")
	)
	(gr_line
		(start 29.50718 -247.36933)
		(end 29.522674 -247.347232)
		(stroke
			(width 0.08255)
			(type default)
		)
		(layer "In5.Cu")
	)
	(gr_line
		(start 29.51607 -243.986812)
		(end 29.52242 -243.950744)
		(stroke
			(width 0.08255)
			(type default)
		)
		(layer "In5.Cu")
	)
	(gr_line
		(start 29.523182 -39.501064)
		(end 29.54147 -39.513764)
		(stroke
			(width 0.08255)
			(type default)
		)
		(layer "In5.Cu")
	)
	(gr_line
		(start 29.524706 -450.131434)
		(end 29.54655 -450.100446)
		(stroke
			(width 0.08255)
			(type default)
		)
		(layer "In5.Cu")
	)
	(gr_line
		(start 29.527246 -130.036316)
		(end 29.533596 -130.072384)
		(stroke
			(width 0.08255)
			(type default)
		)
		(layer "In5.Cu")
	)
	(gr_line
		(start 29.54147 -39.513764)
		(end 29.55417 -39.532052)
		(stroke
			(width 0.08255)
			(type default)
		)
		(layer "In5.Cu")
	)
	(gr_line
		(start 29.54655 -450.100446)
		(end 29.553408 -450.062092)
		(stroke
			(width 0.08255)
			(type default)
		)
		(layer "In5.Cu")
	)
	(gr_line
		(start 29.54655 -138.338306)
		(end 29.761434 -138.488674)
		(stroke
			(width 0.08255)
			(type default)
		)
		(layer "In5.Cu")
	)
	(gr_line
		(start 29.556964 -222.525082)
		(end 29.593032 -222.518732)
		(stroke
			(width 0.08255)
			(type default)
		)
		(layer "In5.Cu")
	)
	(gr_line
		(start 29.565346 -454.014078)
		(end 29.583634 -454.001378)
		(stroke
			(width 0.08255)
			(type default)
		)
		(layer "In5.Cu")
	)
	(gr_line
		(start 29.56687 -240.567718)
		(end 29.652976 -240.080038)
		(stroke
			(width 0.08255)
			(type default)
		)
		(layer "In5.Cu")
	)
	(gr_line
		(start 29.56687 -240.567718)
		(end 29.717492 -240.782348)
		(stroke
			(width 0.08255)
			(type default)
		)
		(layer "In5.Cu")
	)
	(gr_line
		(start 29.577538 -436.961026)
		(end 29.623258 -436.702454)
		(stroke
			(width 0.08255)
			(type default)
		)
		(layer "In5.Cu")
	)
	(gr_line
		(start 29.577792 -226.160584)
		(end 29.623258 -225.902266)
		(stroke
			(width 0.08255)
			(type default)
		)
		(layer "In5.Cu")
	)
	(gr_line
		(start 29.583634 -454.001378)
		(end 29.596334 -453.98309)
		(stroke
			(width 0.08255)
			(type default)
		)
		(layer "In5.Cu")
	)
	(gr_line
		(start 29.593032 -222.518732)
		(end 29.623258 -222.49765)
		(stroke
			(width 0.08255)
			(type default)
		)
		(layer "In5.Cu")
	)
	(gr_line
		(start 29.617924 -446.564004)
		(end 29.703776 -446.07607)
		(stroke
			(width 0.08255)
			(type default)
		)
		(layer "In5.Cu")
	)
	(gr_line
		(start 29.617924 -446.564004)
		(end 29.768546 -446.778888)
		(stroke
			(width 0.08255)
			(type default)
		)
		(layer "In5.Cu")
	)
	(gr_line
		(start 29.623258 -436.702454)
		(end 30.028896 -436.418482)
		(stroke
			(width 0.08255)
			(type default)
		)
		(layer "In5.Cu")
	)
	(gr_line
		(start 29.623258 -225.902266)
		(end 30.02915 -225.618294)
		(stroke
			(width 0.08255)
			(type default)
		)
		(layer "In5.Cu")
	)
	(gr_line
		(start 29.648658 -145.283936)
		(end 29.66974 -145.25371)
		(stroke
			(width 0.08255)
			(type default)
		)
		(layer "In5.Cu")
	)
	(gr_line
		(start 29.652976 -240.080038)
		(end 29.86786 -239.929416)
		(stroke
			(width 0.08255)
			(type default)
		)
		(layer "In5.Cu")
	)
	(gr_line
		(start 29.653484 -449.493894)
		(end 29.790644 -448.7164)
		(stroke
			(width 0.08255)
			(type default)
		)
		(layer "In5.Cu")
	)
	(gr_line
		(start 29.657294 -452.266558)
		(end 29.674312 -452.25462)
		(stroke
			(width 0.08255)
			(type default)
		)
		(layer "In5.Cu")
	)
	(gr_line
		(start 29.66974 -145.25371)
		(end 29.67609 -145.217642)
		(stroke
			(width 0.08255)
			(type default)
		)
		(layer "In5.Cu")
	)
	(gr_line
		(start 29.674312 -452.25462)
		(end 29.674566 -452.25462)
		(stroke
			(width 0.08255)
			(type default)
		)
		(layer "In5.Cu")
	)
	(gr_line
		(start 29.674312 -26.312368)
		(end 29.71038 -26.318718)
		(stroke
			(width 0.08255)
			(type default)
		)
		(layer "In5.Cu")
	)
	(gr_line
		(start 29.674566 -452.25462)
		(end 29.688028 -452.23557)
		(stroke
			(width 0.08255)
			(type default)
		)
		(layer "In5.Cu")
	)
	(gr_line
		(start 29.681932 -256.478786)
		(end 29.688282 -256.442718)
		(stroke
			(width 0.08255)
			(type default)
		)
		(layer "In5.Cu")
	)
	(gr_line
		(start 29.688282 -256.442718)
		(end 29.709364 -256.412492)
		(stroke
			(width 0.08255)
			(type default)
		)
		(layer "In5.Cu")
	)
	(gr_line
		(start 29.692346 -340.997032)
		(end 29.695902 -341.01786)
		(stroke
			(width 0.08255)
			(type default)
		)
		(layer "In5.Cu")
	)
	(gr_line
		(start 29.692346 -340.997032)
		(end 29.695902 -340.976458)
		(stroke
			(width 0.08255)
			(type default)
		)
		(layer "In5.Cu")
	)
	(gr_line
		(start 29.695902 -341.017606)
		(end 29.695902 -341.018368)
		(stroke
			(width 0.08255)
			(type default)
		)
		(layer "In5.Cu")
	)
	(gr_line
		(start 29.703776 -446.07607)
		(end 29.918914 -445.925448)
		(stroke
			(width 0.08255)
			(type default)
		)
		(layer "In5.Cu")
	)
	(gr_line
		(start 29.704284 -40.917114)
		(end 29.704538 -40.917368)
		(stroke
			(width 0.08255)
			(type default)
		)
		(layer "In5.Cu")
	)
	(gr_line
		(start 29.71038 -26.318718)
		(end 29.740606 -26.3398)
		(stroke
			(width 0.08255)
			(type default)
		)
		(layer "In5.Cu")
	)
	(gr_line
		(start 29.733494 -136.266428)
		(end 29.870654 -137.044176)
		(stroke
			(width 0.08255)
			(type default)
		)
		(layer "In5.Cu")
	)
	(gr_line
		(start 29.74594 -325.950072)
		(end 29.764228 -325.962772)
		(stroke
			(width 0.08255)
			(type default)
		)
		(layer "In5.Cu")
	)
	(gr_line
		(start 29.764228 -325.962772)
		(end 29.776928 -325.98106)
		(stroke
			(width 0.08255)
			(type default)
		)
		(layer "In5.Cu")
	)
	(gr_line
		(start 29.780738 -180.980588)
		(end 29.810964 -180.959506)
		(stroke
			(width 0.08255)
			(type default)
		)
		(layer "In5.Cu")
	)
	(gr_line
		(start 29.79801 -151.647652)
		(end 29.80436 -151.611584)
		(stroke
			(width 0.08255)
			(type default)
		)
		(layer "In5.Cu")
	)
	(gr_line
		(start 29.80436 -239.222026)
		(end 29.890212 -238.734346)
		(stroke
			(width 0.08255)
			(type default)
		)
		(layer "In5.Cu")
	)
	(gr_line
		(start 29.80436 -239.222026)
		(end 29.954728 -239.43691)
		(stroke
			(width 0.08255)
			(type default)
		)
		(layer "In5.Cu")
	)
	(gr_line
		(start 29.80436 -151.611584)
		(end 29.825188 -151.58212)
		(stroke
			(width 0.08255)
			(type default)
		)
		(layer "In5.Cu")
	)
	(gr_line
		(start 29.810964 -180.959506)
		(end 29.846778 -180.953156)
		(stroke
			(width 0.08255)
			(type default)
		)
		(layer "In5.Cu")
	)
	(gr_line
		(start 29.815028 -437.232044)
		(end 30.46222 -436.778908)
		(stroke
			(width 0.08255)
			(type default)
		)
		(layer "In5.Cu")
	)
	(gr_line
		(start 29.816044 -226.431094)
		(end 30.460442 -225.97999)
		(stroke
			(width 0.08255)
			(type default)
		)
		(layer "In5.Cu")
	)
	(gr_line
		(start 29.869638 -131.977384)
		(end 29.8704 -131.98221)
		(stroke
			(width 0.08255)
			(type default)
		)
		(layer "In5.Cu")
	)
	(gr_line
		(start 29.870146 -131.98221)
		(end 29.8704 -131.98221)
		(stroke
			(width 0.08255)
			(type default)
		)
		(layer "In5.Cu")
	)
	(gr_line
		(start 29.886148 -177.056796)
		(end 29.898848 -177.038508)
		(stroke
			(width 0.08255)
			(type default)
		)
		(layer "In5.Cu")
	)
	(gr_line
		(start 29.890212 -238.734346)
		(end 30.10535 -238.58347)
		(stroke
			(width 0.08255)
			(type default)
		)
		(layer "In5.Cu")
	)
	(gr_line
		(start 29.890212 -40.011858)
		(end 29.911294 -40.042084)
		(stroke
			(width 0.08255)
			(type default)
		)
		(layer "In5.Cu")
	)
	(gr_line
		(start 29.89072 -448.148456)
		(end 30.02788 -447.370454)
		(stroke
			(width 0.08255)
			(type default)
		)
		(layer "In5.Cu")
	)
	(gr_line
		(start 29.896308 -350.30283)
		(end 29.917898 -350.27235)
		(stroke
			(width 0.08255)
			(type default)
		)
		(layer "In5.Cu")
	)
	(gr_line
		(start 29.898848 -177.038508)
		(end 29.917136 -177.025808)
		(stroke
			(width 0.08255)
			(type default)
		)
		(layer "In5.Cu")
	)
	(gr_line
		(start 29.911294 -40.042084)
		(end 29.917644 -40.078152)
		(stroke
			(width 0.08255)
			(type default)
		)
		(layer "In5.Cu")
	)
	(gr_line
		(start 29.917898 -350.27235)
		(end 29.924502 -350.235266)
		(stroke
			(width 0.08255)
			(type default)
		)
		(layer "In5.Cu")
	)
	(gr_line
		(start 29.97073 -137.61212)
		(end 30.107636 -138.388852)
		(stroke
			(width 0.08255)
			(type default)
		)
		(layer "In5.Cu")
	)
	(gr_line
		(start 29.972254 -349.96501)
		(end 29.972254 -349.965772)
		(stroke
			(width 0.08255)
			(type default)
		)
		(layer "In5.Cu")
	)
	(gr_line
		(start 29.972254 -349.96501)
		(end 29.97581 -349.944436)
		(stroke
			(width 0.08255)
			(type default)
		)
		(layer "In5.Cu")
	)
	(gr_line
		(start 29.972254 -349.923862)
		(end 29.97581 -349.944436)
		(stroke
			(width 0.08255)
			(type default)
		)
		(layer "In5.Cu")
	)
	(gr_line
		(start 29.990542 -221.803214)
		(end 30.036262 -221.544642)
		(stroke
			(width 0.08255)
			(type default)
		)
		(layer "In5.Cu")
	)
	(gr_line
		(start 30.005274 -249.530108)
		(end 30.023562 -249.517408)
		(stroke
			(width 0.08255)
			(type default)
		)
		(layer "In5.Cu")
	)
	(gr_line
		(start 30.023562 -249.517408)
		(end 30.036262 -249.49912)
		(stroke
			(width 0.08255)
			(type default)
		)
		(layer "In5.Cu")
	)
	(gr_line
		(start 30.028896 -436.418482)
		(end 30.287468 -436.463948)
		(stroke
			(width 0.08255)
			(type default)
		)
		(layer "In5.Cu")
	)
	(gr_line
		(start 30.02915 -225.618294)
		(end 30.287214 -225.664014)
		(stroke
			(width 0.08255)
			(type default)
		)
		(layer "In5.Cu")
	)
	(gr_line
		(start 30.036262 -221.544642)
		(end 30.4419 -221.260416)
		(stroke
			(width 0.08255)
			(type default)
		)
		(layer "In5.Cu")
	)
	(gr_line
		(start 30.041596 -237.876334)
		(end 30.127702 -237.3884)
		(stroke
			(width 0.08255)
			(type default)
		)
		(layer "In5.Cu")
	)
	(gr_line
		(start 30.041596 -237.876334)
		(end 30.191964 -238.091218)
		(stroke
			(width 0.08255)
			(type default)
		)
		(layer "In5.Cu")
	)
	(gr_line
		(start 30.042612 -26.551382)
		(end 30.0609 -26.564082)
		(stroke
			(width 0.08255)
			(type default)
		)
		(layer "In5.Cu")
	)
	(gr_line
		(start 30.052772 -40.84574)
		(end 30.05455 -40.855392)
		(stroke
			(width 0.08255)
			(type default)
		)
		(layer "In5.Cu")
	)
	(gr_line
		(start 30.054804 -40.855392)
		(end 30.05455 -40.855392)
		(stroke
			(width 0.08255)
			(type default)
		)
		(layer "In5.Cu")
	)
	(gr_line
		(start 30.0609 -26.564082)
		(end 30.0736 -26.58237)
		(stroke
			(width 0.08255)
			(type default)
		)
		(layer "In5.Cu")
	)
	(gr_line
		(start 30.077156 -240.805716)
		(end 30.213808 -240.029492)
		(stroke
			(width 0.08255)
			(type default)
		)
		(layer "In5.Cu")
	)
	(gr_line
		(start 30.127448 -330.28763)
		(end 30.163262 -330.29398)
		(stroke
			(width 0.08255)
			(type default)
		)
		(layer "In5.Cu")
	)
	(gr_line
		(start 30.127702 -237.3884)
		(end 30.342586 -237.238032)
		(stroke
			(width 0.08255)
			(type default)
		)
		(layer "In5.Cu")
	)
	(gr_line
		(start 30.127956 -446.802764)
		(end 30.265116 -446.024762)
		(stroke
			(width 0.08255)
			(type default)
		)
		(layer "In5.Cu")
	)
	(gr_line
		(start 30.132274 -27.613864)
		(end 30.17774 -27.355038)
		(stroke
			(width 0.08255)
			(type default)
		)
		(layer "In5.Cu")
	)
	(gr_line
		(start 30.132274 -27.613864)
		(end 30.4165 -28.019502)
		(stroke
			(width 0.08255)
			(type default)
		)
		(layer "In5.Cu")
	)
	(gr_line
		(start 30.163262 -351.732342)
		(end 30.182058 -351.719134)
		(stroke
			(width 0.08255)
			(type default)
		)
		(layer "In5.Cu")
	)
	(gr_line
		(start 30.163262 -330.29398)
		(end 30.193488 -330.315062)
		(stroke
			(width 0.08255)
			(type default)
		)
		(layer "In5.Cu")
	)
	(gr_line
		(start 30.182058 -351.719134)
		(end 30.194758 -351.7011)
		(stroke
			(width 0.08255)
			(type default)
		)
		(layer "In5.Cu")
	)
	(gr_line
		(start 30.199584 -17.89938)
		(end 30.24505 -18.157698)
		(stroke
			(width 0.08255)
			(type default)
		)
		(layer "In5.Cu")
	)
	(gr_line
		(start 30.228032 -222.074232)
		(end 30.875224 -221.621096)
		(stroke
			(width 0.08255)
			(type default)
		)
		(layer "In5.Cu")
	)
	(gr_line
		(start 30.24505 -18.157698)
		(end 30.650942 -18.441924)
		(stroke
			(width 0.08255)
			(type default)
		)
		(layer "In5.Cu")
	)
	(gr_line
		(start 30.305248 -336.439256)
		(end 30.391354 -335.951576)
		(stroke
			(width 0.08255)
			(type default)
		)
		(layer "In5.Cu")
	)
	(gr_line
		(start 30.305248 -336.439256)
		(end 30.455616 -336.65414)
		(stroke
			(width 0.08255)
			(type default)
		)
		(layer "In5.Cu")
	)
	(gr_line
		(start 30.314392 -239.460532)
		(end 30.451552 -238.682784)
		(stroke
			(width 0.08255)
			(type default)
		)
		(layer "In5.Cu")
	)
	(gr_line
		(start 30.372558 -120.682766)
		(end 30.418278 -120.941338)
		(stroke
			(width 0.08255)
			(type default)
		)
		(layer "In5.Cu")
	)
	(gr_line
		(start 30.391354 -335.951576)
		(end 30.606238 -335.801208)
		(stroke
			(width 0.08255)
			(type default)
		)
		(layer "In5.Cu")
	)
	(gr_line
		(start 30.4165 -28.019502)
		(end 30.674818 -28.064968)
		(stroke
			(width 0.08255)
			(type default)
		)
		(layer "In5.Cu")
	)
	(gr_line
		(start 30.418278 -120.941338)
		(end 30.82417 -121.22531)
		(stroke
			(width 0.08255)
			(type default)
		)
		(layer "In5.Cu")
	)
	(gr_line
		(start 30.437582 -17.62887)
		(end 31.082742 -18.080736)
		(stroke
			(width 0.08255)
			(type default)
		)
		(layer "In5.Cu")
	)
	(gr_line
		(start 30.4419 -221.260416)
		(end 30.700472 -221.306136)
		(stroke
			(width 0.08255)
			(type default)
		)
		(layer "In5.Cu")
	)
	(gr_line
		(start 30.442154 -125.386338)
		(end 30.460442 -125.399038)
		(stroke
			(width 0.08255)
			(type default)
		)
		(layer "In5.Cu")
	)
	(gr_line
		(start 30.442916 -126.322074)
		(end 30.488382 -126.063248)
		(stroke
			(width 0.08255)
			(type default)
		)
		(layer "In5.Cu")
	)
	(gr_line
		(start 30.442916 -126.322074)
		(end 30.726888 -126.727712)
		(stroke
			(width 0.08255)
			(type default)
		)
		(layer "In5.Cu")
	)
	(gr_line
		(start 30.460442 -125.399038)
		(end 30.473142 -125.417326)
		(stroke
			(width 0.08255)
			(type default)
		)
		(layer "In5.Cu")
	)
	(gr_line
		(start 30.489144 -140.596874)
		(end 30.492954 -140.575284)
		(stroke
			(width 0.08255)
			(type default)
		)
		(layer "In5.Cu")
	)
	(gr_line
		(start 30.489398 -140.55471)
		(end 30.492954 -140.575284)
		(stroke
			(width 0.08255)
			(type default)
		)
		(layer "In5.Cu")
	)
	(gr_line
		(start 30.492446 -27.180032)
		(end 30.946852 -27.828748)
		(stroke
			(width 0.08255)
			(type default)
		)
		(layer "In5.Cu")
	)
	(gr_line
		(start 30.501082 -327.963784)
		(end 30.546802 -327.705466)
		(stroke
			(width 0.08255)
			(type default)
		)
		(layer "In5.Cu")
	)
	(gr_line
		(start 30.501082 -327.963784)
		(end 30.785054 -328.369676)
		(stroke
			(width 0.08255)
			(type default)
		)
		(layer "In5.Cu")
	)
	(gr_line
		(start 30.51175 -330.53782)
		(end 30.530038 -330.55052)
		(stroke
			(width 0.08255)
			(type default)
		)
		(layer "In5.Cu")
	)
	(gr_line
		(start 30.52445 -69.536818)
		(end 30.545532 -69.506592)
		(stroke
			(width 0.08255)
			(type default)
		)
		(layer "In5.Cu")
	)
	(gr_line
		(start 30.530038 -330.55052)
		(end 30.542992 -330.568808)
		(stroke
			(width 0.08255)
			(type default)
		)
		(layer "In5.Cu")
	)
	(gr_line
		(start 30.542484 -335.093564)
		(end 30.62859 -334.605884)
		(stroke
			(width 0.08255)
			(type default)
		)
		(layer "In5.Cu")
	)
	(gr_line
		(start 30.542484 -335.093564)
		(end 30.693106 -335.308448)
		(stroke
			(width 0.08255)
			(type default)
		)
		(layer "In5.Cu")
	)
	(gr_line
		(start 30.542484 -332.837536)
		(end 30.62859 -333.325216)
		(stroke
			(width 0.08255)
			(type default)
		)
		(layer "In5.Cu")
	)
	(gr_line
		(start 30.542484 -332.837536)
		(end 30.693106 -332.622652)
		(stroke
			(width 0.08255)
			(type default)
		)
		(layer "In5.Cu")
	)
	(gr_line
		(start 30.545532 -69.506592)
		(end 30.551882 -69.470524)
		(stroke
			(width 0.08255)
			(type default)
		)
		(layer "In5.Cu")
	)
	(gr_line
		(start 30.551628 -238.115094)
		(end 30.688534 -237.338616)
		(stroke
			(width 0.08255)
			(type default)
		)
		(layer "In5.Cu")
	)
	(gr_line
		(start 30.57398 -256.928366)
		(end 30.58033 -256.892298)
		(stroke
			(width 0.08255)
			(type default)
		)
		(layer "In5.Cu")
	)
	(gr_line
		(start 30.58033 -256.892298)
		(end 30.601412 -256.862072)
		(stroke
			(width 0.08255)
			(type default)
		)
		(layer "In5.Cu")
	)
	(gr_line
		(start 30.5943 -230.686356)
		(end 30.612588 -230.673656)
		(stroke
			(width 0.08255)
			(type default)
		)
		(layer "In5.Cu")
	)
	(gr_line
		(start 30.595062 -229.75062)
		(end 30.640528 -230.009446)
		(stroke
			(width 0.08255)
			(type default)
		)
		(layer "In5.Cu")
	)
	(gr_line
		(start 30.595062 -229.75062)
		(end 30.879034 -229.344982)
		(stroke
			(width 0.08255)
			(type default)
		)
		(layer "In5.Cu")
	)
	(gr_line
		(start 30.610048 -120.412002)
		(end 31.256732 -120.86463)
		(stroke
			(width 0.08255)
			(type default)
		)
		(layer "In5.Cu")
	)
	(gr_line
		(start 30.612588 -230.673656)
		(end 30.625288 -230.655368)
		(stroke
			(width 0.08255)
			(type default)
		)
		(layer "In5.Cu")
	)
	(gr_line
		(start 30.62859 -334.605884)
		(end 30.843474 -334.455008)
		(stroke
			(width 0.08255)
			(type default)
		)
		(layer "In5.Cu")
	)
	(gr_line
		(start 30.62859 -333.325216)
		(end 30.843474 -333.476092)
		(stroke
			(width 0.08255)
			(type default)
		)
		(layer "In5.Cu")
	)
	(gr_line
		(start 30.650942 -18.441924)
		(end 30.90926 -18.396204)
		(stroke
			(width 0.08255)
			(type default)
		)
		(layer "In5.Cu")
	)
	(gr_line
		(start 30.669992 -245.708678)
		(end 30.691074 -245.678452)
		(stroke
			(width 0.08255)
			(type default)
		)
		(layer "In5.Cu")
	)
	(gr_line
		(start 30.674056 -377.205748)
		(end 30.705044 -377.184158)
		(stroke
			(width 0.08255)
			(type default)
		)
		(layer "In5.Cu")
	)
	(gr_line
		(start 30.686248 -340.798404)
		(end 30.689804 -340.819232)
		(stroke
			(width 0.08255)
			(type default)
		)
		(layer "In5.Cu")
	)
	(gr_line
		(start 30.686248 -340.798404)
		(end 30.689804 -340.77783)
		(stroke
			(width 0.08255)
			(type default)
		)
		(layer "In5.Cu")
	)
	(gr_line
		(start 30.689804 -340.818978)
		(end 30.689804 -340.81974)
		(stroke
			(width 0.08255)
			(type default)
		)
		(layer "In5.Cu")
	)
	(gr_line
		(start 30.691074 -245.678452)
		(end 30.697424 -245.642384)
		(stroke
			(width 0.08255)
			(type default)
		)
		(layer "In5.Cu")
	)
	(gr_line
		(start 30.696916 -436.177182)
		(end 30.742636 -435.91861)
		(stroke
			(width 0.08255)
			(type default)
		)
		(layer "In5.Cu")
	)
	(gr_line
		(start 30.705044 -377.184158)
		(end 30.742128 -377.177554)
		(stroke
			(width 0.08255)
			(type default)
		)
		(layer "In5.Cu")
	)
	(gr_line
		(start 30.724602 -330.82865)
		(end 30.745684 -330.858876)
		(stroke
			(width 0.08255)
			(type default)
		)
		(layer "In5.Cu")
	)
	(gr_line
		(start 30.726888 -126.727712)
		(end 30.98546 -126.773432)
		(stroke
			(width 0.08255)
			(type default)
		)
		(layer "In5.Cu")
	)
	(gr_line
		(start 30.732476 -152.006808)
		(end 30.738826 -151.97074)
		(stroke
			(width 0.08255)
			(type default)
		)
		(layer "In5.Cu")
	)
	(gr_line
		(start 30.738826 -151.97074)
		(end 30.759908 -151.940514)
		(stroke
			(width 0.08255)
			(type default)
		)
		(layer "In5.Cu")
	)
	(gr_line
		(start 30.739842 -350.92259)
		(end 30.760924 -350.892364)
		(stroke
			(width 0.08255)
			(type default)
		)
		(layer "In5.Cu")
	)
	(gr_line
		(start 30.742636 -435.91861)
		(end 31.148274 -435.634638)
		(stroke
			(width 0.08255)
			(type default)
		)
		(layer "In5.Cu")
	)
	(gr_line
		(start 30.745684 -330.858876)
		(end 30.752034 -330.894944)
		(stroke
			(width 0.08255)
			(type default)
		)
		(layer "In5.Cu")
	)
	(gr_line
		(start 30.758892 -233.807762)
		(end 30.844998 -233.320082)
		(stroke
			(width 0.08255)
			(type default)
		)
		(layer "In5.Cu")
	)
	(gr_line
		(start 30.758892 -233.807762)
		(end 30.909514 -234.022646)
		(stroke
			(width 0.08255)
			(type default)
		)
		(layer "In5.Cu")
	)
	(gr_line
		(start 30.760924 -350.892364)
		(end 30.767274 -350.856296)
		(stroke
			(width 0.08255)
			(type default)
		)
		(layer "In5.Cu")
	)
	(gr_line
		(start 30.785054 -328.369676)
		(end 31.043372 -328.415142)
		(stroke
			(width 0.08255)
			(type default)
		)
		(layer "In5.Cu")
	)
	(gr_line
		(start 30.803088 -125.888242)
		(end 31.256986 -126.53645)
		(stroke
			(width 0.08255)
			(type default)
		)
		(layer "In5.Cu")
	)
	(gr_line
		(start 30.81528 -336.677508)
		(end 30.951932 -335.902808)
		(stroke
			(width 0.08255)
			(type default)
		)
		(layer "In5.Cu")
	)
	(gr_line
		(start 30.82417 -121.22531)
		(end 31.082742 -121.179844)
		(stroke
			(width 0.08255)
			(type default)
		)
		(layer "In5.Cu")
	)
	(gr_line
		(start 30.844998 -233.320082)
		(end 31.059882 -233.169206)
		(stroke
			(width 0.08255)
			(type default)
		)
		(layer "In5.Cu")
	)
	(gr_line
		(start 30.863032 -327.533)
		(end 31.31312 -328.176128)
		(stroke
			(width 0.08255)
			(type default)
		)
		(layer "In5.Cu")
	)
	(gr_line
		(start 30.879034 -229.344982)
		(end 31.137606 -229.299262)
		(stroke
			(width 0.08255)
			(type default)
		)
		(layer "In5.Cu")
	)
	(gr_line
		(start 30.916372 -28.732988)
		(end 30.961838 -28.474416)
		(stroke
			(width 0.08255)
			(type default)
		)
		(layer "In5.Cu")
	)
	(gr_line
		(start 30.916372 -28.732988)
		(end 31.200598 -29.138626)
		(stroke
			(width 0.08255)
			(type default)
		)
		(layer "In5.Cu")
	)
	(gr_line
		(start 30.917642 -440.274456)
		(end 30.923992 -440.238388)
		(stroke
			(width 0.08255)
			(type default)
		)
		(layer "In5.Cu")
	)
	(gr_line
		(start 30.923992 -440.238388)
		(end 30.945074 -440.208162)
		(stroke
			(width 0.08255)
			(type default)
		)
		(layer "In5.Cu")
	)
	(gr_line
		(start 30.934406 -436.447946)
		(end 31.580328 -435.995572)
		(stroke
			(width 0.08255)
			(type default)
		)
		(layer "In5.Cu")
	)
	(gr_line
		(start 30.955234 -230.184198)
		(end 31.408624 -229.536752)
		(stroke
			(width 0.08255)
			(type default)
		)
		(layer "In5.Cu")
	)
	(gr_line
		(start 30.967934 -22.52091)
		(end 30.986222 -22.53361)
		(stroke
			(width 0.08255)
			(type default)
		)
		(layer "In5.Cu")
	)
	(gr_line
		(start 30.968696 -23.456646)
		(end 31.014162 -23.19782)
		(stroke
			(width 0.08255)
			(type default)
		)
		(layer "In5.Cu")
	)
	(gr_line
		(start 30.968696 -23.456646)
		(end 31.252668 -23.862284)
		(stroke
			(width 0.08255)
			(type default)
		)
		(layer "In5.Cu")
	)
	(gr_line
		(start 30.98038 -352.438462)
		(end 30.997398 -352.426524)
		(stroke
			(width 0.08255)
			(type default)
		)
		(layer "In5.Cu")
	)
	(gr_line
		(start 30.986222 -22.53361)
		(end 30.998922 -22.551898)
		(stroke
			(width 0.08255)
			(type default)
		)
		(layer "In5.Cu")
	)
	(gr_line
		(start 30.996382 -232.46207)
		(end 31.082488 -231.97439)
		(stroke
			(width 0.08255)
			(type default)
		)
		(layer "In5.Cu")
	)
	(gr_line
		(start 30.996382 -232.46207)
		(end 31.14675 -232.676954)
		(stroke
			(width 0.08255)
			(type default)
		)
		(layer "In5.Cu")
	)
	(gr_line
		(start 30.997398 -352.426524)
		(end 31.008828 -352.410014)
		(stroke
			(width 0.08255)
			(type default)
		)
		(layer "In5.Cu")
	)
	(gr_line
		(start 31.046928 -328.41565)
		(end 31.053786 -328.425556)
		(stroke
			(width 0.08255)
			(type default)
		)
		(layer "In5.Cu")
	)
	(gr_line
		(start 31.05277 -335.331816)
		(end 31.189676 -334.555084)
		(stroke
			(width 0.08255)
			(type default)
		)
		(layer "In5.Cu")
	)
	(gr_line
		(start 31.05277 -332.599538)
		(end 31.189676 -333.376016)
		(stroke
			(width 0.08255)
			(type default)
		)
		(layer "In5.Cu")
	)
	(gr_line
		(start 31.082488 -231.97439)
		(end 31.297372 -231.823768)
		(stroke
			(width 0.08255)
			(type default)
		)
		(layer "In5.Cu")
	)
	(gr_line
		(start 31.10992 -221.01937)
		(end 31.15564 -220.760798)
		(stroke
			(width 0.08255)
			(type default)
		)
		(layer "In5.Cu")
	)
	(gr_line
		(start 31.148274 -435.634638)
		(end 31.4071 -435.680104)
		(stroke
			(width 0.08255)
			(type default)
		)
		(layer "In5.Cu")
	)
	(gr_line
		(start 31.15564 -220.760798)
		(end 31.561532 -220.476826)
		(stroke
			(width 0.08255)
			(type default)
		)
		(layer "In5.Cu")
	)
	(gr_line
		(start 31.16199 -439.570876)
		(end 31.207456 -439.829448)
		(stroke
			(width 0.08255)
			(type default)
		)
		(layer "In5.Cu")
	)
	(gr_line
		(start 31.16199 -439.570876)
		(end 31.445962 -439.165238)
		(stroke
			(width 0.08255)
			(type default)
		)
		(layer "In5.Cu")
	)
	(gr_line
		(start 31.200598 -29.138626)
		(end 31.45917 -29.184346)
		(stroke
			(width 0.08255)
			(type default)
		)
		(layer "In5.Cu")
	)
	(gr_line
		(start 31.252668 -23.862284)
		(end 31.51124 -23.908004)
		(stroke
			(width 0.08255)
			(type default)
		)
		(layer "In5.Cu")
	)
	(gr_line
		(start 31.25343 -144.77873)
		(end 31.274512 -144.748504)
		(stroke
			(width 0.08255)
			(type default)
		)
		(layer "In5.Cu")
	)
	(gr_line
		(start 31.269178 -234.046776)
		(end 31.406592 -233.267758)
		(stroke
			(width 0.08255)
			(type default)
		)
		(layer "In5.Cu")
	)
	(gr_line
		(start 31.274512 -144.748504)
		(end 31.280862 -144.71269)
		(stroke
			(width 0.08255)
			(type default)
		)
		(layer "In5.Cu")
	)
	(gr_line
		(start 31.275528 -347.97111)
		(end 31.279338 -347.94952)
		(stroke
			(width 0.08255)
			(type default)
		)
		(layer "In5.Cu")
	)
	(gr_line
		(start 31.275782 -347.928946)
		(end 31.279338 -347.94952)
		(stroke
			(width 0.08255)
			(type default)
		)
		(layer "In5.Cu")
	)
	(gr_line
		(start 31.277052 -28.300172)
		(end 31.730442 -28.947618)
		(stroke
			(width 0.08255)
			(type default)
		)
		(layer "In5.Cu")
	)
	(gr_line
		(start 31.290006 -333.986378)
		(end 31.293562 -333.96555)
		(stroke
			(width 0.08255)
			(type default)
		)
		(layer "In5.Cu")
	)
	(gr_line
		(start 31.290006 -333.986124)
		(end 31.290006 -333.986886)
		(stroke
			(width 0.08255)
			(type default)
		)
		(layer "In5.Cu")
	)
	(gr_line
		(start 31.290006 -333.944976)
		(end 31.293562 -333.96555)
		(stroke
			(width 0.08255)
			(type default)
		)
		(layer "In5.Cu")
	)
	(gr_line
		(start 31.314644 -247.673622)
		(end 31.335726 -247.643396)
		(stroke
			(width 0.08255)
			(type default)
		)
		(layer "In5.Cu")
	)
	(gr_line
		(start 31.318962 -18.683224)
		(end 31.364682 -18.941542)
		(stroke
			(width 0.08255)
			(type default)
		)
		(layer "In5.Cu")
	)
	(gr_line
		(start 31.328868 -23.023068)
		(end 31.782258 -23.670514)
		(stroke
			(width 0.08255)
			(type default)
		)
		(layer "In5.Cu")
	)
	(gr_line
		(start 31.335726 -247.643396)
		(end 31.342076 -247.607328)
		(stroke
			(width 0.08255)
			(type default)
		)
		(layer "In5.Cu")
	)
	(gr_line
		(start 31.33725 -328.210418)
		(end 31.339028 -328.212704)
		(stroke
			(width 0.08255)
			(type default)
		)
		(layer "In5.Cu")
	)
	(gr_line
		(start 31.346648 -221.290896)
		(end 31.994602 -220.837252)
		(stroke
			(width 0.08255)
			(type default)
		)
		(layer "In5.Cu")
	)
	(gr_line
		(start 31.364682 -18.941542)
		(end 31.77032 -19.225768)
		(stroke
			(width 0.08255)
			(type default)
		)
		(layer "In5.Cu")
	)
	(gr_line
		(start 31.377636 -283.698696)
		(end 31.407862 -283.677614)
		(stroke
			(width 0.08255)
			(type default)
		)
		(layer "In5.Cu")
	)
	(gr_line
		(start 31.378652 -228.631242)
		(end 31.424372 -228.889814)
		(stroke
			(width 0.08255)
			(type default)
		)
		(layer "In5.Cu")
	)
	(gr_line
		(start 31.378652 -228.631242)
		(end 31.662878 -228.22535)
		(stroke
			(width 0.08255)
			(type default)
		)
		(layer "In5.Cu")
	)
	(gr_line
		(start 31.397956 -231.267254)
		(end 31.404306 -231.231186)
		(stroke
			(width 0.08255)
			(type default)
		)
		(layer "In5.Cu")
	)
	(gr_line
		(start 31.404306 -231.231186)
		(end 31.425388 -231.20096)
		(stroke
			(width 0.08255)
			(type default)
		)
		(layer "In5.Cu")
	)
	(gr_line
		(start 31.407862 -283.677614)
		(end 31.44393 -283.671264)
		(stroke
			(width 0.08255)
			(type default)
		)
		(layer "In5.Cu")
	)
	(gr_line
		(start 31.409132 -380.97206)
		(end 31.429706 -380.968504)
		(stroke
			(width 0.08255)
			(type default)
		)
		(layer "In5.Cu")
	)
	(gr_line
		(start 31.429706 -380.968504)
		(end 31.45028 -380.97206)
		(stroke
			(width 0.08255)
			(type default)
		)
		(layer "In5.Cu")
	)
	(gr_line
		(start 31.437326 -330.506832)
		(end 31.523178 -330.994512)
		(stroke
			(width 0.08255)
			(type default)
		)
		(layer "In5.Cu")
	)
	(gr_line
		(start 31.437326 -330.506832)
		(end 31.587694 -330.291948)
		(stroke
			(width 0.08255)
			(type default)
		)
		(layer "In5.Cu")
	)
	(gr_line
		(start 31.445962 -439.165238)
		(end 31.70428 -439.119518)
		(stroke
			(width 0.08255)
			(type default)
		)
		(layer "In5.Cu")
	)
	(gr_line
		(start 31.50616 -232.701084)
		(end 31.643066 -231.925368)
		(stroke
			(width 0.08255)
			(type default)
		)
		(layer "In5.Cu")
	)
	(gr_line
		(start 31.51251 -257.198622)
		(end 31.51886 -257.162554)
		(stroke
			(width 0.08255)
			(type default)
		)
		(layer "In5.Cu")
	)
	(gr_line
		(start 31.51886 -257.162554)
		(end 31.539942 -257.132328)
		(stroke
			(width 0.08255)
			(type default)
		)
		(layer "In5.Cu")
	)
	(gr_line
		(start 31.523178 -330.994512)
		(end 31.738062 -331.14488)
		(stroke
			(width 0.08255)
			(type default)
		)
		(layer "In5.Cu")
	)
	(gr_line
		(start 31.523432 -440.002422)
		(end 31.975044 -439.357516)
		(stroke
			(width 0.08255)
			(type default)
		)
		(layer "In5.Cu")
	)
	(gr_line
		(start 31.551118 -274.917408)
		(end 31.563818 -274.89912)
		(stroke
			(width 0.08255)
			(type default)
		)
		(layer "In5.Cu")
	)
	(gr_line
		(start 31.557976 -18.413476)
		(end 32.201358 -18.863818)
		(stroke
			(width 0.08255)
			(type default)
		)
		(layer "In5.Cu")
	)
	(gr_line
		(start 31.561532 -220.476826)
		(end 31.820104 -220.522292)
		(stroke
			(width 0.08255)
			(type default)
		)
		(layer "In5.Cu")
	)
	(gr_line
		(start 31.563818 -274.89912)
		(end 31.582106 -274.88642)
		(stroke
			(width 0.08255)
			(type default)
		)
		(layer "In5.Cu")
	)
	(gr_line
		(start 31.609538 -175.840644)
		(end 31.639764 -175.819562)
		(stroke
			(width 0.08255)
			(type default)
		)
		(layer "In5.Cu")
	)
	(gr_line
		(start 31.630366 -152.404064)
		(end 31.636716 -152.367996)
		(stroke
			(width 0.08255)
			(type default)
		)
		(layer "In5.Cu")
	)
	(gr_line
		(start 31.636716 -152.367996)
		(end 31.657798 -152.33777)
		(stroke
			(width 0.08255)
			(type default)
		)
		(layer "In5.Cu")
	)
	(gr_line
		(start 31.639764 -175.819562)
		(end 31.675578 -175.813212)
		(stroke
			(width 0.08255)
			(type default)
		)
		(layer "In5.Cu")
	)
	(gr_line
		(start 31.644336 -238.217964)
		(end 31.650686 -238.181896)
		(stroke
			(width 0.08255)
			(type default)
		)
		(layer "In5.Cu")
	)
	(gr_line
		(start 31.646368 -328.65187)
		(end 31.66745 -328.682096)
		(stroke
			(width 0.08255)
			(type default)
		)
		(layer "In5.Cu")
	)
	(gr_line
		(start 31.650686 -238.181896)
		(end 31.671768 -238.15167)
		(stroke
			(width 0.08255)
			(type default)
		)
		(layer "In5.Cu")
	)
	(gr_line
		(start 31.662878 -228.22535)
		(end 31.92145 -228.179884)
		(stroke
			(width 0.08255)
			(type default)
		)
		(layer "In5.Cu")
	)
	(gr_line
		(start 31.66745 -328.682096)
		(end 31.6738 -328.718164)
		(stroke
			(width 0.08255)
			(type default)
		)
		(layer "In5.Cu")
	)
	(gr_line
		(start 31.674562 -331.852524)
		(end 31.760414 -332.340204)
		(stroke
			(width 0.08255)
			(type default)
		)
		(layer "In5.Cu")
	)
	(gr_line
		(start 31.674562 -331.852524)
		(end 31.82493 -331.63764)
		(stroke
			(width 0.08255)
			(type default)
		)
		(layer "In5.Cu")
	)
	(gr_line
		(start 31.67888 -351.45218)
		(end 31.701232 -351.420176)
		(stroke
			(width 0.08255)
			(type default)
		)
		(layer "In5.Cu")
	)
	(gr_line
		(start 31.699962 -171.566078)
		(end 31.721044 -171.535852)
		(stroke
			(width 0.08255)
			(type default)
		)
		(layer "In5.Cu")
	)
	(gr_line
		(start 31.70047 -29.852112)
		(end 31.745936 -29.593794)
		(stroke
			(width 0.08255)
			(type default)
		)
		(layer "In5.Cu")
	)
	(gr_line
		(start 31.70047 -29.852112)
		(end 31.984696 -30.25775)
		(stroke
			(width 0.08255)
			(type default)
		)
		(layer "In5.Cu")
	)
	(gr_line
		(start 31.700978 -351.419922)
		(end 31.701232 -351.420176)
		(stroke
			(width 0.08255)
			(type default)
		)
		(layer "In5.Cu")
	)
	(gr_line
		(start 31.700978 -351.419922)
		(end 31.707328 -351.384362)
		(stroke
			(width 0.08255)
			(type default)
		)
		(layer "In5.Cu")
	)
	(gr_line
		(start 31.721044 -171.535852)
		(end 31.727394 -171.499784)
		(stroke
			(width 0.08255)
			(type default)
		)
		(layer "In5.Cu")
	)
	(gr_line
		(start 31.739078 -229.06482)
		(end 32.19323 -228.416104)
		(stroke
			(width 0.08255)
			(type default)
		)
		(layer "In5.Cu")
	)
	(gr_line
		(start 31.749238 -278.816054)
		(end 31.779464 -278.794972)
		(stroke
			(width 0.08255)
			(type default)
		)
		(layer "In5.Cu")
	)
	(gr_line
		(start 31.75254 -24.576024)
		(end 31.798006 -24.317452)
		(stroke
			(width 0.08255)
			(type default)
		)
		(layer "In5.Cu")
	)
	(gr_line
		(start 31.75254 -24.576024)
		(end 32.036512 -24.981662)
		(stroke
			(width 0.08255)
			(type default)
		)
		(layer "In5.Cu")
	)
	(gr_line
		(start 31.757874 -68.797424)
		(end 31.770574 -68.779136)
		(stroke
			(width 0.08255)
			(type default)
		)
		(layer "In5.Cu")
	)
	(gr_line
		(start 31.760414 -332.340204)
		(end 31.975298 -332.49108)
		(stroke
			(width 0.08255)
			(type default)
		)
		(layer "In5.Cu")
	)
	(gr_line
		(start 31.77032 -19.225768)
		(end 32.028892 -19.180048)
		(stroke
			(width 0.08255)
			(type default)
		)
		(layer "In5.Cu")
	)
	(gr_line
		(start 31.770574 -68.779136)
		(end 31.788862 -68.766436)
		(stroke
			(width 0.08255)
			(type default)
		)
		(layer "In5.Cu")
	)
	(gr_line
		(start 31.779464 -278.794972)
		(end 31.815278 -278.788622)
		(stroke
			(width 0.08255)
			(type default)
		)
		(layer "In5.Cu")
	)
	(gr_line
		(start 31.783528 -262.41502)
		(end 31.789878 -262.379206)
		(stroke
			(width 0.08255)
			(type default)
		)
		(layer "In5.Cu")
	)
	(gr_line
		(start 31.789878 -262.379206)
		(end 31.810706 -262.349742)
		(stroke
			(width 0.08255)
			(type default)
		)
		(layer "In5.Cu")
	)
	(gr_line
		(start 31.79064 -72.803004)
		(end 31.821628 -72.781414)
		(stroke
			(width 0.08255)
			(type default)
		)
		(layer "In5.Cu")
	)
	(gr_line
		(start 31.821628 -72.781414)
		(end 31.821882 -72.781414)
		(stroke
			(width 0.08255)
			(type default)
		)
		(layer "In5.Cu")
	)
	(gr_line
		(start 31.821882 -72.781414)
		(end 31.85795 -72.775064)
		(stroke
			(width 0.08255)
			(type default)
		)
		(layer "In5.Cu")
	)
	(gr_line
		(start 31.853886 -427.492922)
		(end 31.899606 -427.234604)
		(stroke
			(width 0.08255)
			(type default)
		)
		(layer "In5.Cu")
	)
	(gr_line
		(start 31.899606 -427.234604)
		(end 32.305244 -426.950378)
		(stroke
			(width 0.08255)
			(type default)
		)
		(layer "In5.Cu")
	)
	(gr_line
		(start 31.938722 -330.220828)
		(end 31.941008 -330.234036)
		(stroke
			(width 0.08255)
			(type default)
		)
		(layer "In5.Cu")
	)
	(gr_line
		(start 31.945834 -438.451498)
		(end 31.9913 -438.71007)
		(stroke
			(width 0.08255)
			(type default)
		)
		(layer "In5.Cu")
	)
	(gr_line
		(start 31.945834 -438.451498)
		(end 32.229806 -438.04586)
		(stroke
			(width 0.08255)
			(type default)
		)
		(layer "In5.Cu")
	)
	(gr_line
		(start 31.947358 -330.269596)
		(end 32.08401 -331.044042)
		(stroke
			(width 0.08255)
			(type default)
		)
		(layer "In5.Cu")
	)
	(gr_line
		(start 31.981902 -146.363436)
		(end 32.002984 -146.33321)
		(stroke
			(width 0.08255)
			(type default)
		)
		(layer "In5.Cu")
	)
	(gr_line
		(start 31.984696 -30.25775)
		(end 32.243014 -30.30347)
		(stroke
			(width 0.08255)
			(type default)
		)
		(layer "In5.Cu")
	)
	(gr_line
		(start 32.002984 -146.33321)
		(end 32.009334 -146.297396)
		(stroke
			(width 0.08255)
			(type default)
		)
		(layer "In5.Cu")
	)
	(gr_line
		(start 32.036512 -24.981662)
		(end 32.295084 -25.027382)
		(stroke
			(width 0.08255)
			(type default)
		)
		(layer "In5.Cu")
	)
	(gr_line
		(start 32.06115 -29.41955)
		(end 32.514032 -30.06598)
		(stroke
			(width 0.08255)
			(type default)
		)
		(layer "In5.Cu")
	)
	(gr_line
		(start 32.091122 -427.764194)
		(end 32.73679 -427.312074)
		(stroke
			(width 0.08255)
			(type default)
		)
		(layer "In5.Cu")
	)
	(gr_line
		(start 32.11322 -24.143208)
		(end 32.56534 -24.78913)
		(stroke
			(width 0.08255)
			(type default)
		)
		(layer "In5.Cu")
	)
	(gr_line
		(start 32.162496 -227.511864)
		(end 32.208216 -227.770182)
		(stroke
			(width 0.08255)
			(type default)
		)
		(layer "In5.Cu")
	)
	(gr_line
		(start 32.162496 -227.511864)
		(end 32.446468 -227.105972)
		(stroke
			(width 0.08255)
			(type default)
		)
		(layer "In5.Cu")
	)
	(gr_line
		(start 32.184594 -331.614018)
		(end 32.321246 -332.39075)
		(stroke
			(width 0.08255)
			(type default)
		)
		(layer "In5.Cu")
	)
	(gr_line
		(start 32.189674 -248.010172)
		(end 32.193484 -248.004584)
		(stroke
			(width 0.08255)
			(type default)
		)
		(layer "In5.Cu")
	)
	(gr_arc
		(start 32.215328 -247.973342)
		(mid 32.232697 -247.941838)
		(end 32.24276 -247.907302)
		(stroke
			(width 0.08255)
			(type default)
		)
		(layer "In5.Cu")
	)
	(gr_line
		(start 32.221932 -121.54027)
		(end 32.24022 -121.55297)
		(stroke
			(width 0.08255)
			(type default)
		)
		(layer "In5.Cu")
	)
	(gr_line
		(start 32.229552 -220.235526)
		(end 32.275018 -219.976954)
		(stroke
			(width 0.08255)
			(type default)
		)
		(layer "In5.Cu")
	)
	(gr_line
		(start 32.229806 -438.04586)
		(end 32.488124 -438.00014)
		(stroke
			(width 0.08255)
			(type default)
		)
		(layer "In5.Cu")
	)
	(gr_line
		(start 32.24022 -121.55297)
		(end 32.25292 -121.571258)
		(stroke
			(width 0.08255)
			(type default)
		)
		(layer "In5.Cu")
	)
	(gr_line
		(start 32.275018 -219.976954)
		(end 32.68091 -219.692982)
		(stroke
			(width 0.08255)
			(type default)
		)
		(layer "In5.Cu")
	)
	(gr_line
		(start 32.305244 -426.950378)
		(end 32.563562 -426.996098)
		(stroke
			(width 0.08255)
			(type default)
		)
		(layer "In5.Cu")
	)
	(gr_line
		(start 32.306768 -438.883552)
		(end 32.757872 -438.239154)
		(stroke
			(width 0.08255)
			(type default)
		)
		(layer "In5.Cu")
	)
	(gr_line
		(start 32.30753 -347.985842)
		(end 32.30753 -347.986604)
		(stroke
			(width 0.08255)
			(type default)
		)
		(layer "In5.Cu")
	)
	(gr_line
		(start 32.30753 -347.985842)
		(end 32.311086 -347.965268)
		(stroke
			(width 0.08255)
			(type default)
		)
		(layer "In5.Cu")
	)
	(gr_line
		(start 32.30753 -347.944694)
		(end 32.311086 -347.965268)
		(stroke
			(width 0.08255)
			(type default)
		)
		(layer "In5.Cu")
	)
	(gr_line
		(start 32.352234 -128.10109)
		(end 32.373316 -128.131316)
		(stroke
			(width 0.08255)
			(type default)
		)
		(layer "In5.Cu")
	)
	(gr_line
		(start 32.373316 -128.131316)
		(end 32.379666 -128.167384)
		(stroke
			(width 0.08255)
			(type default)
		)
		(layer "In5.Cu")
	)
	(gr_line
		(start 32.410146 -161.245042)
		(end 32.413702 -161.26587)
		(stroke
			(width 0.08255)
			(type default)
		)
		(layer "In5.Cu")
	)
	(gr_line
		(start 32.410146 -161.245042)
		(end 32.413702 -161.224468)
		(stroke
			(width 0.08255)
			(type default)
		)
		(layer "In5.Cu")
	)
	(gr_line
		(start 32.413702 -161.265616)
		(end 32.413702 -161.266378)
		(stroke
			(width 0.08255)
			(type default)
		)
		(layer "In5.Cu")
	)
	(gr_line
		(start 32.42183 -333.001366)
		(end 32.425386 -332.980538)
		(stroke
			(width 0.08255)
			(type default)
		)
		(layer "In5.Cu")
	)
	(gr_line
		(start 32.42183 -333.001112)
		(end 32.42183 -333.001874)
		(stroke
			(width 0.08255)
			(type default)
		)
		(layer "In5.Cu")
	)
	(gr_line
		(start 32.42183 -332.959964)
		(end 32.425386 -332.980538)
		(stroke
			(width 0.08255)
			(type default)
		)
		(layer "In5.Cu")
	)
	(gr_line
		(start 32.43834 -19.466814)
		(end 32.48406 -19.725386)
		(stroke
			(width 0.08255)
			(type default)
		)
		(layer "In5.Cu")
	)
	(gr_line
		(start 32.446468 -227.105972)
		(end 32.70504 -227.060506)
		(stroke
			(width 0.08255)
			(type default)
		)
		(layer "In5.Cu")
	)
	(gr_line
		(start 32.46755 -220.506036)
		(end 33.11271 -220.054424)
		(stroke
			(width 0.08255)
			(type default)
		)
		(layer "In5.Cu")
	)
	(gr_line
		(start 32.481774 -261.391908)
		(end 32.494474 -261.37362)
		(stroke
			(width 0.08255)
			(type default)
		)
		(layer "In5.Cu")
	)
	(gr_line
		(start 32.48406 -19.725386)
		(end 32.889698 -20.009358)
		(stroke
			(width 0.08255)
			(type default)
		)
		(layer "In5.Cu")
	)
	(gr_line
		(start 32.494474 -261.37362)
		(end 32.512762 -261.36092)
		(stroke
			(width 0.08255)
			(type default)
		)
		(layer "In5.Cu")
	)
	(gr_line
		(start 32.523938 -227.943156)
		(end 32.97428 -227.299774)
		(stroke
			(width 0.08255)
			(type default)
		)
		(layer "In5.Cu")
	)
	(gr_line
		(start 32.52724 -56.21782)
		(end 32.533844 -56.18099)
		(stroke
			(width 0.08255)
			(type default)
		)
		(layer "In5.Cu")
	)
	(gr_line
		(start 32.533844 -56.18099)
		(end 32.555434 -56.150002)
		(stroke
			(width 0.08255)
			(type default)
		)
		(layer "In5.Cu")
	)
	(gr_line
		(start 32.53613 -25.695402)
		(end 32.58185 -25.43683)
		(stroke
			(width 0.08255)
			(type default)
		)
		(layer "In5.Cu")
	)
	(gr_line
		(start 32.53613 -25.695402)
		(end 32.820356 -26.10104)
		(stroke
			(width 0.08255)
			(type default)
		)
		(layer "In5.Cu")
	)
	(gr_line
		(start 32.536384 -152.753314)
		(end 32.542734 -152.717246)
		(stroke
			(width 0.08255)
			(type default)
		)
		(layer "In5.Cu")
	)
	(gr_line
		(start 32.542734 -152.717246)
		(end 32.563816 -152.68702)
		(stroke
			(width 0.08255)
			(type default)
		)
		(layer "In5.Cu")
	)
	(gr_line
		(start 32.590994 -238.474758)
		(end 32.597344 -238.43869)
		(stroke
			(width 0.08255)
			(type default)
		)
		(layer "In5.Cu")
	)
	(gr_line
		(start 32.597344 -238.43869)
		(end 32.618426 -238.408464)
		(stroke
			(width 0.08255)
			(type default)
		)
		(layer "In5.Cu")
	)
	(gr_line
		(start 32.677354 -19.19732)
		(end 33.321752 -19.64817)
		(stroke
			(width 0.08255)
			(type default)
		)
		(layer "In5.Cu")
	)
	(gr_line
		(start 32.68091 -219.692982)
		(end 32.939228 -219.738702)
		(stroke
			(width 0.08255)
			(type default)
		)
		(layer "In5.Cu")
	)
	(gr_line
		(start 32.682434 -435.224174)
		(end 32.700722 -435.211474)
		(stroke
			(width 0.08255)
			(type default)
		)
		(layer "In5.Cu")
	)
	(gr_line
		(start 32.683196 -434.288438)
		(end 32.728916 -434.54701)
		(stroke
			(width 0.08255)
			(type default)
		)
		(layer "In5.Cu")
	)
	(gr_line
		(start 32.683196 -434.288438)
		(end 32.967168 -433.8828)
		(stroke
			(width 0.08255)
			(type default)
		)
		(layer "In5.Cu")
	)
	(gr_line
		(start 32.700722 -435.211474)
		(end 32.713422 -435.193186)
		(stroke
			(width 0.08255)
			(type default)
		)
		(layer "In5.Cu")
	)
	(gr_line
		(start 32.729424 -437.33212)
		(end 32.775144 -437.590692)
		(stroke
			(width 0.08255)
			(type default)
		)
		(layer "In5.Cu")
	)
	(gr_line
		(start 32.729424 -437.33212)
		(end 33.01365 -436.926482)
		(stroke
			(width 0.08255)
			(type default)
		)
		(layer "In5.Cu")
	)
	(gr_line
		(start 32.7914 -171.059348)
		(end 32.8041 -171.04106)
		(stroke
			(width 0.08255)
			(type default)
		)
		(layer "In5.Cu")
	)
	(gr_line
		(start 32.8041 -171.04106)
		(end 32.822388 -171.028106)
		(stroke
			(width 0.08255)
			(type default)
		)
		(layer "In5.Cu")
	)
	(gr_line
		(start 32.820356 -26.10104)
		(end 33.078674 -26.14676)
		(stroke
			(width 0.08255)
			(type default)
		)
		(layer "In5.Cu")
	)
	(gr_line
		(start 32.830516 -158.862522)
		(end 32.836866 -158.826708)
		(stroke
			(width 0.08255)
			(type default)
		)
		(layer "In5.Cu")
	)
	(gr_line
		(start 32.836866 -158.826708)
		(end 32.857948 -158.796482)
		(stroke
			(width 0.08255)
			(type default)
		)
		(layer "In5.Cu")
	)
	(gr_line
		(start 32.84601 -30.539944)
		(end 32.867092 -30.57017)
		(stroke
			(width 0.08255)
			(type default)
		)
		(layer "In5.Cu")
	)
	(gr_line
		(start 32.867092 -30.57017)
		(end 32.873442 -30.606238)
		(stroke
			(width 0.08255)
			(type default)
		)
		(layer "In5.Cu")
	)
	(gr_line
		(start 32.889698 -20.009358)
		(end 33.148524 -19.963892)
		(stroke
			(width 0.08255)
			(type default)
		)
		(layer "In5.Cu")
	)
	(gr_line
		(start 32.897826 -25.263856)
		(end 33.349184 -25.908508)
		(stroke
			(width 0.08255)
			(type default)
		)
		(layer "In5.Cu")
	)
	(gr_line
		(start 32.967168 -433.8828)
		(end 33.225994 -433.83708)
		(stroke
			(width 0.08255)
			(type default)
		)
		(layer "In5.Cu")
	)
	(gr_line
		(start 32.973264 -426.709078)
		(end 33.018984 -426.45076)
		(stroke
			(width 0.08255)
			(type default)
		)
		(layer "In5.Cu")
	)
	(gr_line
		(start 33.01365 -436.926482)
		(end 33.271968 -436.880762)
		(stroke
			(width 0.08255)
			(type default)
		)
		(layer "In5.Cu")
	)
	(gr_line
		(start 33.018984 -426.45076)
		(end 33.424622 -426.166534)
		(stroke
			(width 0.08255)
			(type default)
		)
		(layer "In5.Cu")
	)
	(gr_line
		(start 33.045146 -434.719222)
		(end 33.49625 -434.075078)
		(stroke
			(width 0.08255)
			(type default)
		)
		(layer "In5.Cu")
	)
	(gr_line
		(start 33.046162 -260.987286)
		(end 33.076388 -260.966204)
		(stroke
			(width 0.08255)
			(type default)
		)
		(layer "In5.Cu")
	)
	(gr_line
		(start 33.076388 -260.966204)
		(end 33.112456 -260.959854)
		(stroke
			(width 0.08255)
			(type default)
		)
		(layer "In5.Cu")
	)
	(gr_line
		(start 33.08223 -26.147268)
		(end 33.101026 -26.174192)
		(stroke
			(width 0.08255)
			(type default)
		)
		(layer "In5.Cu")
	)
	(gr_line
		(start 33.091374 -437.762904)
		(end 33.541208 -437.120538)
		(stroke
			(width 0.08255)
			(type default)
		)
		(layer "In5.Cu")
	)
	(gr_line
		(start 33.130236 -55.328566)
		(end 33.14319 -55.310278)
		(stroke
			(width 0.08255)
			(type default)
		)
		(layer "In5.Cu")
	)
	(gr_line
		(start 33.135062 -158.399988)
		(end 33.148016 -158.3817)
		(stroke
			(width 0.08255)
			(type default)
		)
		(layer "In5.Cu")
	)
	(gr_line
		(start 33.135824 -32.13481)
		(end 33.135824 -32.135318)
		(stroke
			(width 0.08255)
			(type default)
		)
		(layer "In5.Cu")
	)
	(gr_line
		(start 33.135824 -32.13481)
		(end 33.13938 -32.114236)
		(stroke
			(width 0.08255)
			(type default)
		)
		(layer "In5.Cu")
	)
	(gr_line
		(start 33.135824 -32.093408)
		(end 33.13938 -32.114236)
		(stroke
			(width 0.08255)
			(type default)
		)
		(layer "In5.Cu")
	)
	(gr_line
		(start 33.14319 -55.310278)
		(end 33.161478 -55.297578)
		(stroke
			(width 0.08255)
			(type default)
		)
		(layer "In5.Cu")
	)
	(gr_line
		(start 33.148016 -158.3817)
		(end 33.166304 -158.368746)
		(stroke
			(width 0.08255)
			(type default)
		)
		(layer "In5.Cu")
	)
	(gr_line
		(start 33.149794 -163.431982)
		(end 33.15335 -163.411154)
		(stroke
			(width 0.08255)
			(type default)
		)
		(layer "In5.Cu")
	)
	(gr_line
		(start 33.149794 -163.431728)
		(end 33.149794 -163.43249)
		(stroke
			(width 0.08255)
			(type default)
		)
		(layer "In5.Cu")
	)
	(gr_line
		(start 33.149794 -163.39058)
		(end 33.15335 -163.411154)
		(stroke
			(width 0.08255)
			(type default)
		)
		(layer "In5.Cu")
	)
	(gr_line
		(start 33.174686 -248.337324)
		(end 33.195768 -248.307098)
		(stroke
			(width 0.08255)
			(type default)
		)
		(layer "In5.Cu")
	)
	(gr_line
		(start 33.175702 -429.777144)
		(end 33.221422 -429.518826)
		(stroke
			(width 0.08255)
			(type default)
		)
		(layer "In5.Cu")
	)
	(gr_line
		(start 33.185608 -273.762978)
		(end 33.216596 -273.741388)
		(stroke
			(width 0.08255)
			(type default)
		)
		(layer "In5.Cu")
	)
	(gr_line
		(start 33.195768 -248.307098)
		(end 33.202118 -248.271284)
		(stroke
			(width 0.08255)
			(type default)
		)
		(layer "In5.Cu")
	)
	(gr_line
		(start 33.207706 -170.758612)
		(end 33.237932 -170.73753)
		(stroke
			(width 0.08255)
			(type default)
		)
		(layer "In5.Cu")
	)
	(gr_line
		(start 33.211262 -426.979588)
		(end 33.854898 -426.528738)
		(stroke
			(width 0.08255)
			(type default)
		)
		(layer "In5.Cu")
	)
	(gr_line
		(start 33.216596 -273.741388)
		(end 33.21685 -273.741388)
		(stroke
			(width 0.08255)
			(type default)
		)
		(layer "In5.Cu")
	)
	(gr_line
		(start 33.21685 -273.741388)
		(end 33.252664 -273.735038)
		(stroke
			(width 0.08255)
			(type default)
		)
		(layer "In5.Cu")
	)
	(gr_line
		(start 33.221422 -429.518826)
		(end 33.627314 -429.234854)
		(stroke
			(width 0.08255)
			(type default)
		)
		(layer "In5.Cu")
	)
	(gr_line
		(start 33.237932 -170.73753)
		(end 33.274 -170.73118)
		(stroke
			(width 0.08255)
			(type default)
		)
		(layer "In5.Cu")
	)
	(gr_line
		(start 33.24606 -67.746372)
		(end 33.276286 -67.72529)
		(stroke
			(width 0.08255)
			(type default)
		)
		(layer "In5.Cu")
	)
	(gr_line
		(start 33.276286 -67.72529)
		(end 33.3121 -67.71894)
		(stroke
			(width 0.08255)
			(type default)
		)
		(layer "In5.Cu")
	)
	(gr_line
		(start 33.285938 -133.347206)
		(end 33.289494 -133.326378)
		(stroke
			(width 0.08255)
			(type default)
		)
		(layer "In5.Cu")
	)
	(gr_line
		(start 33.285938 -133.346952)
		(end 33.285938 -133.347714)
		(stroke
			(width 0.08255)
			(type default)
		)
		(layer "In5.Cu")
	)
	(gr_line
		(start 33.285938 -133.305804)
		(end 33.289494 -133.326378)
		(stroke
			(width 0.08255)
			(type default)
		)
		(layer "In5.Cu")
	)
	(gr_line
		(start 33.372552 -25.942036)
		(end 33.37433 -25.944322)
		(stroke
			(width 0.08255)
			(type default)
		)
		(layer "In5.Cu")
	)
	(gr_line
		(start 33.413954 -430.047654)
		(end 34.058606 -429.596296)
		(stroke
			(width 0.08255)
			(type default)
		)
		(layer "In5.Cu")
	)
	(gr_line
		(start 33.424622 -426.166534)
		(end 33.68294 -426.212254)
		(stroke
			(width 0.08255)
			(type default)
		)
		(layer "In5.Cu")
	)
	(gr_line
		(start 33.45688 -238.975392)
		(end 33.463484 -238.938562)
		(stroke
			(width 0.08255)
			(type default)
		)
		(layer "In5.Cu")
	)
	(gr_line
		(start 33.463484 -238.938562)
		(end 33.48482 -238.908336)
		(stroke
			(width 0.08255)
			(type default)
		)
		(layer "In5.Cu")
	)
	(gr_line
		(start 33.46704 -433.16906)
		(end 33.51276 -433.427632)
		(stroke
			(width 0.08255)
			(type default)
		)
		(layer "In5.Cu")
	)
	(gr_line
		(start 33.46704 -433.16906)
		(end 33.751266 -432.763422)
		(stroke
			(width 0.08255)
			(type default)
		)
		(layer "In5.Cu")
	)
	(gr_line
		(start 33.627314 -429.234854)
		(end 33.885632 -429.28032)
		(stroke
			(width 0.08255)
			(type default)
		)
		(layer "In5.Cu")
	)
	(gr_line
		(start 33.679892 -54.934612)
		(end 33.710118 -54.91353)
		(stroke
			(width 0.08255)
			(type default)
		)
		(layer "In5.Cu")
	)
	(gr_line
		(start 33.70707 -33.415478)
		(end 33.792922 -32.927798)
		(stroke
			(width 0.08255)
			(type default)
		)
		(layer "In5.Cu")
	)
	(gr_line
		(start 33.70707 -33.415478)
		(end 33.857438 -33.630362)
		(stroke
			(width 0.08255)
			(type default)
		)
		(layer "In5.Cu")
	)
	(gr_line
		(start 33.710118 -54.91353)
		(end 33.746186 -54.90718)
		(stroke
			(width 0.08255)
			(type default)
		)
		(layer "In5.Cu")
	)
	(gr_line
		(start 33.731708 -157.973268)
		(end 33.761934 -157.952186)
		(stroke
			(width 0.08255)
			(type default)
		)
		(layer "In5.Cu")
	)
	(gr_line
		(start 33.751266 -432.763422)
		(end 34.009838 -432.717702)
		(stroke
			(width 0.08255)
			(type default)
		)
		(layer "In5.Cu")
	)
	(gr_line
		(start 33.761934 -157.952186)
		(end 33.798002 -157.945836)
		(stroke
			(width 0.08255)
			(type default)
		)
		(layer "In5.Cu")
	)
	(gr_line
		(start 33.792922 -32.927798)
		(end 34.00806 -32.77743)
		(stroke
			(width 0.08255)
			(type default)
		)
		(layer "In5.Cu")
	)
	(gr_line
		(start 33.794446 -19.979132)
		(end 33.812734 -19.991832)
		(stroke
			(width 0.08255)
			(type default)
		)
		(layer "In5.Cu")
	)
	(gr_line
		(start 33.812734 -19.991832)
		(end 33.825434 -20.01012)
		(stroke
			(width 0.08255)
			(type default)
		)
		(layer "In5.Cu")
	)
	(gr_line
		(start 33.82899 -433.600098)
		(end 34.280348 -432.955192)
		(stroke
			(width 0.08255)
			(type default)
		)
		(layer "In5.Cu")
	)
	(gr_line
		(start 33.941258 -26.754074)
		(end 33.96234 -26.7843)
		(stroke
			(width 0.08255)
			(type default)
		)
		(layer "In5.Cu")
	)
	(gr_line
		(start 33.944306 -32.069786)
		(end 34.030412 -31.582106)
		(stroke
			(width 0.08255)
			(type default)
		)
		(layer "In5.Cu")
	)
	(gr_line
		(start 33.944306 -32.069786)
		(end 34.094928 -32.28467)
		(stroke
			(width 0.08255)
			(type default)
		)
		(layer "In5.Cu")
	)
	(gr_line
		(start 33.96234 -26.7843)
		(end 33.96869 -26.820368)
		(stroke
			(width 0.08255)
			(type default)
		)
		(layer "In5.Cu")
	)
	(gr_line
		(start 34.030412 -31.582106)
		(end 34.245296 -31.431484)
		(stroke
			(width 0.08255)
			(type default)
		)
		(layer "In5.Cu")
	)
	(gr_line
		(start 34.092642 -425.925234)
		(end 34.138362 -425.666916)
		(stroke
			(width 0.08255)
			(type default)
		)
		(layer "In5.Cu")
	)
	(gr_line
		(start 34.138362 -425.666916)
		(end 34.544 -425.38269)
		(stroke
			(width 0.08255)
			(type default)
		)
		(layer "In5.Cu")
	)
	(gr_line
		(start 34.217102 -33.65373)
		(end 34.353754 -32.878522)
		(stroke
			(width 0.08255)
			(type default)
		)
		(layer "In5.Cu")
	)
	(gr_line
		(start 34.250884 -432.049682)
		(end 34.296604 -432.308254)
		(stroke
			(width 0.08255)
			(type default)
		)
		(layer "In5.Cu")
	)
	(gr_line
		(start 34.250884 -432.049682)
		(end 34.53511 -431.644044)
		(stroke
			(width 0.08255)
			(type default)
		)
		(layer "In5.Cu")
	)
	(gr_line
		(start 34.29508 -428.993554)
		(end 34.3408 -428.734982)
		(stroke
			(width 0.08255)
			(type default)
		)
		(layer "In5.Cu")
	)
	(gr_line
		(start 34.329878 -145.772124)
		(end 34.350706 -145.74266)
		(stroke
			(width 0.08255)
			(type default)
		)
		(layer "In5.Cu")
	)
	(gr_line
		(start 34.330894 -426.19549)
		(end 34.97453 -425.744894)
		(stroke
			(width 0.08255)
			(type default)
		)
		(layer "In5.Cu")
	)
	(gr_line
		(start 34.3408 -428.734982)
		(end 34.746692 -428.45101)
		(stroke
			(width 0.08255)
			(type default)
		)
		(layer "In5.Cu")
	)
	(gr_line
		(start 34.342832 -248.787412)
		(end 34.364676 -248.755916)
		(stroke
			(width 0.08255)
			(type default)
		)
		(layer "In5.Cu")
	)
	(gr_line
		(start 34.34715 -124.562616)
		(end 34.368232 -124.592842)
		(stroke
			(width 0.08255)
			(type default)
		)
		(layer "In5.Cu")
	)
	(gr_line
		(start 34.350706 -145.74266)
		(end 34.357056 -145.706592)
		(stroke
			(width 0.08255)
			(type default)
		)
		(layer "In5.Cu")
	)
	(gr_line
		(start 34.364676 -248.755916)
		(end 34.37128 -248.719086)
		(stroke
			(width 0.08255)
			(type default)
		)
		(layer "In5.Cu")
	)
	(gr_line
		(start 34.368232 -124.592842)
		(end 34.374582 -124.62891)
		(stroke
			(width 0.08255)
			(type default)
		)
		(layer "In5.Cu")
	)
	(gr_line
		(start 34.450274 -239.146842)
		(end 34.456624 -239.111028)
		(stroke
			(width 0.08255)
			(type default)
		)
		(layer "In5.Cu")
	)
	(gr_line
		(start 34.454084 -32.309562)
		(end 34.591498 -31.531306)
		(stroke
			(width 0.08255)
			(type default)
		)
		(layer "In5.Cu")
	)
	(gr_line
		(start 34.456624 -239.111028)
		(end 34.477706 -239.080802)
		(stroke
			(width 0.08255)
			(type default)
		)
		(layer "In5.Cu")
	)
	(gr_line
		(start 34.533078 -429.264064)
		(end 35.178492 -428.811944)
		(stroke
			(width 0.08255)
			(type default)
		)
		(layer "In5.Cu")
	)
	(gr_line
		(start 34.53511 -431.644044)
		(end 34.793682 -431.598324)
		(stroke
			(width 0.08255)
			(type default)
		)
		(layer "In5.Cu")
	)
	(gr_line
		(start 34.544 -425.38269)
		(end 34.802318 -425.42841)
		(stroke
			(width 0.08255)
			(type default)
		)
		(layer "In5.Cu")
	)
	(gr_line
		(start 34.613088 -432.480466)
		(end 35.064954 -431.835052)
		(stroke
			(width 0.08255)
			(type default)
		)
		(layer "In5.Cu")
	)
	(gr_line
		(start 34.649918 -22.939502)
		(end 34.73577 -23.427182)
		(stroke
			(width 0.08255)
			(type default)
		)
		(layer "In5.Cu")
	)
	(gr_line
		(start 34.649918 -22.939502)
		(end 34.800286 -22.724618)
		(stroke
			(width 0.08255)
			(type default)
		)
		(layer "In5.Cu")
	)
	(gr_line
		(start 34.691828 -30.9626)
		(end 34.695384 -30.941772)
		(stroke
			(width 0.08255)
			(type default)
		)
		(layer "In5.Cu")
	)
	(gr_line
		(start 34.691828 -30.962346)
		(end 34.691828 -30.963108)
		(stroke
			(width 0.08255)
			(type default)
		)
		(layer "In5.Cu")
	)
	(gr_line
		(start 34.691828 -30.921198)
		(end 34.695384 -30.941772)
		(stroke
			(width 0.08255)
			(type default)
		)
		(layer "In5.Cu")
	)
	(gr_line
		(start 34.73577 -23.427182)
		(end 34.950654 -23.57755)
		(stroke
			(width 0.08255)
			(type default)
		)
		(layer "In5.Cu")
	)
	(gr_line
		(start 34.746692 -428.45101)
		(end 35.00501 -428.496476)
		(stroke
			(width 0.08255)
			(type default)
		)
		(layer "In5.Cu")
	)
	(gr_line
		(start 34.8869 -24.285194)
		(end 34.973006 -24.772874)
		(stroke
			(width 0.08255)
			(type default)
		)
		(layer "In5.Cu")
	)
	(gr_line
		(start 34.8869 -24.285194)
		(end 35.037522 -24.070056)
		(stroke
			(width 0.08255)
			(type default)
		)
		(layer "In5.Cu")
	)
	(gr_line
		(start 34.896552 -222.873824)
		(end 34.91484 -222.861124)
		(stroke
			(width 0.08255)
			(type default)
		)
		(layer "In5.Cu")
	)
	(gr_line
		(start 34.897314 -221.938088)
		(end 34.943034 -222.19666)
		(stroke
			(width 0.08255)
			(type default)
		)
		(layer "In5.Cu")
	)
	(gr_line
		(start 34.897314 -221.938088)
		(end 35.181286 -221.53245)
		(stroke
			(width 0.08255)
			(type default)
		)
		(layer "In5.Cu")
	)
	(gr_line
		(start 34.91484 -222.861124)
		(end 34.92754 -222.842836)
		(stroke
			(width 0.08255)
			(type default)
		)
		(layer "In5.Cu")
	)
	(gr_line
		(start 34.953702 -21.62175)
		(end 34.974784 -21.651976)
		(stroke
			(width 0.08255)
			(type default)
		)
		(layer "In5.Cu")
	)
	(gr_line
		(start 34.973006 -24.772874)
		(end 35.18789 -24.923496)
		(stroke
			(width 0.08255)
			(type default)
		)
		(layer "In5.Cu")
	)
	(gr_line
		(start 34.974784 -21.651976)
		(end 34.981134 -21.688044)
		(stroke
			(width 0.08255)
			(type default)
		)
		(layer "In5.Cu")
	)
	(gr_line
		(start 35.099498 -128.782064)
		(end 35.103054 -128.761236)
		(stroke
			(width 0.08255)
			(type default)
		)
		(layer "In5.Cu")
	)
	(gr_line
		(start 35.099498 -128.78181)
		(end 35.099498 -128.782572)
		(stroke
			(width 0.08255)
			(type default)
		)
		(layer "In5.Cu")
	)
	(gr_line
		(start 35.099498 -128.740662)
		(end 35.103054 -128.761236)
		(stroke
			(width 0.08255)
			(type default)
		)
		(layer "In5.Cu")
	)
	(gr_line
		(start 35.124136 -25.630886)
		(end 35.210242 -26.118566)
		(stroke
			(width 0.08255)
			(type default)
		)
		(layer "In5.Cu")
	)
	(gr_line
		(start 35.124136 -25.630886)
		(end 35.274758 -25.415748)
		(stroke
			(width 0.08255)
			(type default)
		)
		(layer "In5.Cu")
	)
	(gr_line
		(start 35.15995 -22.70125)
		(end 35.296602 -23.477474)
		(stroke
			(width 0.08255)
			(type default)
		)
		(layer "In5.Cu")
	)
	(gr_line
		(start 35.176968 -489.64342)
		(end 35.33013 -489.796582)
		(stroke
			(width 0.08255)
			(type default)
		)
		(layer "In5.Cu")
	)
	(gr_line
		(start 35.176968 -489.136944)
		(end 35.33013 -488.983782)
		(stroke
			(width 0.08255)
			(type default)
		)
		(layer "In5.Cu")
	)
	(gr_line
		(start 35.176968 -484.843328)
		(end 35.33013 -484.99649)
		(stroke
			(width 0.08255)
			(type default)
		)
		(layer "In5.Cu")
	)
	(gr_line
		(start 35.176968 -484.336852)
		(end 35.33013 -484.18369)
		(stroke
			(width 0.08255)
			(type default)
		)
		(layer "In5.Cu")
	)
	(gr_line
		(start 35.176968 -480.04349)
		(end 35.33013 -480.196652)
		(stroke
			(width 0.08255)
			(type default)
		)
		(layer "In5.Cu")
	)
	(gr_line
		(start 35.176968 -479.537014)
		(end 35.33013 -479.383852)
		(stroke
			(width 0.08255)
			(type default)
		)
		(layer "In5.Cu")
	)
	(gr_line
		(start 35.176968 -467.243414)
		(end 35.33013 -467.396576)
		(stroke
			(width 0.08255)
			(type default)
		)
		(layer "In5.Cu")
	)
	(gr_line
		(start 35.176968 -466.736938)
		(end 35.33013 -466.583776)
		(stroke
			(width 0.08255)
			(type default)
		)
		(layer "In5.Cu")
	)
	(gr_line
		(start 35.176968 -386.643372)
		(end 35.33013 -386.796534)
		(stroke
			(width 0.08255)
			(type default)
		)
		(layer "In5.Cu")
	)
	(gr_line
		(start 35.176968 -386.136896)
		(end 35.33013 -385.983734)
		(stroke
			(width 0.08255)
			(type default)
		)
		(layer "In5.Cu")
	)
	(gr_line
		(start 35.176968 -381.84328)
		(end 35.33013 -381.996442)
		(stroke
			(width 0.08255)
			(type default)
		)
		(layer "In5.Cu")
	)
	(gr_line
		(start 35.176968 -381.336804)
		(end 35.33013 -381.183642)
		(stroke
			(width 0.08255)
			(type default)
		)
		(layer "In5.Cu")
	)
	(gr_line
		(start 35.176968 -377.043442)
		(end 35.33013 -377.196604)
		(stroke
			(width 0.08255)
			(type default)
		)
		(layer "In5.Cu")
	)
	(gr_line
		(start 35.176968 -376.536966)
		(end 35.33013 -376.383804)
		(stroke
			(width 0.08255)
			(type default)
		)
		(layer "In5.Cu")
	)
	(gr_line
		(start 35.176968 -364.243366)
		(end 35.33013 -364.396528)
		(stroke
			(width 0.08255)
			(type default)
		)
		(layer "In5.Cu")
	)
	(gr_line
		(start 35.176968 -363.73689)
		(end 35.33013 -363.583728)
		(stroke
			(width 0.08255)
			(type default)
		)
		(layer "In5.Cu")
	)
	(gr_line
		(start 35.176968 -283.643324)
		(end 35.33013 -283.796486)
		(stroke
			(width 0.08255)
			(type default)
		)
		(layer "In5.Cu")
	)
	(gr_line
		(start 35.176968 -283.136848)
		(end 35.33013 -282.983686)
		(stroke
			(width 0.08255)
			(type default)
		)
		(layer "In5.Cu")
	)
	(gr_line
		(start 35.176968 -278.843232)
		(end 35.33013 -278.996394)
		(stroke
			(width 0.08255)
			(type default)
		)
		(layer "In5.Cu")
	)
	(gr_line
		(start 35.176968 -278.336756)
		(end 35.33013 -278.183594)
		(stroke
			(width 0.08255)
			(type default)
		)
		(layer "In5.Cu")
	)
	(gr_line
		(start 35.176968 -274.043394)
		(end 35.33013 -274.196556)
		(stroke
			(width 0.08255)
			(type default)
		)
		(layer "In5.Cu")
	)
	(gr_line
		(start 35.176968 -273.536918)
		(end 35.33013 -273.383756)
		(stroke
			(width 0.08255)
			(type default)
		)
		(layer "In5.Cu")
	)
	(gr_line
		(start 35.176968 -261.243318)
		(end 35.33013 -261.39648)
		(stroke
			(width 0.08255)
			(type default)
		)
		(layer "In5.Cu")
	)
	(gr_line
		(start 35.176968 -260.736842)
		(end 35.33013 -260.58368)
		(stroke
			(width 0.08255)
			(type default)
		)
		(layer "In5.Cu")
	)
	(gr_line
		(start 35.176968 -180.643276)
		(end 35.33013 -180.796438)
		(stroke
			(width 0.08255)
			(type default)
		)
		(layer "In5.Cu")
	)
	(gr_line
		(start 35.176968 -180.1368)
		(end 35.33013 -179.983638)
		(stroke
			(width 0.08255)
			(type default)
		)
		(layer "In5.Cu")
	)
	(gr_line
		(start 35.176968 -175.843184)
		(end 35.33013 -175.996346)
		(stroke
			(width 0.08255)
			(type default)
		)
		(layer "In5.Cu")
	)
	(gr_line
		(start 35.176968 -175.336708)
		(end 35.33013 -175.183546)
		(stroke
			(width 0.08255)
			(type default)
		)
		(layer "In5.Cu")
	)
	(gr_line
		(start 35.176968 -171.043346)
		(end 35.33013 -171.196508)
		(stroke
			(width 0.08255)
			(type default)
		)
		(layer "In5.Cu")
	)
	(gr_line
		(start 35.176968 -170.53687)
		(end 35.33013 -170.383708)
		(stroke
			(width 0.08255)
			(type default)
		)
		(layer "In5.Cu")
	)
	(gr_line
		(start 35.176968 -158.24327)
		(end 35.33013 -158.396432)
		(stroke
			(width 0.08255)
			(type default)
		)
		(layer "In5.Cu")
	)
	(gr_line
		(start 35.176968 -157.736794)
		(end 35.33013 -157.583632)
		(stroke
			(width 0.08255)
			(type default)
		)
		(layer "In5.Cu")
	)
	(gr_line
		(start 35.176968 -77.643228)
		(end 35.33013 -77.79639)
		(stroke
			(width 0.08255)
			(type default)
		)
		(layer "In5.Cu")
	)
	(gr_line
		(start 35.176968 -77.136752)
		(end 35.33013 -76.98359)
		(stroke
			(width 0.08255)
			(type default)
		)
		(layer "In5.Cu")
	)
	(gr_line
		(start 35.176968 -72.843136)
		(end 35.33013 -72.996298)
		(stroke
			(width 0.08255)
			(type default)
		)
		(layer "In5.Cu")
	)
	(gr_line
		(start 35.176968 -72.33666)
		(end 35.33013 -72.183498)
		(stroke
			(width 0.08255)
			(type default)
		)
		(layer "In5.Cu")
	)
	(gr_line
		(start 35.176968 -68.043298)
		(end 35.33013 -68.19646)
		(stroke
			(width 0.08255)
			(type default)
		)
		(layer "In5.Cu")
	)
	(gr_line
		(start 35.176968 -67.536822)
		(end 35.33013 -67.38366)
		(stroke
			(width 0.08255)
			(type default)
		)
		(layer "In5.Cu")
	)
	(gr_line
		(start 35.176968 -55.243222)
		(end 35.33013 -55.396384)
		(stroke
			(width 0.08255)
			(type default)
		)
		(layer "In5.Cu")
	)
	(gr_line
		(start 35.176968 -54.736746)
		(end 35.33013 -54.583584)
		(stroke
			(width 0.08255)
			(type default)
		)
		(layer "In5.Cu")
	)
	(gr_line
		(start 35.181286 -221.53245)
		(end 35.439858 -221.48673)
		(stroke
			(width 0.08255)
			(type default)
		)
		(layer "In5.Cu")
	)
	(gr_line
		(start 35.20694 -249.182128)
		(end 35.228022 -249.151902)
		(stroke
			(width 0.08255)
			(type default)
		)
		(layer "In5.Cu")
	)
	(gr_line
		(start 35.210242 -26.118566)
		(end 35.42538 -26.269188)
		(stroke
			(width 0.08255)
			(type default)
		)
		(layer "In5.Cu")
	)
	(gr_line
		(start 35.21202 -146.203162)
		(end 35.233102 -146.172936)
		(stroke
			(width 0.08255)
			(type default)
		)
		(layer "In5.Cu")
	)
	(gr_line
		(start 35.228022 -249.151902)
		(end 35.234372 -249.116088)
		(stroke
			(width 0.08255)
			(type default)
		)
		(layer "In5.Cu")
	)
	(gr_line
		(start 35.233102 -146.172936)
		(end 35.239452 -146.136868)
		(stroke
			(width 0.08255)
			(type default)
		)
		(layer "In5.Cu")
	)
	(gr_line
		(start 35.259264 -222.369126)
		(end 35.71113 -221.723966)
		(stroke
			(width 0.08255)
			(type default)
		)
		(layer "In5.Cu")
	)
	(gr_line
		(start 35.397186 -24.046942)
		(end 35.533838 -24.823166)
		(stroke
			(width 0.08255)
			(type default)
		)
		(layer "In5.Cu")
	)
	(gr_line
		(start 35.623754 -239.570006)
		(end 35.630358 -239.532922)
		(stroke
			(width 0.08255)
			(type default)
		)
		(layer "In5.Cu")
	)
	(gr_line
		(start 35.630358 -239.532922)
		(end 35.651186 -239.503458)
		(stroke
			(width 0.08255)
			(type default)
		)
		(layer "In5.Cu")
	)
	(gr_line
		(start 35.634422 -25.39238)
		(end 35.771582 -26.169874)
		(stroke
			(width 0.08255)
			(type default)
		)
		(layer "In5.Cu")
	)
	(gr_line
		(start 35.681158 -220.81871)
		(end 35.726878 -221.077282)
		(stroke
			(width 0.08255)
			(type default)
		)
		(layer "In5.Cu")
	)
	(gr_line
		(start 35.681158 -220.81871)
		(end 35.96513 -220.413072)
		(stroke
			(width 0.08255)
			(type default)
		)
		(layer "In5.Cu")
	)
	(gr_line
		(start 35.760914 -433.002944)
		(end 35.806634 -433.261262)
		(stroke
			(width 0.08255)
			(type default)
		)
		(layer "In5.Cu")
	)
	(gr_line
		(start 35.760914 -433.002944)
		(end 36.04514 -432.597052)
		(stroke
			(width 0.08255)
			(type default)
		)
		(layer "In5.Cu")
	)
	(gr_line
		(start 35.96513 -220.413072)
		(end 36.223702 -220.367352)
		(stroke
			(width 0.08255)
			(type default)
		)
		(layer "In5.Cu")
	)
	(gr_line
		(start 36.043108 -221.249748)
		(end 36.494974 -220.604588)
		(stroke
			(width 0.08255)
			(type default)
		)
		(layer "In5.Cu")
	)
	(gr_line
		(start 36.04514 -432.597052)
		(end 36.303458 -432.551586)
		(stroke
			(width 0.08255)
			(type default)
		)
		(layer "In5.Cu")
	)
	(gr_line
		(start 36.082732 -146.638264)
		(end 36.103814 -146.608038)
		(stroke
			(width 0.08255)
			(type default)
		)
		(layer "In5.Cu")
	)
	(gr_line
		(start 36.090098 -249.643646)
		(end 36.11118 -249.61342)
		(stroke
			(width 0.08255)
			(type default)
		)
		(layer "In5.Cu")
	)
	(gr_line
		(start 36.103814 -146.608038)
		(end 36.110164 -146.572224)
		(stroke
			(width 0.08255)
			(type default)
		)
		(layer "In5.Cu")
	)
	(gr_line
		(start 36.11118 -249.61342)
		(end 36.11753 -249.577352)
		(stroke
			(width 0.08255)
			(type default)
		)
		(layer "In5.Cu")
	)
	(gr_line
		(start 36.122864 -433.433728)
		(end 36.572698 -432.791362)
		(stroke
			(width 0.08255)
			(type default)
		)
		(layer "In5.Cu")
	)
	(gr_line
		(start 36.160964 -28.419806)
		(end 36.16452 -28.398978)
		(stroke
			(width 0.08255)
			(type default)
		)
		(layer "In5.Cu")
	)
	(gr_line
		(start 36.160964 -28.419552)
		(end 36.160964 -28.420314)
		(stroke
			(width 0.08255)
			(type default)
		)
		(layer "In5.Cu")
	)
	(gr_line
		(start 36.160964 -28.378404)
		(end 36.16452 -28.398978)
		(stroke
			(width 0.08255)
			(type default)
		)
		(layer "In5.Cu")
	)
	(gr_line
		(start 36.2077 -429.255682)
		(end 36.253166 -429.514254)
		(stroke
			(width 0.08255)
			(type default)
		)
		(layer "In5.Cu")
	)
	(gr_line
		(start 36.2077 -429.255682)
		(end 36.491672 -428.84979)
		(stroke
			(width 0.08255)
			(type default)
		)
		(layer "In5.Cu")
	)
	(gr_line
		(start 36.397184 -424.748706)
		(end 36.415472 -424.736006)
		(stroke
			(width 0.08255)
			(type default)
		)
		(layer "In5.Cu")
	)
	(gr_line
		(start 36.397946 -423.81297)
		(end 36.443666 -424.071542)
		(stroke
			(width 0.08255)
			(type default)
		)
		(layer "In5.Cu")
	)
	(gr_line
		(start 36.397946 -423.81297)
		(end 36.681918 -423.407332)
		(stroke
			(width 0.08255)
			(type default)
		)
		(layer "In5.Cu")
	)
	(gr_line
		(start 36.415472 -424.736006)
		(end 36.428172 -424.717718)
		(stroke
			(width 0.08255)
			(type default)
		)
		(layer "In5.Cu")
	)
	(gr_line
		(start 36.465002 -219.699332)
		(end 36.510722 -219.95765)
		(stroke
			(width 0.08255)
			(type default)
		)
		(layer "In5.Cu")
	)
	(gr_line
		(start 36.465002 -219.699332)
		(end 36.748974 -219.293694)
		(stroke
			(width 0.08255)
			(type default)
		)
		(layer "In5.Cu")
	)
	(gr_line
		(start 36.48456 -239.979962)
		(end 36.49091 -239.944148)
		(stroke
			(width 0.08255)
			(type default)
		)
		(layer "In5.Cu")
	)
	(gr_line
		(start 36.49091 -239.944148)
		(end 36.511992 -239.913922)
		(stroke
			(width 0.08255)
			(type default)
		)
		(layer "In5.Cu")
	)
	(gr_line
		(start 36.491672 -428.84979)
		(end 36.750244 -428.804324)
		(stroke
			(width 0.08255)
			(type default)
		)
		(layer "In5.Cu")
	)
	(gr_line
		(start 36.568634 -429.687482)
		(end 37.01923 -429.0441)
		(stroke
			(width 0.08255)
			(type default)
		)
		(layer "In5.Cu")
	)
	(gr_line
		(start 36.681918 -423.407332)
		(end 36.940744 -423.361612)
		(stroke
			(width 0.08255)
			(type default)
		)
		(layer "In5.Cu")
	)
	(gr_line
		(start 36.748974 -219.293694)
		(end 37.007546 -219.247974)
		(stroke
			(width 0.08255)
			(type default)
		)
		(layer "In5.Cu")
	)
	(gr_line
		(start 36.759896 -424.243754)
		(end 37.211 -423.59961)
		(stroke
			(width 0.08255)
			(type default)
		)
		(layer "In5.Cu")
	)
	(gr_line
		(start 36.826952 -220.13037)
		(end 37.278818 -219.48521)
		(stroke
			(width 0.08255)
			(type default)
		)
		(layer "In5.Cu")
	)
	(gr_line
		(start 36.913312 -426.56252)
		(end 36.959032 -426.821092)
		(stroke
			(width 0.08255)
			(type default)
		)
		(layer "In5.Cu")
	)
	(gr_line
		(start 36.913312 -426.56252)
		(end 37.197284 -426.156882)
		(stroke
			(width 0.08255)
			(type default)
		)
		(layer "In5.Cu")
	)
	(gr_line
		(start 37.007038 -249.944382)
		(end 37.02812 -249.914156)
		(stroke
			(width 0.08255)
			(type default)
		)
		(layer "In5.Cu")
	)
	(gr_line
		(start 37.02812 -249.914156)
		(end 37.03447 -249.878342)
		(stroke
			(width 0.08255)
			(type default)
		)
		(layer "In5.Cu")
	)
	(gr_line
		(start 37.034978 -146.922744)
		(end 37.05606 -146.892518)
		(stroke
			(width 0.08255)
			(type default)
		)
		(layer "In5.Cu")
	)
	(gr_line
		(start 37.05606 -146.892518)
		(end 37.06241 -146.85645)
		(stroke
			(width 0.08255)
			(type default)
		)
		(layer "In5.Cu")
	)
	(gr_line
		(start 37.18179 -422.693592)
		(end 37.22751 -422.952164)
		(stroke
			(width 0.08255)
			(type default)
		)
		(layer "In5.Cu")
	)
	(gr_line
		(start 37.18179 -422.693592)
		(end 37.466016 -422.287954)
		(stroke
			(width 0.08255)
			(type default)
		)
		(layer "In5.Cu")
	)
	(gr_line
		(start 37.197284 -426.156882)
		(end 37.455856 -426.111162)
		(stroke
			(width 0.08255)
			(type default)
		)
		(layer "In5.Cu")
	)
	(gr_line
		(start 37.24783 -203.547218)
		(end 37.283644 -203.553568)
		(stroke
			(width 0.08255)
			(type default)
		)
		(layer "In5.Cu")
	)
	(gr_line
		(start 37.275008 -426.994066)
		(end 37.72662 -426.348652)
		(stroke
			(width 0.08255)
			(type default)
		)
		(layer "In5.Cu")
	)
	(gr_line
		(start 37.283644 -203.553568)
		(end 37.31387 -203.57465)
		(stroke
			(width 0.08255)
			(type default)
		)
		(layer "In5.Cu")
	)
	(gr_line
		(start 37.398706 -240.257584)
		(end 37.405056 -240.221516)
		(stroke
			(width 0.08255)
			(type default)
		)
		(layer "In5.Cu")
	)
	(gr_line
		(start 37.405056 -240.221516)
		(end 37.426138 -240.19129)
		(stroke
			(width 0.08255)
			(type default)
		)
		(layer "In5.Cu")
	)
	(gr_line
		(start 37.466016 -422.287954)
		(end 37.724588 -422.242234)
		(stroke
			(width 0.08255)
			(type default)
		)
		(layer "In5.Cu")
	)
	(gr_line
		(start 37.54374 -423.12463)
		(end 37.995098 -422.479724)
		(stroke
			(width 0.08255)
			(type default)
		)
		(layer "In5.Cu")
	)
	(gr_line
		(start 37.697156 -425.443142)
		(end 37.742876 -425.70146)
		(stroke
			(width 0.08255)
			(type default)
		)
		(layer "In5.Cu")
	)
	(gr_line
		(start 37.697156 -425.443142)
		(end 37.981128 -425.037504)
		(stroke
			(width 0.08255)
			(type default)
		)
		(layer "In5.Cu")
	)
	(gr_line
		(start 37.965634 -421.574214)
		(end 38.011354 -421.832786)
		(stroke
			(width 0.08255)
			(type default)
		)
		(layer "In5.Cu")
	)
	(gr_line
		(start 37.965634 -421.574214)
		(end 38.24986 -421.168576)
		(stroke
			(width 0.08255)
			(type default)
		)
		(layer "In5.Cu")
	)
	(gr_line
		(start 37.981128 -425.037504)
		(end 38.239446 -424.991784)
		(stroke
			(width 0.08255)
			(type default)
		)
		(layer "In5.Cu")
	)
	(gr_line
		(start 38.058852 -425.874688)
		(end 38.510464 -425.229274)
		(stroke
			(width 0.08255)
			(type default)
		)
		(layer "In5.Cu")
	)
	(gr_line
		(start 38.07079 -241.95786)
		(end 38.07714 -241.922046)
		(stroke
			(width 0.08255)
			(type default)
		)
		(layer "In5.Cu")
	)
	(gr_line
		(start 38.07714 -241.922046)
		(end 38.098222 -241.89182)
		(stroke
			(width 0.08255)
			(type default)
		)
		(layer "In5.Cu")
	)
	(gr_line
		(start 38.186868 -216.501472)
		(end 38.205156 -216.488772)
		(stroke
			(width 0.08255)
			(type default)
		)
		(layer "In5.Cu")
	)
	(gr_line
		(start 38.18763 -215.565736)
		(end 38.23335 -215.824308)
		(stroke
			(width 0.08255)
			(type default)
		)
		(layer "In5.Cu")
	)
	(gr_line
		(start 38.18763 -215.565736)
		(end 38.471602 -215.160098)
		(stroke
			(width 0.08255)
			(type default)
		)
		(layer "In5.Cu")
	)
	(gr_line
		(start 38.205156 -216.488772)
		(end 38.217856 -216.470484)
		(stroke
			(width 0.08255)
			(type default)
		)
		(layer "In5.Cu")
	)
	(gr_line
		(start 38.24986 -421.168576)
		(end 38.508178 -421.122856)
		(stroke
			(width 0.08255)
			(type default)
		)
		(layer "In5.Cu")
	)
	(gr_line
		(start 38.327076 -422.006268)
		(end 38.780212 -421.359076)
		(stroke
			(width 0.08255)
			(type default)
		)
		(layer "In5.Cu")
	)
	(gr_line
		(start 38.471602 -215.160098)
		(end 38.730174 -215.114378)
		(stroke
			(width 0.08255)
			(type default)
		)
		(layer "In5.Cu")
	)
	(gr_line
		(start 38.476428 -412.015178)
		(end 38.512496 -412.021528)
		(stroke
			(width 0.08255)
			(type default)
		)
		(layer "In5.Cu")
	)
	(gr_line
		(start 38.512496 -412.021528)
		(end 38.542722 -412.04261)
		(stroke
			(width 0.08255)
			(type default)
		)
		(layer "In5.Cu")
	)
	(gr_line
		(start 38.54958 -215.99652)
		(end 39.000684 -215.352376)
		(stroke
			(width 0.08255)
			(type default)
		)
		(layer "In5.Cu")
	)
	(gr_line
		(start 38.641528 -202.860402)
		(end 38.677342 -202.866752)
		(stroke
			(width 0.08255)
			(type default)
		)
		(layer "In5.Cu")
	)
	(gr_line
		(start 38.677342 -202.866752)
		(end 38.707568 -202.887834)
		(stroke
			(width 0.08255)
			(type default)
		)
		(layer "In5.Cu")
	)
	(gr_line
		(start 38.843204 -306.940204)
		(end 38.863778 -306.94376)
		(stroke
			(width 0.08255)
			(type default)
		)
		(layer "In5.Cu")
	)
	(gr_line
		(start 38.863778 -306.94376)
		(end 38.884352 -306.940204)
		(stroke
			(width 0.08255)
			(type default)
		)
		(layer "In5.Cu")
	)
	(gr_line
		(start 38.971474 -214.446358)
		(end 39.017194 -214.70493)
		(stroke
			(width 0.08255)
			(type default)
		)
		(layer "In5.Cu")
	)
	(gr_line
		(start 38.971474 -214.446358)
		(end 39.255446 -214.04072)
		(stroke
			(width 0.08255)
			(type default)
		)
		(layer "In5.Cu")
	)
	(gr_line
		(start 39.077392 -304.102516)
		(end 39.097966 -304.106072)
		(stroke
			(width 0.08255)
			(type default)
		)
		(layer "In5.Cu")
	)
	(gr_line
		(start 39.08425 -305.973734)
		(end 39.104824 -305.97729)
		(stroke
			(width 0.08255)
			(type default)
		)
		(layer "In5.Cu")
	)
	(gr_line
		(start 39.089076 -305.048412)
		(end 39.10965 -305.051968)
		(stroke
			(width 0.08255)
			(type default)
		)
		(layer "In5.Cu")
	)
	(gr_line
		(start 39.097966 -304.106072)
		(end 39.11854 -304.102516)
		(stroke
			(width 0.08255)
			(type default)
		)
		(layer "In5.Cu")
	)
	(gr_line
		(start 39.104824 -305.97729)
		(end 39.125398 -305.973734)
		(stroke
			(width 0.08255)
			(type default)
		)
		(layer "In5.Cu")
	)
	(gr_line
		(start 39.10965 -305.051968)
		(end 39.130224 -305.048412)
		(stroke
			(width 0.08255)
			(type default)
		)
		(layer "In5.Cu")
	)
	(gr_line
		(start 39.118794 -201.96048)
		(end 39.154862 -201.96683)
		(stroke
			(width 0.08255)
			(type default)
		)
		(layer "In5.Cu")
	)
	(gr_line
		(start 39.154862 -201.96683)
		(end 39.185088 -201.987912)
		(stroke
			(width 0.08255)
			(type default)
		)
		(layer "In5.Cu")
	)
	(gr_line
		(start 39.240968 -203.698602)
		(end 39.286688 -203.957428)
		(stroke
			(width 0.08255)
			(type default)
		)
		(layer "In5.Cu")
	)
	(gr_line
		(start 39.255446 -214.04072)
		(end 39.514018 -213.995)
		(stroke
			(width 0.08255)
			(type default)
		)
		(layer "In5.Cu")
	)
	(gr_line
		(start 39.286688 -203.957428)
		(end 39.692326 -204.2414)
		(stroke
			(width 0.08255)
			(type default)
		)
		(layer "In5.Cu")
	)
	(gr_line
		(start 39.333678 -214.876634)
		(end 39.784274 -214.233252)
		(stroke
			(width 0.08255)
			(type default)
		)
		(layer "In5.Cu")
	)
	(gr_line
		(start 39.36365 -423.063162)
		(end 39.409116 -423.32148)
		(stroke
			(width 0.08255)
			(type default)
		)
		(layer "In5.Cu")
	)
	(gr_line
		(start 39.36365 -423.063162)
		(end 39.647622 -422.65727)
		(stroke
			(width 0.08255)
			(type default)
		)
		(layer "In5.Cu")
	)
	(gr_line
		(start 39.384986 -205.462632)
		(end 39.430706 -205.721458)
		(stroke
			(width 0.08255)
			(type default)
		)
		(layer "In5.Cu")
	)
	(gr_line
		(start 39.398194 -115.049554)
		(end 39.40175 -115.030504)
		(stroke
			(width 0.08255)
			(type default)
		)
		(layer "In5.Cu")
	)
	(gr_line
		(start 39.407338 -114.997484)
		(end 39.413688 -114.962178)
		(stroke
			(width 0.08255)
			(type default)
		)
		(layer "In5.Cu")
	)
	(gr_line
		(start 39.413688 -114.962178)
		(end 39.43477 -114.931952)
		(stroke
			(width 0.08255)
			(type default)
		)
		(layer "In5.Cu")
	)
	(gr_line
		(start 39.430706 -205.721458)
		(end 39.836344 -206.005684)
		(stroke
			(width 0.08255)
			(type default)
		)
		(layer "In5.Cu")
	)
	(gr_line
		(start 39.477188 -203.426822)
		(end 40.126158 -203.881228)
		(stroke
			(width 0.08255)
			(type default)
		)
		(layer "In5.Cu")
	)
	(gr_line
		(start 39.484808 -441.178696)
		(end 39.515034 -441.157614)
		(stroke
			(width 0.08255)
			(type default)
		)
		(layer "In5.Cu")
	)
	(gr_line
		(start 39.515034 -441.157614)
		(end 39.550848 -441.151264)
		(stroke
			(width 0.08255)
			(type default)
		)
		(layer "In5.Cu")
	)
	(gr_line
		(start 39.51605 -442.26353)
		(end 39.547038 -442.24194)
		(stroke
			(width 0.08255)
			(type default)
		)
		(layer "In5.Cu")
	)
	(gr_line
		(start 39.547038 -442.24194)
		(end 39.584376 -442.235336)
		(stroke
			(width 0.08255)
			(type default)
		)
		(layer "In5.Cu")
	)
	(gr_line
		(start 39.562278 -201.111358)
		(end 39.598346 -201.117708)
		(stroke
			(width 0.08255)
			(type default)
		)
		(layer "In5.Cu")
	)
	(gr_line
		(start 39.598346 -201.117708)
		(end 39.628572 -201.13879)
		(stroke
			(width 0.08255)
			(type default)
		)
		(layer "In5.Cu")
	)
	(gr_line
		(start 39.622476 -205.192122)
		(end 40.26789 -205.643988)
		(stroke
			(width 0.08255)
			(type default)
		)
		(layer "In5.Cu")
	)
	(gr_line
		(start 39.637716 -101.446584)
		(end 39.673784 -101.452934)
		(stroke
			(width 0.08255)
			(type default)
		)
		(layer "In5.Cu")
	)
	(gr_line
		(start 39.647622 -422.65727)
		(end 39.90594 -422.61155)
		(stroke
			(width 0.08255)
			(type default)
		)
		(layer "In5.Cu")
	)
	(gr_line
		(start 39.673784 -101.452934)
		(end 39.70401 -101.474016)
		(stroke
			(width 0.08255)
			(type default)
		)
		(layer "In5.Cu")
	)
	(gr_line
		(start 39.692326 -204.2414)
		(end 39.951152 -204.195934)
		(stroke
			(width 0.08255)
			(type default)
		)
		(layer "In5.Cu")
	)
	(gr_line
		(start 39.701978 -419.094666)
		(end 39.747698 -419.352984)
		(stroke
			(width 0.08255)
			(type default)
		)
		(layer "In5.Cu")
	)
	(gr_line
		(start 39.701978 -419.094666)
		(end 39.986204 -418.689028)
		(stroke
			(width 0.08255)
			(type default)
		)
		(layer "In5.Cu")
	)
	(gr_line
		(start 39.72433 -423.495724)
		(end 40.176958 -422.849294)
		(stroke
			(width 0.08255)
			(type default)
		)
		(layer "In5.Cu")
	)
	(gr_line
		(start 39.749984 -115.102132)
		(end 39.750238 -115.101878)
		(stroke
			(width 0.08255)
			(type default)
		)
		(layer "In5.Cu")
	)
	(gr_line
		(start 39.755318 -213.32698)
		(end 39.801038 -213.585298)
		(stroke
			(width 0.08255)
			(type default)
		)
		(layer "In5.Cu")
	)
	(gr_line
		(start 39.755318 -213.32698)
		(end 40.03929 -212.921342)
		(stroke
			(width 0.08255)
			(type default)
		)
		(layer "In5.Cu")
	)
	(gr_line
		(start 39.836344 -206.005684)
		(end 40.094916 -205.959964)
		(stroke
			(width 0.08255)
			(type default)
		)
		(layer "In5.Cu")
	)
	(gr_line
		(start 39.848282 -98.08718)
		(end 39.88435 -98.09353)
		(stroke
			(width 0.08255)
			(type default)
		)
		(layer "In5.Cu")
	)
	(gr_line
		(start 39.88435 -98.09353)
		(end 39.914576 -98.114612)
		(stroke
			(width 0.08255)
			(type default)
		)
		(layer "In5.Cu")
	)
	(gr_line
		(start 39.904416 -443.20841)
		(end 39.934642 -443.187328)
		(stroke
			(width 0.08255)
			(type default)
		)
		(layer "In5.Cu")
	)
	(gr_line
		(start 39.934642 -443.187328)
		(end 39.970456 -443.180978)
		(stroke
			(width 0.08255)
			(type default)
		)
		(layer "In5.Cu")
	)
	(gr_line
		(start 39.938198 -100.548186)
		(end 39.974012 -100.554536)
		(stroke
			(width 0.08255)
			(type default)
		)
		(layer "In5.Cu")
	)
	(gr_line
		(start 39.974012 -100.554536)
		(end 40.004238 -100.575618)
		(stroke
			(width 0.08255)
			(type default)
		)
		(layer "In5.Cu")
	)
	(gr_line
		(start 39.986204 -418.689028)
		(end 40.244522 -418.643308)
		(stroke
			(width 0.08255)
			(type default)
		)
		(layer "In5.Cu")
	)
	(gr_line
		(start 40.03929 -212.921342)
		(end 40.297862 -212.875622)
		(stroke
			(width 0.08255)
			(type default)
		)
		(layer "In5.Cu")
	)
	(gr_line
		(start 40.063674 -419.526212)
		(end 40.515794 -418.880544)
		(stroke
			(width 0.08255)
			(type default)
		)
		(layer "In5.Cu")
	)
	(gr_line
		(start 40.11803 -213.756748)
		(end 40.568626 -213.113366)
		(stroke
			(width 0.08255)
			(type default)
		)
		(layer "In5.Cu")
	)
	(gr_line
		(start 40.14724 -421.94353)
		(end 40.19296 -422.201848)
		(stroke
			(width 0.08255)
			(type default)
		)
		(layer "In5.Cu")
	)
	(gr_line
		(start 40.14724 -421.94353)
		(end 40.431466 -421.537892)
		(stroke
			(width 0.08255)
			(type default)
		)
		(layer "In5.Cu")
	)
	(gr_line
		(start 40.228266 -444.140082)
		(end 40.258492 -444.119)
		(stroke
			(width 0.08255)
			(type default)
		)
		(layer "In5.Cu")
	)
	(gr_line
		(start 40.258492 -444.119)
		(end 40.294306 -444.11265)
		(stroke
			(width 0.08255)
			(type default)
		)
		(layer "In5.Cu")
	)
	(gr_line
		(start 40.30472 -115.349782)
		(end 40.31107 -115.313714)
		(stroke
			(width 0.08255)
			(type default)
		)
		(layer "In5.Cu")
	)
	(gr_line
		(start 40.31107 -115.313714)
		(end 40.332152 -115.283488)
		(stroke
			(width 0.08255)
			(type default)
		)
		(layer "In5.Cu")
	)
	(gr_line
		(start 40.330628 -99.619816)
		(end 40.366696 -99.626166)
		(stroke
			(width 0.08255)
			(type default)
		)
		(layer "In5.Cu")
	)
	(gr_line
		(start 40.360346 -204.482446)
		(end 40.406066 -204.741272)
		(stroke
			(width 0.08255)
			(type default)
		)
		(layer "In5.Cu")
	)
	(gr_line
		(start 40.366696 -99.626166)
		(end 40.396922 -99.647248)
		(stroke
			(width 0.08255)
			(type default)
		)
		(layer "In5.Cu")
	)
	(gr_line
		(start 40.406066 -204.741272)
		(end 40.811704 -205.025244)
		(stroke
			(width 0.08255)
			(type default)
		)
		(layer "In5.Cu")
	)
	(gr_line
		(start 40.431466 -421.537892)
		(end 40.689784 -421.492172)
		(stroke
			(width 0.08255)
			(type default)
		)
		(layer "In5.Cu")
	)
	(gr_line
		(start 40.4749 -411.44444)
		(end 40.51173 -411.451044)
		(stroke
			(width 0.08255)
			(type default)
		)
		(layer "In5.Cu")
	)
	(gr_line
		(start 40.509444 -422.374314)
		(end 40.961056 -421.729408)
		(stroke
			(width 0.08255)
			(type default)
		)
		(layer "In5.Cu")
	)
	(gr_line
		(start 40.51173 -411.451044)
		(end 40.541956 -411.47238)
		(stroke
			(width 0.08255)
			(type default)
		)
		(layer "In5.Cu")
	)
	(gr_line
		(start 40.541956 -413.442658)
		(end 40.55872 -413.454342)
		(stroke
			(width 0.08255)
			(type default)
		)
		(layer "In5.Cu")
	)
	(gr_line
		(start 40.55872 -413.454342)
		(end 40.57015 -413.470852)
		(stroke
			(width 0.08255)
			(type default)
		)
		(layer "In5.Cu")
	)
	(gr_line
		(start 40.595804 -204.209904)
		(end 41.24579 -204.665072)
		(stroke
			(width 0.08255)
			(type default)
		)
		(layer "In5.Cu")
	)
	(gr_line
		(start 40.741092 -205.975458)
		(end 40.75938 -205.988158)
		(stroke
			(width 0.08255)
			(type default)
		)
		(layer "In5.Cu")
	)
	(gr_line
		(start 40.75938 -205.988158)
		(end 40.77208 -206.006446)
		(stroke
			(width 0.08255)
			(type default)
		)
		(layer "In5.Cu")
	)
	(gr_line
		(start 40.811704 -205.025244)
		(end 41.070276 -204.979778)
		(stroke
			(width 0.08255)
			(type default)
		)
		(layer "In5.Cu")
	)
	(gr_line
		(start 40.847518 -418.406834)
		(end 40.8686 -418.376608)
		(stroke
			(width 0.08255)
			(type default)
		)
		(layer "In5.Cu")
	)
	(gr_line
		(start 40.8686 -418.376608)
		(end 40.87495 -418.34054)
		(stroke
			(width 0.08255)
			(type default)
		)
		(layer "In5.Cu")
	)
	(gr_line
		(start 40.931084 -420.824152)
		(end 40.97655 -421.082724)
		(stroke
			(width 0.08255)
			(type default)
		)
		(layer "In5.Cu")
	)
	(gr_line
		(start 40.931084 -420.824152)
		(end 41.215056 -420.418514)
		(stroke
			(width 0.08255)
			(type default)
		)
		(layer "In5.Cu")
	)
	(gr_line
		(start 41.188894 -115.756436)
		(end 41.195244 -115.720622)
		(stroke
			(width 0.08255)
			(type default)
		)
		(layer "In5.Cu")
	)
	(gr_line
		(start 41.195244 -115.720622)
		(end 41.216326 -115.690396)
		(stroke
			(width 0.08255)
			(type default)
		)
		(layer "In5.Cu")
	)
	(gr_line
		(start 41.204896 -410.647388)
		(end 41.241726 -410.653992)
		(stroke
			(width 0.08255)
			(type default)
		)
		(layer "In5.Cu")
	)
	(gr_line
		(start 41.215056 -420.418514)
		(end 41.473374 -420.372794)
		(stroke
			(width 0.08255)
			(type default)
		)
		(layer "In5.Cu")
	)
	(gr_line
		(start 41.24071 -414.428178)
		(end 41.261792 -414.458404)
		(stroke
			(width 0.08255)
			(type default)
		)
		(layer "In5.Cu")
	)
	(gr_line
		(start 41.241726 -410.653992)
		(end 41.271952 -410.675328)
		(stroke
			(width 0.08255)
			(type default)
		)
		(layer "In5.Cu")
	)
	(gr_line
		(start 41.261792 -414.458404)
		(end 41.268142 -414.494218)
		(stroke
			(width 0.08255)
			(type default)
		)
		(layer "In5.Cu")
	)
	(gr_line
		(start 41.292018 -421.256206)
		(end 41.743122 -420.611808)
		(stroke
			(width 0.08255)
			(type default)
		)
		(layer "In5.Cu")
	)
	(gr_line
		(start 41.40708 -415.322766)
		(end 41.410636 -415.302192)
		(stroke
			(width 0.08255)
			(type default)
		)
		(layer "In5.Cu")
	)
	(gr_line
		(start 41.40708 -415.281364)
		(end 41.410636 -415.302192)
		(stroke
			(width 0.08255)
			(type default)
		)
		(layer "In5.Cu")
	)
	(gr_line
		(start 41.40708 -415.280856)
		(end 41.40708 -415.281618)
		(stroke
			(width 0.08255)
			(type default)
		)
		(layer "In5.Cu")
	)
	(gr_line
		(start 41.606216 -409.785312)
		(end 41.643046 -409.791916)
		(stroke
			(width 0.08255)
			(type default)
		)
		(layer "In5.Cu")
	)
	(gr_line
		(start 41.622726 -211.608162)
		(end 41.643808 -211.577936)
		(stroke
			(width 0.08255)
			(type default)
		)
		(layer "In5.Cu")
	)
	(gr_line
		(start 41.638728 -440.78271)
		(end 41.659302 -440.779154)
		(stroke
			(width 0.08255)
			(type default)
		)
		(layer "In5.Cu")
	)
	(gr_line
		(start 41.643046 -409.791916)
		(end 41.673272 -409.813252)
		(stroke
			(width 0.08255)
			(type default)
		)
		(layer "In5.Cu")
	)
	(gr_line
		(start 41.643808 -211.577936)
		(end 41.650158 -211.541868)
		(stroke
			(width 0.08255)
			(type default)
		)
		(layer "In5.Cu")
	)
	(gr_line
		(start 41.659302 -440.779154)
		(end 41.679876 -440.78271)
		(stroke
			(width 0.08255)
			(type default)
		)
		(layer "In5.Cu")
	)
	(gr_line
		(start 41.745662 -205.015084)
		(end 41.76395 -205.028038)
		(stroke
			(width 0.08255)
			(type default)
		)
		(layer "In5.Cu")
	)
	(gr_line
		(start 41.76395 -205.028038)
		(end 41.77665 -205.046326)
		(stroke
			(width 0.08255)
			(type default)
		)
		(layer "In5.Cu")
	)
	(gr_line
		(start 41.768522 -207.429608)
		(end 41.789604 -207.459834)
		(stroke
			(width 0.08255)
			(type default)
		)
		(layer "In5.Cu")
	)
	(gr_line
		(start 41.789604 -207.459834)
		(end 41.795954 -207.495902)
		(stroke
			(width 0.08255)
			(type default)
		)
		(layer "In5.Cu")
	)
	(gr_line
		(start 41.84904 -441.835794)
		(end 41.869614 -441.832238)
		(stroke
			(width 0.08255)
			(type default)
		)
		(layer "In5.Cu")
	)
	(gr_line
		(start 41.869614 -441.831984)
		(end 41.869614 -441.832238)
		(stroke
			(width 0.08255)
			(type default)
		)
		(layer "In5.Cu")
	)
	(gr_line
		(start 41.869614 -441.831984)
		(end 41.89222 -441.836048)
		(stroke
			(width 0.08255)
			(type default)
		)
		(layer "In5.Cu")
	)
	(gr_line
		(start 41.872154 -442.845444)
		(end 41.892728 -442.841888)
		(stroke
			(width 0.08255)
			(type default)
		)
		(layer "In5.Cu")
	)
	(gr_line
		(start 41.88968 -443.831218)
		(end 41.91 -443.827662)
		(stroke
			(width 0.08255)
			(type default)
		)
		(layer "In5.Cu")
	)
	(gr_line
		(start 41.892728 -442.841888)
		(end 41.913302 -442.845444)
		(stroke
			(width 0.08255)
			(type default)
		)
		(layer "In5.Cu")
	)
	(gr_line
		(start 41.91 -443.827662)
		(end 41.910762 -443.827662)
		(stroke
			(width 0.08255)
			(type default)
		)
		(layer "In5.Cu")
	)
	(gr_line
		(start 41.910762 -443.827662)
		(end 41.931336 -443.831218)
		(stroke
			(width 0.08255)
			(type default)
		)
		(layer "In5.Cu")
	)
	(gr_line
		(start 41.919144 -112.004348)
		(end 41.940226 -111.974122)
		(stroke
			(width 0.08255)
			(type default)
		)
		(layer "In5.Cu")
	)
	(gr_line
		(start 41.940226 -111.974122)
		(end 41.946576 -111.938054)
		(stroke
			(width 0.08255)
			(type default)
		)
		(layer "In5.Cu")
	)
	(gr_line
		(start 41.985184 -103.071168)
		(end 42.003472 -103.083868)
		(stroke
			(width 0.08255)
			(type default)
		)
		(layer "In5.Cu")
	)
	(gr_line
		(start 42.003472 -103.083868)
		(end 42.016426 -103.102156)
		(stroke
			(width 0.08255)
			(type default)
		)
		(layer "In5.Cu")
	)
	(gr_line
		(start 42.00525 -412.496762)
		(end 42.023538 -412.509462)
		(stroke
			(width 0.08255)
			(type default)
		)
		(layer "In5.Cu")
	)
	(gr_line
		(start 42.023538 -412.509462)
		(end 42.036238 -412.52775)
		(stroke
			(width 0.08255)
			(type default)
		)
		(layer "In5.Cu")
	)
	(gr_line
		(start 42.076116 -209.126328)
		(end 42.079672 -209.105754)
		(stroke
			(width 0.08255)
			(type default)
		)
		(layer "In5.Cu")
	)
	(gr_line
		(start 42.076116 -209.084926)
		(end 42.079672 -209.105754)
		(stroke
			(width 0.08255)
			(type default)
		)
		(layer "In5.Cu")
	)
	(gr_line
		(start 42.076116 -209.084418)
		(end 42.076116 -209.08518)
		(stroke
			(width 0.08255)
			(type default)
		)
		(layer "In5.Cu")
	)
	(gr_line
		(start 42.13733 -116.034058)
		(end 42.14368 -115.99799)
		(stroke
			(width 0.08255)
			(type default)
		)
		(layer "In5.Cu")
	)
	(gr_line
		(start 42.14368 -115.99799)
		(end 42.164762 -115.967764)
		(stroke
			(width 0.08255)
			(type default)
		)
		(layer "In5.Cu")
	)
	(gr_line
		(start 42.21099 -204.106526)
		(end 42.229278 -204.119226)
		(stroke
			(width 0.08255)
			(type default)
		)
		(layer "In5.Cu")
	)
	(gr_line
		(start 42.229278 -204.119226)
		(end 42.241978 -204.137514)
		(stroke
			(width 0.08255)
			(type default)
		)
		(layer "In5.Cu")
	)
	(gr_line
		(start 42.401236 -411.465776)
		(end 42.419524 -411.478476)
		(stroke
			(width 0.08255)
			(type default)
		)
		(layer "In5.Cu")
	)
	(gr_line
		(start 42.419524 -411.478476)
		(end 42.432224 -411.496764)
		(stroke
			(width 0.08255)
			(type default)
		)
		(layer "In5.Cu")
	)
	(gr_line
		(start 42.45102 -419.601142)
		(end 42.472102 -419.570916)
		(stroke
			(width 0.08255)
			(type default)
		)
		(layer "In5.Cu")
	)
	(gr_line
		(start 42.472102 -419.570916)
		(end 42.478452 -419.534848)
		(stroke
			(width 0.08255)
			(type default)
		)
		(layer "In5.Cu")
	)
	(gr_line
		(start 42.537888 -103.847646)
		(end 42.55897 -103.877872)
		(stroke
			(width 0.08255)
			(type default)
		)
		(layer "In5.Cu")
	)
	(gr_line
		(start 42.55897 -103.877872)
		(end 42.56532 -103.913686)
		(stroke
			(width 0.08255)
			(type default)
		)
		(layer "In5.Cu")
	)
	(gr_line
		(start 42.685462 -102.453694)
		(end 42.70375 -102.466394)
		(stroke
			(width 0.08255)
			(type default)
		)
		(layer "In5.Cu")
	)
	(gr_line
		(start 42.70375 -102.466394)
		(end 42.71645 -102.484682)
		(stroke
			(width 0.08255)
			(type default)
		)
		(layer "In5.Cu")
	)
	(gr_line
		(start 42.845482 -112.31499)
		(end 42.866564 -112.284764)
		(stroke
			(width 0.08255)
			(type default)
		)
		(layer "In5.Cu")
	)
	(gr_line
		(start 42.866564 -112.284764)
		(end 42.872914 -112.248696)
		(stroke
			(width 0.08255)
			(type default)
		)
		(layer "In5.Cu")
	)
	(gr_line
		(start 42.941494 -206.709518)
		(end 42.962576 -206.739744)
		(stroke
			(width 0.08255)
			(type default)
		)
		(layer "In5.Cu")
	)
	(gr_line
		(start 42.960036 -106.19105)
		(end 42.963592 -106.170222)
		(stroke
			(width 0.08255)
			(type default)
		)
		(layer "In5.Cu")
	)
	(gr_line
		(start 42.960036 -106.190796)
		(end 42.960036 -106.191558)
		(stroke
			(width 0.08255)
			(type default)
		)
		(layer "In5.Cu")
	)
	(gr_line
		(start 42.960036 -106.149648)
		(end 42.963592 -106.170222)
		(stroke
			(width 0.08255)
			(type default)
		)
		(layer "In5.Cu")
	)
	(gr_line
		(start 42.962576 -206.739744)
		(end 42.968926 -206.775558)
		(stroke
			(width 0.08255)
			(type default)
		)
		(layer "In5.Cu")
	)
	(gr_line
		(start 42.997374 -203.497942)
		(end 43.015662 -203.510642)
		(stroke
			(width 0.08255)
			(type default)
		)
		(layer "In5.Cu")
	)
	(gr_line
		(start 43.015662 -203.510642)
		(end 43.028362 -203.52893)
		(stroke
			(width 0.08255)
			(type default)
		)
		(layer "In5.Cu")
	)
	(gr_line
		(start 43.01617 -413.927544)
		(end 43.037252 -413.95777)
		(stroke
			(width 0.08255)
			(type default)
		)
		(layer "In5.Cu")
	)
	(gr_line
		(start 43.023282 -410.758386)
		(end 43.04157 -410.771086)
		(stroke
			(width 0.08255)
			(type default)
		)
		(layer "In5.Cu")
	)
	(gr_line
		(start 43.036236 -211.262976)
		(end 43.057318 -211.23275)
		(stroke
			(width 0.08255)
			(type default)
		)
		(layer "In5.Cu")
	)
	(gr_line
		(start 43.037252 -413.95777)
		(end 43.043602 -413.993838)
		(stroke
			(width 0.08255)
			(type default)
		)
		(layer "In5.Cu")
	)
	(gr_line
		(start 43.04157 -410.771086)
		(end 43.05427 -410.789374)
		(stroke
			(width 0.08255)
			(type default)
		)
		(layer "In5.Cu")
	)
	(gr_line
		(start 43.057318 -211.23275)
		(end 43.063668 -211.196936)
		(stroke
			(width 0.08255)
			(type default)
		)
		(layer "In5.Cu")
	)
	(gr_line
		(start 43.192446 -101.604318)
		(end 43.210734 -101.617018)
		(stroke
			(width 0.08255)
			(type default)
		)
		(layer "In5.Cu")
	)
	(gr_line
		(start 43.210734 -101.617018)
		(end 43.223688 -101.635306)
		(stroke
			(width 0.08255)
			(type default)
		)
		(layer "In5.Cu")
	)
	(gr_line
		(start 43.24604 -415.182812)
		(end 43.249596 -415.162238)
		(stroke
			(width 0.08255)
			(type default)
		)
		(layer "In5.Cu")
	)
	(gr_line
		(start 43.24604 -415.14141)
		(end 43.249596 -415.162238)
		(stroke
			(width 0.08255)
			(type default)
		)
		(layer "In5.Cu")
	)
	(gr_line
		(start 43.24604 -415.140902)
		(end 43.24604 -415.141664)
		(stroke
			(width 0.08255)
			(type default)
		)
		(layer "In5.Cu")
	)
	(gr_line
		(start 43.311572 -420.059104)
		(end 43.332654 -420.028878)
		(stroke
			(width 0.08255)
			(type default)
		)
		(layer "In5.Cu")
	)
	(gr_line
		(start 43.332654 -420.028878)
		(end 43.339004 -419.99281)
		(stroke
			(width 0.08255)
			(type default)
		)
		(layer "In5.Cu")
	)
	(gr_line
		(start 43.402758 -209.274918)
		(end 43.406314 -209.254344)
		(stroke
			(width 0.08255)
			(type default)
		)
		(layer "In5.Cu")
	)
	(gr_line
		(start 43.402758 -209.234024)
		(end 43.406314 -209.254344)
		(stroke
			(width 0.08255)
			(type default)
		)
		(layer "In5.Cu")
	)
	(gr_line
		(start 43.402758 -209.233008)
		(end 43.402758 -209.23377)
		(stroke
			(width 0.08255)
			(type default)
		)
		(layer "In5.Cu")
	)
	(gr_line
		(start 43.473116 -103.565706)
		(end 43.494198 -103.595932)
		(stroke
			(width 0.08255)
			(type default)
		)
		(layer "In5.Cu")
	)
	(gr_line
		(start 43.494198 -103.595932)
		(end 43.500548 -103.632)
		(stroke
			(width 0.08255)
			(type default)
		)
		(layer "In5.Cu")
	)
	(gr_line
		(start 43.511724 -422.219374)
		(end 43.511978 -422.219374)
		(stroke
			(width 0.08255)
			(type default)
		)
		(layer "In5.Cu")
	)
	(gr_line
		(start 43.802554 -112.615218)
		(end 43.823636 -112.584992)
		(stroke
			(width 0.08255)
			(type default)
		)
		(layer "In5.Cu")
	)
	(gr_line
		(start 43.823636 -112.584992)
		(end 43.829986 -112.548924)
		(stroke
			(width 0.08255)
			(type default)
		)
		(layer "In5.Cu")
	)
	(gr_line
		(start 43.862244 -422.281096)
		(end 43.862244 -422.28135)
		(stroke
			(width 0.08255)
			(type default)
		)
		(layer "In5.Cu")
	)
	(gr_line
		(start 43.908472 -100.911152)
		(end 43.92676 -100.923852)
		(stroke
			(width 0.08255)
			(type default)
		)
		(layer "In5.Cu")
	)
	(gr_line
		(start 43.92676 -100.923852)
		(end 43.93946 -100.94214)
		(stroke
			(width 0.08255)
			(type default)
		)
		(layer "In5.Cu")
	)
	(gr_line
		(start 43.942762 -106.18089)
		(end 43.946318 -106.160062)
		(stroke
			(width 0.08255)
			(type default)
		)
		(layer "In5.Cu")
	)
	(gr_line
		(start 43.942762 -106.180636)
		(end 43.942762 -106.181398)
		(stroke
			(width 0.08255)
			(type default)
		)
		(layer "In5.Cu")
	)
	(gr_line
		(start 43.942762 -106.139488)
		(end 43.946318 -106.160062)
		(stroke
			(width 0.08255)
			(type default)
		)
		(layer "In5.Cu")
	)
	(gr_line
		(start 43.968924 -206.6036)
		(end 43.990006 -206.633826)
		(stroke
			(width 0.08255)
			(type default)
		)
		(layer "In5.Cu")
	)
	(gr_line
		(start 43.990006 -206.633826)
		(end 43.996356 -206.669894)
		(stroke
			(width 0.08255)
			(type default)
		)
		(layer "In5.Cu")
	)
	(gr_line
		(start 43.99788 -413.73298)
		(end 44.018962 -413.763206)
		(stroke
			(width 0.08255)
			(type default)
		)
		(layer "In5.Cu")
	)
	(gr_line
		(start 44.018962 -413.763206)
		(end 44.025312 -413.79902)
		(stroke
			(width 0.08255)
			(type default)
		)
		(layer "In5.Cu")
	)
	(gr_line
		(start 44.028868 -211.511388)
		(end 44.04995 -211.481162)
		(stroke
			(width 0.08255)
			(type default)
		)
		(layer "In5.Cu")
	)
	(gr_line
		(start 44.04995 -211.481162)
		(end 44.0563 -211.445348)
		(stroke
			(width 0.08255)
			(type default)
		)
		(layer "In5.Cu")
	)
	(gr_line
		(start 44.224702 -414.970722)
		(end 44.228258 -414.950148)
		(stroke
			(width 0.08255)
			(type default)
		)
		(layer "In5.Cu")
	)
	(gr_line
		(start 44.224702 -414.92932)
		(end 44.228258 -414.950148)
		(stroke
			(width 0.08255)
			(type default)
		)
		(layer "In5.Cu")
	)
	(gr_line
		(start 44.224702 -414.928812)
		(end 44.224702 -414.929574)
		(stroke
			(width 0.08255)
			(type default)
		)
		(layer "In5.Cu")
	)
	(gr_line
		(start 44.37634 -103.283004)
		(end 44.397422 -103.31323)
		(stroke
			(width 0.08255)
			(type default)
		)
		(layer "In5.Cu")
	)
	(gr_line
		(start 44.397422 -103.31323)
		(end 44.403772 -103.349044)
		(stroke
			(width 0.08255)
			(type default)
		)
		(layer "In5.Cu")
	)
	(gr_line
		(start 44.443396 -209.20837)
		(end 44.447206 -209.22996)
		(stroke
			(width 0.08255)
			(type default)
		)
		(layer "In5.Cu")
	)
	(gr_line
		(start 44.44365 -209.250534)
		(end 44.447206 -209.22996)
		(stroke
			(width 0.08255)
			(type default)
		)
		(layer "In5.Cu")
	)
	(gr_line
		(start 44.786804 -212.738208)
		(end 44.807886 -212.707982)
		(stroke
			(width 0.08255)
			(type default)
		)
		(layer "In5.Cu")
	)
	(gr_line
		(start 44.807886 -212.707982)
		(end 44.814236 -212.671914)
		(stroke
			(width 0.08255)
			(type default)
		)
		(layer "In5.Cu")
	)
	(gr_line
		(start 44.822364 -206.091028)
		(end 44.843446 -206.121254)
		(stroke
			(width 0.08255)
			(type default)
		)
		(layer "In5.Cu")
	)
	(gr_line
		(start 44.843446 -206.121254)
		(end 44.849796 -206.157322)
		(stroke
			(width 0.08255)
			(type default)
		)
		(layer "In5.Cu")
	)
	(gr_line
		(start 44.869608 -413.38246)
		(end 44.89069 -413.412686)
		(stroke
			(width 0.08255)
			(type default)
		)
		(layer "In5.Cu")
	)
	(gr_line
		(start 44.89069 -413.412686)
		(end 44.89704 -413.4485)
		(stroke
			(width 0.08255)
			(type default)
		)
		(layer "In5.Cu")
	)
	(gr_line
		(start 44.924472 -106.341926)
		(end 44.928028 -106.321352)
		(stroke
			(width 0.08255)
			(type default)
		)
		(layer "In5.Cu")
	)
	(gr_line
		(start 44.924472 -106.300524)
		(end 44.928028 -106.321352)
		(stroke
			(width 0.08255)
			(type default)
		)
		(layer "In5.Cu")
	)
	(gr_line
		(start 44.924472 -106.300016)
		(end 44.924472 -106.300778)
		(stroke
			(width 0.08255)
			(type default)
		)
		(layer "In5.Cu")
	)
	(gr_line
		(start 45.098208 -303.047908)
		(end 45.134276 -303.041558)
		(stroke
			(width 0.08255)
			(type default)
		)
		(layer "In5.Cu")
	)
	(gr_line
		(start 45.134276 -303.041558)
		(end 45.164502 -303.020476)
		(stroke
			(width 0.08255)
			(type default)
		)
		(layer "In5.Cu")
	)
	(gr_line
		(start 45.15485 -414.950402)
		(end 45.158406 -414.929828)
		(stroke
			(width 0.08255)
			(type default)
		)
		(layer "In5.Cu")
	)
	(gr_line
		(start 45.15485 -414.909508)
		(end 45.158406 -414.929828)
		(stroke
			(width 0.08255)
			(type default)
		)
		(layer "In5.Cu")
	)
	(gr_line
		(start 45.15485 -414.908492)
		(end 45.15485 -414.909254)
		(stroke
			(width 0.08255)
			(type default)
		)
		(layer "In5.Cu")
	)
	(gr_line
		(start 45.288708 -102.87)
		(end 45.310298 -102.900988)
		(stroke
			(width 0.08255)
			(type default)
		)
		(layer "In5.Cu")
	)
	(gr_line
		(start 45.310298 -102.900988)
		(end 45.316902 -102.938326)
		(stroke
			(width 0.08255)
			(type default)
		)
		(layer "In5.Cu")
	)
	(gr_line
		(start 45.334936 -112.059466)
		(end 45.356018 -112.02924)
		(stroke
			(width 0.08255)
			(type default)
		)
		(layer "In5.Cu")
	)
	(gr_line
		(start 45.356018 -112.02924)
		(end 45.362368 -111.993426)
		(stroke
			(width 0.08255)
			(type default)
		)
		(layer "In5.Cu")
	)
	(gr_line
		(start 45.4025 -209.334354)
		(end 45.406056 -209.31378)
		(stroke
			(width 0.08255)
			(type default)
		)
		(layer "In5.Cu")
	)
	(gr_line
		(start 45.4025 -209.292952)
		(end 45.406056 -209.31378)
		(stroke
			(width 0.08255)
			(type default)
		)
		(layer "In5.Cu")
	)
	(gr_line
		(start 45.4025 -209.292444)
		(end 45.4025 -209.293206)
		(stroke
			(width 0.08255)
			(type default)
		)
		(layer "In5.Cu")
	)
	(gr_line
		(start 45.471842 -303.929796)
		(end 45.507656 -303.923446)
		(stroke
			(width 0.08255)
			(type default)
		)
		(layer "In5.Cu")
	)
	(gr_line
		(start 45.507656 -303.923446)
		(end 45.537882 -303.902364)
		(stroke
			(width 0.08255)
			(type default)
		)
		(layer "In5.Cu")
	)
	(gr_line
		(start 45.823632 -304.79238)
		(end 45.8597 -304.78603)
		(stroke
			(width 0.08255)
			(type default)
		)
		(layer "In5.Cu")
	)
	(gr_line
		(start 45.8597 -304.78603)
		(end 45.889926 -304.764948)
		(stroke
			(width 0.08255)
			(type default)
		)
		(layer "In5.Cu")
	)
	(gr_line
		(start 46.134274 -107.617768)
		(end 46.13783 -107.59694)
		(stroke
			(width 0.08255)
			(type default)
		)
		(layer "In5.Cu")
	)
	(gr_line
		(start 46.134274 -107.617514)
		(end 46.134274 -107.618276)
		(stroke
			(width 0.08255)
			(type default)
		)
		(layer "In5.Cu")
	)
	(gr_line
		(start 46.134274 -107.576366)
		(end 46.13783 -107.59694)
		(stroke
			(width 0.08255)
			(type default)
		)
		(layer "In5.Cu")
	)
	(gr_line
		(start 46.271688 -305.637184)
		(end 46.307502 -305.630834)
		(stroke
			(width 0.08255)
			(type default)
		)
		(layer "In5.Cu")
	)
	(gr_line
		(start 46.307502 -305.630834)
		(end 46.337728 -305.609752)
		(stroke
			(width 0.08255)
			(type default)
		)
		(layer "In5.Cu")
	)
	(gr_line
		(start 55.23865 -211.517738)
		(end 55.25135 -211.49945)
		(stroke
			(width 0.08255)
			(type default)
		)
		(layer "In5.Cu")
	)
	(gr_line
		(start 55.25135 -211.49945)
		(end 55.269638 -211.48675)
		(stroke
			(width 0.08255)
			(type default)
		)
		(layer "In5.Cu")
	)
	(gr_line
		(start 55.93842 -212.173058)
		(end 55.949596 -212.156802)
		(stroke
			(width 0.08255)
			(type default)
		)
		(layer "In5.Cu")
	)
	(gr_line
		(start 55.949596 -212.156802)
		(end 55.966868 -212.14461)
		(stroke
			(width 0.08255)
			(type default)
		)
		(layer "In5.Cu")
	)
	(gr_line
		(start 56.603646 -212.809582)
		(end 56.616346 -212.791294)
		(stroke
			(width 0.08255)
			(type default)
		)
		(layer "In5.Cu")
	)
	(gr_line
		(start 56.616346 -212.791294)
		(end 56.634634 -212.778594)
		(stroke
			(width 0.08255)
			(type default)
		)
		(layer "In5.Cu")
	)
	(gr_line
		(start 58.0263 -213.425786)
		(end 58.039 -213.407498)
		(stroke
			(width 0.08255)
			(type default)
		)
		(layer "In5.Cu")
	)
	(gr_line
		(start 58.039 -213.407498)
		(end 58.057288 -213.394798)
		(stroke
			(width 0.08255)
			(type default)
		)
		(layer "In5.Cu")
	)
	(gr_line
		(start 66.727832 -287.486598)
		(end 66.758058 -287.465516)
		(stroke
			(width 0.08255)
			(type default)
		)
		(layer "In5.Cu")
	)
	(gr_line
		(start 66.758058 -287.465516)
		(end 66.794126 -287.459166)
		(stroke
			(width 0.08255)
			(type default)
		)
		(layer "In5.Cu")
	)
	(gr_line
		(start 67.142868 -288.340038)
		(end 67.173094 -288.318956)
		(stroke
			(width 0.08255)
			(type default)
		)
		(layer "In5.Cu")
	)
	(gr_line
		(start 67.173094 -288.318956)
		(end 67.209162 -288.312606)
		(stroke
			(width 0.08255)
			(type default)
		)
		(layer "In5.Cu")
	)
	(gr_line
		(start 67.38112 -289.283902)
		(end 67.411346 -289.26282)
		(stroke
			(width 0.08255)
			(type default)
		)
		(layer "In5.Cu")
	)
	(gr_line
		(start 67.411346 -289.26282)
		(end 67.447414 -289.25647)
		(stroke
			(width 0.08255)
			(type default)
		)
		(layer "In5.Cu")
	)
	(gr_line
		(start 67.663568 -290.24326)
		(end 67.693794 -290.222178)
		(stroke
			(width 0.08255)
			(type default)
		)
		(layer "In5.Cu")
	)
	(gr_line
		(start 67.693794 -290.222178)
		(end 67.729862 -290.215828)
		(stroke
			(width 0.08255)
			(type default)
		)
		(layer "In5.Cu")
	)
	(gr_line
		(start 81.446878 -193.157348)
		(end 81.477104 -193.136266)
		(stroke
			(width 0.08255)
			(type default)
		)
		(layer "In5.Cu")
	)
	(gr_line
		(start 81.477104 -193.136266)
		(end 81.513172 -193.129916)
		(stroke
			(width 0.08255)
			(type default)
		)
		(layer "In5.Cu")
	)
	(gr_line
		(start 81.813908 -194.046602)
		(end 81.844134 -194.02552)
		(stroke
			(width 0.08255)
			(type default)
		)
		(layer "In5.Cu")
	)
	(gr_line
		(start 81.844134 -194.02552)
		(end 81.880202 -194.01917)
		(stroke
			(width 0.08255)
			(type default)
		)
		(layer "In5.Cu")
	)
	(gr_line
		(start 82.06867 -194.969638)
		(end 82.098896 -194.948556)
		(stroke
			(width 0.08255)
			(type default)
		)
		(layer "In5.Cu")
	)
	(gr_line
		(start 82.098896 -194.948556)
		(end 82.134964 -194.942206)
		(stroke
			(width 0.08255)
			(type default)
		)
		(layer "In5.Cu")
	)
	(gr_line
		(start 83.361022 -195.678298)
		(end 83.391248 -195.657216)
		(stroke
			(width 0.08255)
			(type default)
		)
		(layer "In5.Cu")
	)
	(gr_line
		(start 83.391248 -195.657216)
		(end 83.427316 -195.650866)
		(stroke
			(width 0.08255)
			(type default)
		)
		(layer "In5.Cu")
	)
	(gr_line
		(start 88.113616 -157.544008)
		(end 88.126316 -157.52572)
		(stroke
			(width 0.08255)
			(type default)
		)
		(layer "In5.Cu")
	)
	(gr_line
		(start 88.126316 -157.52572)
		(end 88.144604 -157.51302)
		(stroke
			(width 0.08255)
			(type default)
		)
		(layer "In5.Cu")
	)
	(gr_line
		(start 88.674956 -158.379668)
		(end 88.68791 -158.36138)
		(stroke
			(width 0.08255)
			(type default)
		)
		(layer "In5.Cu")
	)
	(gr_line
		(start 88.68791 -158.36138)
		(end 88.706452 -158.348426)
		(stroke
			(width 0.08255)
			(type default)
		)
		(layer "In5.Cu")
	)
	(gr_line
		(start 89.367868 -159.089598)
		(end 89.381838 -159.069786)
		(stroke
			(width 0.08255)
			(type default)
		)
		(layer "In5.Cu")
	)
	(gr_line
		(start 89.381838 -159.069786)
		(end 89.40038 -159.057086)
		(stroke
			(width 0.08255)
			(type default)
		)
		(layer "In5.Cu")
	)
	(gr_line
		(start 89.938352 -159.897826)
		(end 89.951052 -159.879538)
		(stroke
			(width 0.08255)
			(type default)
		)
		(layer "In5.Cu")
	)
	(gr_line
		(start 89.951052 -159.879538)
		(end 89.96934 -159.866838)
		(stroke
			(width 0.08255)
			(type default)
		)
		(layer "In5.Cu")
	)
	(gr_line
		(start 163.227004 -273.377406)
		(end 163.247578 -273.37385)
		(stroke
			(width 0.08255)
			(type default)
		)
		(layer "In5.Cu")
	)
	(gr_line
		(start 163.247578 -273.37385)
		(end 163.268406 -273.377406)
		(stroke
			(width 0.08255)
			(type default)
		)
		(layer "In5.Cu")
	)
	(gr_line
		(start 173.939962 -270.483584)
		(end 173.961044 -270.480028)
		(stroke
			(width 0.08255)
			(type default)
		)
		(layer "In5.Cu")
	)
	(gr_line
		(start 173.961044 -270.480028)
		(end 173.964092 -270.480536)
		(stroke
			(width 0.08255)
			(type default)
		)
		(layer "In5.Cu")
	)
	(gr_line
		(start 173.964092 -270.480536)
		(end 173.981618 -270.483584)
		(stroke
			(width 0.08255)
			(type default)
		)
		(layer "In5.Cu")
	)
	(gr_line
		(start 184.749948 -267.589508)
		(end 184.770522 -267.585952)
		(stroke
			(width 0.08255)
			(type default)
		)
		(layer "In5.Cu")
	)
	(gr_line
		(start 184.770522 -267.585952)
		(end 184.791096 -267.589508)
		(stroke
			(width 0.08255)
			(type default)
		)
		(layer "In5.Cu")
	)
	(gr_line
		(start 188.787786 -469.721184)
		(end 188.823854 -469.727534)
		(stroke
			(width 0.08255)
			(type default)
		)
		(layer "In5.Cu")
	)
	(gr_line
		(start 188.823854 -469.727534)
		(end 188.85408 -469.748616)
		(stroke
			(width 0.08255)
			(type default)
		)
		(layer "In5.Cu")
	)
	(gr_line
		(start 194.392296 -176.084738)
		(end 194.41287 -176.081182)
		(stroke
			(width 0.08255)
			(type default)
		)
		(layer "In5.Cu")
	)
	(gr_line
		(start 194.41287 -176.081182)
		(end 194.433444 -176.084738)
		(stroke
			(width 0.08255)
			(type default)
		)
		(layer "In5.Cu")
	)
	(gr_line
		(start 195.360798 -469.892634)
		(end 195.395342 -469.89873)
		(stroke
			(width 0.08255)
			(type default)
		)
		(layer "In5.Cu")
	)
	(gr_line
		(start 195.395342 -469.89873)
		(end 195.396612 -469.89873)
		(stroke
			(width 0.08255)
			(type default)
		)
		(layer "In5.Cu")
	)
	(gr_line
		(start 195.396612 -469.89873)
		(end 195.427092 -469.920066)
		(stroke
			(width 0.08255)
			(type default)
		)
		(layer "In5.Cu")
	)
	(gr_line
		(start 195.583556 -173.373796)
		(end 195.614544 -173.368208)
		(stroke
			(width 0.08255)
			(type default)
		)
		(layer "In5.Cu")
	)
	(gr_line
		(start 195.614544 -173.368208)
		(end 195.640198 -173.351444)
		(stroke
			(width 0.08255)
			(type default)
		)
		(layer "In5.Cu")
	)
	(gr_line
		(start 198.052436 -174.501302)
		(end 198.07301 -174.497746)
		(stroke
			(width 0.08255)
			(type default)
		)
		(layer "In5.Cu")
	)
	(gr_line
		(start 198.07301 -174.497746)
		(end 198.093584 -174.501302)
		(stroke
			(width 0.08255)
			(type default)
		)
		(layer "In5.Cu")
	)
	(gr_line
		(start 201.30389 -469.959944)
		(end 201.339704 -469.966294)
		(stroke
			(width 0.08255)
			(type default)
		)
		(layer "In5.Cu")
	)
	(gr_line
		(start 201.339704 -469.966294)
		(end 201.36993 -469.987376)
		(stroke
			(width 0.08255)
			(type default)
		)
		(layer "In5.Cu")
	)
	(gr_line
		(start 203.633832 -172.912024)
		(end 203.66482 -172.906436)
		(stroke
			(width 0.08255)
			(type default)
		)
		(layer "In5.Cu")
	)
	(gr_line
		(start 203.66482 -172.906436)
		(end 203.690474 -172.889672)
		(stroke
			(width 0.08255)
			(type default)
		)
		(layer "In5.Cu")
	)
	(gr_line
		(start 204.203808 -79.876396)
		(end 204.234034 -79.855314)
		(stroke
			(width 0.08255)
			(type default)
		)
		(layer "In5.Cu")
	)
	(gr_line
		(start 204.234034 -79.855314)
		(end 204.269848 -79.848964)
		(stroke
			(width 0.08255)
			(type default)
		)
		(layer "In5.Cu")
	)
	(gr_line
		(start 204.455014 -76.5048)
		(end 204.477112 -76.489306)
		(stroke
			(width 0.08255)
			(type default)
		)
		(layer "In5.Cu")
	)
	(gr_line
		(start 204.477112 -76.489306)
		(end 204.491844 -76.4667)
		(stroke
			(width 0.08255)
			(type default)
		)
		(layer "In5.Cu")
	)
	(gr_line
		(start 205.511654 -470.050368)
		(end 205.539086 -470.055194)
		(stroke
			(width 0.08255)
			(type default)
		)
		(layer "In5.Cu")
	)
	(gr_line
		(start 205.539086 -470.055194)
		(end 205.566264 -470.049352)
		(stroke
			(width 0.08255)
			(type default)
		)
		(layer "In5.Cu")
	)
	(gr_line
		(start 206.579978 -170.59021)
		(end 206.59979 -170.577256)
		(stroke
			(width 0.08255)
			(type default)
		)
		(layer "In5.Cu")
	)
	(gr_line
		(start 206.59979 -170.577256)
		(end 206.623666 -170.572176)
		(stroke
			(width 0.08255)
			(type default)
		)
		(layer "In5.Cu")
	)
	(gr_line
		(start 211.175092 -73.787762)
		(end 211.205318 -73.76668)
		(stroke
			(width 0.08255)
			(type default)
		)
		(layer "In5.Cu")
	)
	(gr_line
		(start 211.205318 -73.76668)
		(end 211.241386 -73.76033)
		(stroke
			(width 0.08255)
			(type default)
		)
		(layer "In5.Cu")
	)
	(gr_line
		(start 211.910168 -177.298858)
		(end 211.9376 -177.303684)
		(stroke
			(width 0.08255)
			(type default)
		)
		(layer "In5.Cu")
	)
	(gr_line
		(start 211.9376 -177.303684)
		(end 211.964778 -177.297842)
		(stroke
			(width 0.08255)
			(type default)
		)
		(layer "In5.Cu")
	)
	(gr_line
		(start 212.575394 -169.306748)
		(end 212.609176 -169.299636)
		(stroke
			(width 0.08255)
			(type default)
		)
		(layer "In5.Cu")
	)
	(gr_line
		(start 212.609176 -169.299636)
		(end 212.642958 -169.306748)
		(stroke
			(width 0.08255)
			(type default)
		)
		(layer "In5.Cu")
	)
	(gr_line
		(start 214.494364 -479.611182)
		(end 214.52459 -479.632264)
		(stroke
			(width 0.08255)
			(type default)
		)
		(layer "In5.Cu")
	)
	(gr_line
		(start 214.52459 -479.632264)
		(end 214.560658 -479.638614)
		(stroke
			(width 0.08255)
			(type default)
		)
		(layer "In5.Cu")
	)
	(gr_line
		(start 214.999316 -484.06177)
		(end 215.029542 -484.082852)
		(stroke
			(width 0.08255)
			(type default)
		)
		(layer "In5.Cu")
	)
	(gr_line
		(start 215.029542 -484.082852)
		(end 215.06561 -484.089202)
		(stroke
			(width 0.08255)
			(type default)
		)
		(layer "In5.Cu")
	)
	(gr_line
		(start 215.708738 -488.987084)
		(end 215.738964 -489.008166)
		(stroke
			(width 0.08255)
			(type default)
		)
		(layer "In5.Cu")
	)
	(gr_line
		(start 215.738964 -489.008166)
		(end 215.775032 -489.014516)
		(stroke
			(width 0.08255)
			(type default)
		)
		(layer "In5.Cu")
	)
	(gr_line
		(start 217.442542 -55.870094)
		(end 217.461846 -55.840376)
		(stroke
			(width 0.08255)
			(type default)
		)
		(layer "In5.Cu")
	)
	(gr_line
		(start 217.461846 -55.840376)
		(end 217.491818 -55.820818)
		(stroke
			(width 0.08255)
			(type default)
		)
		(layer "In5.Cu")
	)
	(gr_line
		(start 218.063318 -67.773042)
		(end 218.093544 -67.75196)
		(stroke
			(width 0.08255)
			(type default)
		)
		(layer "In5.Cu")
	)
	(gr_line
		(start 218.093544 -67.75196)
		(end 218.129358 -67.74561)
		(stroke
			(width 0.08255)
			(type default)
		)
		(layer "In5.Cu")
	)
	(gr_line
		(start 218.778328 -363.852714)
		(end 218.835732 -363.812582)
		(stroke
			(width 0.08255)
			(type default)
		)
		(layer "In5.Cu")
	)
	(gr_line
		(start 218.86418 -157.846776)
		(end 218.917012 -157.812486)
		(stroke
			(width 0.08255)
			(type default)
		)
		(layer "In5.Cu")
	)
	(gr_line
		(start 218.99245 -54.846728)
		(end 219.045536 -54.812438)
		(stroke
			(width 0.08255)
			(type default)
		)
		(layer "In5.Cu")
	)
	(gr_line
		(start 220.176852 -489.64342)
		(end 220.330014 -489.796582)
		(stroke
			(width 0.08255)
			(type default)
		)
		(layer "In5.Cu")
	)
	(gr_line
		(start 220.176852 -489.136944)
		(end 220.330014 -488.983782)
		(stroke
			(width 0.08255)
			(type default)
		)
		(layer "In5.Cu")
	)
	(gr_line
		(start 220.176852 -484.843328)
		(end 220.330014 -484.99649)
		(stroke
			(width 0.08255)
			(type default)
		)
		(layer "In5.Cu")
	)
	(gr_line
		(start 220.176852 -484.336852)
		(end 220.330014 -484.18369)
		(stroke
			(width 0.08255)
			(type default)
		)
		(layer "In5.Cu")
	)
	(gr_line
		(start 220.176852 -480.04349)
		(end 220.330014 -480.196652)
		(stroke
			(width 0.08255)
			(type default)
		)
		(layer "In5.Cu")
	)
	(gr_line
		(start 220.176852 -479.537014)
		(end 220.330014 -479.383852)
		(stroke
			(width 0.08255)
			(type default)
		)
		(layer "In5.Cu")
	)
	(gr_line
		(start 220.176852 -467.243414)
		(end 220.330014 -467.396576)
		(stroke
			(width 0.08255)
			(type default)
		)
		(layer "In5.Cu")
	)
	(gr_line
		(start 220.176852 -466.736938)
		(end 220.330014 -466.583776)
		(stroke
			(width 0.08255)
			(type default)
		)
		(layer "In5.Cu")
	)
	(gr_line
		(start 220.176852 -386.643372)
		(end 220.330014 -386.796534)
		(stroke
			(width 0.08255)
			(type default)
		)
		(layer "In5.Cu")
	)
	(gr_line
		(start 220.176852 -386.136896)
		(end 220.330014 -385.983734)
		(stroke
			(width 0.08255)
			(type default)
		)
		(layer "In5.Cu")
	)
	(gr_line
		(start 220.176852 -381.84328)
		(end 220.330014 -381.996442)
		(stroke
			(width 0.08255)
			(type default)
		)
		(layer "In5.Cu")
	)
	(gr_line
		(start 220.176852 -381.336804)
		(end 220.330014 -381.183642)
		(stroke
			(width 0.08255)
			(type default)
		)
		(layer "In5.Cu")
	)
	(gr_line
		(start 220.176852 -377.043442)
		(end 220.330014 -377.196604)
		(stroke
			(width 0.08255)
			(type default)
		)
		(layer "In5.Cu")
	)
	(gr_line
		(start 220.176852 -376.536966)
		(end 220.330014 -376.383804)
		(stroke
			(width 0.08255)
			(type default)
		)
		(layer "In5.Cu")
	)
	(gr_line
		(start 220.176852 -364.243366)
		(end 220.330014 -364.396528)
		(stroke
			(width 0.08255)
			(type default)
		)
		(layer "In5.Cu")
	)
	(gr_line
		(start 220.176852 -363.73689)
		(end 220.330014 -363.583728)
		(stroke
			(width 0.08255)
			(type default)
		)
		(layer "In5.Cu")
	)
	(gr_line
		(start 220.176852 -283.643324)
		(end 220.330014 -283.796486)
		(stroke
			(width 0.08255)
			(type default)
		)
		(layer "In5.Cu")
	)
	(gr_line
		(start 220.176852 -283.136848)
		(end 220.330014 -282.983686)
		(stroke
			(width 0.08255)
			(type default)
		)
		(layer "In5.Cu")
	)
	(gr_line
		(start 220.176852 -278.843232)
		(end 220.330014 -278.996394)
		(stroke
			(width 0.08255)
			(type default)
		)
		(layer "In5.Cu")
	)
	(gr_line
		(start 220.176852 -278.336756)
		(end 220.330014 -278.183594)
		(stroke
			(width 0.08255)
			(type default)
		)
		(layer "In5.Cu")
	)
	(gr_line
		(start 220.176852 -274.043394)
		(end 220.330014 -274.196556)
		(stroke
			(width 0.08255)
			(type default)
		)
		(layer "In5.Cu")
	)
	(gr_line
		(start 220.176852 -273.536918)
		(end 220.330014 -273.383756)
		(stroke
			(width 0.08255)
			(type default)
		)
		(layer "In5.Cu")
	)
	(gr_line
		(start 220.176852 -261.243318)
		(end 220.330014 -261.39648)
		(stroke
			(width 0.08255)
			(type default)
		)
		(layer "In5.Cu")
	)
	(gr_line
		(start 220.176852 -260.736842)
		(end 220.330014 -260.58368)
		(stroke
			(width 0.08255)
			(type default)
		)
		(layer "In5.Cu")
	)
	(gr_line
		(start 220.176852 -180.643276)
		(end 220.330014 -180.796438)
		(stroke
			(width 0.08255)
			(type default)
		)
		(layer "In5.Cu")
	)
	(gr_line
		(start 220.176852 -180.1368)
		(end 220.330014 -179.983638)
		(stroke
			(width 0.08255)
			(type default)
		)
		(layer "In5.Cu")
	)
	(gr_line
		(start 220.176852 -175.843184)
		(end 220.330014 -175.996346)
		(stroke
			(width 0.08255)
			(type default)
		)
		(layer "In5.Cu")
	)
	(gr_line
		(start 220.176852 -175.336708)
		(end 220.330014 -175.183546)
		(stroke
			(width 0.08255)
			(type default)
		)
		(layer "In5.Cu")
	)
	(gr_line
		(start 220.176852 -171.043346)
		(end 220.330014 -171.196508)
		(stroke
			(width 0.08255)
			(type default)
		)
		(layer "In5.Cu")
	)
	(gr_line
		(start 220.176852 -170.53687)
		(end 220.330014 -170.383708)
		(stroke
			(width 0.08255)
			(type default)
		)
		(layer "In5.Cu")
	)
	(gr_line
		(start 220.176852 -158.24327)
		(end 220.330014 -158.396432)
		(stroke
			(width 0.08255)
			(type default)
		)
		(layer "In5.Cu")
	)
	(gr_line
		(start 220.176852 -157.736794)
		(end 220.330014 -157.583632)
		(stroke
			(width 0.08255)
			(type default)
		)
		(layer "In5.Cu")
	)
	(gr_line
		(start 220.176852 -77.643228)
		(end 220.330014 -77.79639)
		(stroke
			(width 0.08255)
			(type default)
		)
		(layer "In5.Cu")
	)
	(gr_line
		(start 220.176852 -77.136752)
		(end 220.330014 -76.98359)
		(stroke
			(width 0.08255)
			(type default)
		)
		(layer "In5.Cu")
	)
	(gr_line
		(start 220.176852 -72.843136)
		(end 220.330014 -72.996298)
		(stroke
			(width 0.08255)
			(type default)
		)
		(layer "In5.Cu")
	)
	(gr_line
		(start 220.176852 -72.33666)
		(end 220.330014 -72.183498)
		(stroke
			(width 0.08255)
			(type default)
		)
		(layer "In5.Cu")
	)
	(gr_line
		(start 220.176852 -68.043298)
		(end 220.330014 -68.19646)
		(stroke
			(width 0.08255)
			(type default)
		)
		(layer "In5.Cu")
	)
	(gr_line
		(start 220.176852 -67.536822)
		(end 220.330014 -67.38366)
		(stroke
			(width 0.08255)
			(type default)
		)
		(layer "In5.Cu")
	)
	(gr_line
		(start 220.176852 -55.243222)
		(end 220.330014 -55.396384)
		(stroke
			(width 0.08255)
			(type default)
		)
		(layer "In5.Cu")
	)
	(gr_line
		(start 220.176852 -54.736746)
		(end 220.330014 -54.583584)
		(stroke
			(width 0.08255)
			(type default)
		)
		(layer "In5.Cu")
	)
	(gr_line
		(start 0 -505.000006)
		(end 0 -421.942006)
		(stroke
			(width 1.524)
			(type default)
		)
		(layer "In6.Cu")
	)
	(gr_arc
		(start 0 -505.000006)
		(mid 0.292895 -505.707108)
		(end 0.999998 -506.000004)
		(stroke
			(width 1.524)
			(type default)
		)
		(layer "In6.Cu")
	)
	(gr_line
		(start 0 -421.942006)
		(end 0.500126 -421.44188)
		(stroke
			(width 1.524)
			(type default)
		)
		(layer "In6.Cu")
	)
	(gr_line
		(start 0 -418.742114)
		(end 0 -315.941964)
		(stroke
			(width 1.524)
			(type default)
		)
		(layer "In6.Cu")
	)
	(gr_line
		(start 0 -315.941964)
		(end 0.500126 -315.442092)
		(stroke
			(width 1.524)
			(type default)
		)
		(layer "In6.Cu")
	)
	(gr_line
		(start 0 -312.742072)
		(end 0 -189.941962)
		(stroke
			(width 1.524)
			(type default)
		)
		(layer "In6.Cu")
	)
	(gr_line
		(start 0 -189.941962)
		(end 0.500126 -189.44209)
		(stroke
			(width 1.524)
			(type default)
		)
		(layer "In6.Cu")
	)
	(gr_line
		(start 0 -186.74207)
		(end 0 -0.999998)
		(stroke
			(width 1.524)
			(type default)
		)
		(layer "In6.Cu")
	)
	(gr_line
		(start 0.500126 -421.44188)
		(end 4.400042 -421.44188)
		(stroke
			(width 1.524)
			(type default)
		)
		(layer "In6.Cu")
	)
	(gr_line
		(start 0.500126 -419.241986)
		(end 0 -418.742114)
		(stroke
			(width 1.524)
			(type default)
		)
		(layer "In6.Cu")
	)
	(gr_line
		(start 0.500126 -315.442092)
		(end 4.400042 -315.442092)
		(stroke
			(width 1.524)
			(type default)
		)
		(layer "In6.Cu")
	)
	(gr_line
		(start 0.500126 -313.241944)
		(end 0 -312.742072)
		(stroke
			(width 1.524)
			(type default)
		)
		(layer "In6.Cu")
	)
	(gr_line
		(start 0.500126 -189.44209)
		(end 4.400042 -189.44209)
		(stroke
			(width 1.524)
			(type default)
		)
		(layer "In6.Cu")
	)
	(gr_line
		(start 0.500126 -187.241942)
		(end 0 -186.74207)
		(stroke
			(width 1.524)
			(type default)
		)
		(layer "In6.Cu")
	)
	(gr_arc
		(start 0.999998 0)
		(mid 0.292893 -0.292893)
		(end 0 -0.999998)
		(stroke
			(width 1.524)
			(type default)
		)
		(layer "In6.Cu")
	)
	(gr_line
		(start 0.999998 0)
		(end 30.80004 0)
		(stroke
			(width 1.524)
			(type default)
		)
		(layer "In6.Cu")
	)
	(gr_rect
		(start 1.005332 -446.887854)
		(end 3.494532 -448.195954)
		(stroke
			(width 0)
			(type default)
		)
		(fill no)
		(layer "In6.Cu")
	)
	(gr_rect
		(start 1.005332 -444.487808)
		(end 3.494532 -445.795908)
		(stroke
			(width 0)
			(type default)
		)
		(fill no)
		(layer "In6.Cu")
	)
	(gr_rect
		(start 1.005332 -441.287916)
		(end 3.494532 -442.596016)
		(stroke
			(width 0)
			(type default)
		)
		(fill no)
		(layer "In6.Cu")
	)
	(gr_rect
		(start 1.005332 -438.088024)
		(end 3.494532 -439.39587)
		(stroke
			(width 0)
			(type default)
		)
		(fill no)
		(layer "In6.Cu")
	)
	(gr_rect
		(start 1.005332 -434.887878)
		(end 3.494532 -436.195978)
		(stroke
			(width 0)
			(type default)
		)
		(fill no)
		(layer "In6.Cu")
	)
	(gr_rect
		(start 1.005332 -429.28794)
		(end 3.494532 -430.595786)
		(stroke
			(width 0)
			(type default)
		)
		(fill no)
		(layer "In6.Cu")
	)
	(gr_rect
		(start 1.005332 -426.087794)
		(end 3.494532 -427.395894)
		(stroke
			(width 0)
			(type default)
		)
		(fill no)
		(layer "In6.Cu")
	)
	(gr_rect
		(start 1.005332 -422.887902)
		(end 3.494532 -424.196002)
		(stroke
			(width 0)
			(type default)
		)
		(fill no)
		(layer "In6.Cu")
	)
	(gr_rect
		(start 1.005332 -416.487864)
		(end 3.494532 -417.795964)
		(stroke
			(width 0)
			(type default)
		)
		(fill no)
		(layer "In6.Cu")
	)
	(gr_rect
		(start 1.005332 -413.287972)
		(end 3.494532 -414.595818)
		(stroke
			(width 0)
			(type default)
		)
		(fill no)
		(layer "In6.Cu")
	)
	(gr_rect
		(start 1.005332 -410.087826)
		(end 3.494532 -411.395926)
		(stroke
			(width 0)
			(type default)
		)
		(fill no)
		(layer "In6.Cu")
	)
	(gr_rect
		(start 1.005332 -406.887934)
		(end 3.494532 -408.19578)
		(stroke
			(width 0)
			(type default)
		)
		(fill no)
		(layer "In6.Cu")
	)
	(gr_rect
		(start 1.005332 -403.687788)
		(end 3.494532 -404.995888)
		(stroke
			(width 0)
			(type default)
		)
		(fill no)
		(layer "In6.Cu")
	)
	(gr_rect
		(start 1.005332 -398.08785)
		(end 3.494532 -399.39595)
		(stroke
			(width 0)
			(type default)
		)
		(fill no)
		(layer "In6.Cu")
	)
	(gr_rect
		(start 1.005332 -394.887958)
		(end 3.494532 -396.195804)
		(stroke
			(width 0)
			(type default)
		)
		(fill no)
		(layer "In6.Cu")
	)
	(gr_rect
		(start 1.005332 -391.687812)
		(end 3.494532 -392.995912)
		(stroke
			(width 0)
			(type default)
		)
		(fill no)
		(layer "In6.Cu")
	)
	(gr_rect
		(start 1.005332 -388.48792)
		(end 3.494532 -389.79602)
		(stroke
			(width 0)
			(type default)
		)
		(fill no)
		(layer "In6.Cu")
	)
	(gr_rect
		(start 1.005332 -384.487928)
		(end 3.494532 -385.795774)
		(stroke
			(width 0)
			(type default)
		)
		(fill no)
		(layer "In6.Cu")
	)
	(gr_rect
		(start 1.005332 -357.688134)
		(end 3.494532 -358.996234)
		(stroke
			(width 0)
			(type default)
		)
		(fill no)
		(layer "In6.Cu")
	)
	(gr_rect
		(start 1.005332 -354.487988)
		(end 3.494532 -355.796088)
		(stroke
			(width 0)
			(type default)
		)
		(fill no)
		(layer "In6.Cu")
	)
	(gr_rect
		(start 1.005332 -351.288096)
		(end 3.494532 -352.596196)
		(stroke
			(width 0)
			(type default)
		)
		(fill no)
		(layer "In6.Cu")
	)
	(gr_rect
		(start 1.005332 -348.088204)
		(end 3.494532 -349.39605)
		(stroke
			(width 0)
			(type default)
		)
		(fill no)
		(layer "In6.Cu")
	)
	(gr_rect
		(start 1.005332 -344.888058)
		(end 3.494532 -346.196158)
		(stroke
			(width 0)
			(type default)
		)
		(fill no)
		(layer "In6.Cu")
	)
	(gr_rect
		(start 1.005332 -341.688166)
		(end 3.494532 -342.996012)
		(stroke
			(width 0)
			(type default)
		)
		(fill no)
		(layer "In6.Cu")
	)
	(gr_rect
		(start 1.005332 -338.48802)
		(end 3.494532 -339.79612)
		(stroke
			(width 0)
			(type default)
		)
		(fill no)
		(layer "In6.Cu")
	)
	(gr_rect
		(start 1.005332 -335.288128)
		(end 3.494532 -336.596228)
		(stroke
			(width 0)
			(type default)
		)
		(fill no)
		(layer "In6.Cu")
	)
	(gr_rect
		(start 1.005332 -329.68819)
		(end 3.494532 -330.996036)
		(stroke
			(width 0)
			(type default)
		)
		(fill no)
		(layer "In6.Cu")
	)
	(gr_rect
		(start 1.005332 -326.488044)
		(end 3.494532 -327.796144)
		(stroke
			(width 0)
			(type default)
		)
		(fill no)
		(layer "In6.Cu")
	)
	(gr_rect
		(start 1.005332 -323.288152)
		(end 3.494532 -324.595998)
		(stroke
			(width 0)
			(type default)
		)
		(fill no)
		(layer "In6.Cu")
	)
	(gr_rect
		(start 1.005332 -320.088006)
		(end 3.494532 -321.396106)
		(stroke
			(width 0)
			(type default)
		)
		(fill no)
		(layer "In6.Cu")
	)
	(gr_rect
		(start 1.005332 -316.888114)
		(end 3.494532 -318.196214)
		(stroke
			(width 0)
			(type default)
		)
		(fill no)
		(layer "In6.Cu")
	)
	(gr_rect
		(start 1.005332 -308.88813)
		(end 3.494532 -310.19623)
		(stroke
			(width 0)
			(type default)
		)
		(fill no)
		(layer "In6.Cu")
	)
	(gr_rect
		(start 1.005332 -305.687984)
		(end 3.494532 -306.996084)
		(stroke
			(width 0)
			(type default)
		)
		(fill no)
		(layer "In6.Cu")
	)
	(gr_rect
		(start 1.005332 -302.488092)
		(end 3.494532 -303.796192)
		(stroke
			(width 0)
			(type default)
		)
		(fill no)
		(layer "In6.Cu")
	)
	(gr_rect
		(start 1.005332 -299.2882)
		(end 3.494532 -300.596046)
		(stroke
			(width 0)
			(type default)
		)
		(fill no)
		(layer "In6.Cu")
	)
	(gr_rect
		(start 1.005332 -296.088054)
		(end 3.494532 -297.396154)
		(stroke
			(width 0)
			(type default)
		)
		(fill no)
		(layer "In6.Cu")
	)
	(gr_rect
		(start 1.005332 -292.888162)
		(end 3.494532 -294.196008)
		(stroke
			(width 0)
			(type default)
		)
		(fill no)
		(layer "In6.Cu")
	)
	(gr_rect
		(start 1.005332 -289.688016)
		(end 3.494532 -290.996116)
		(stroke
			(width 0)
			(type default)
		)
		(fill no)
		(layer "In6.Cu")
	)
	(gr_rect
		(start 1.005332 -283.288232)
		(end 3.494532 -284.596078)
		(stroke
			(width 0)
			(type default)
		)
		(fill no)
		(layer "In6.Cu")
	)
	(gr_rect
		(start 1.005332 -280.088086)
		(end 3.494532 -281.396186)
		(stroke
			(width 0)
			(type default)
		)
		(fill no)
		(layer "In6.Cu")
	)
	(gr_rect
		(start 1.005332 -231.688132)
		(end 3.494532 -232.996232)
		(stroke
			(width 0)
			(type default)
		)
		(fill no)
		(layer "In6.Cu")
	)
	(gr_rect
		(start 1.005332 -228.487986)
		(end 3.494532 -229.796086)
		(stroke
			(width 0)
			(type default)
		)
		(fill no)
		(layer "In6.Cu")
	)
	(gr_rect
		(start 1.005332 -222.088202)
		(end 3.494532 -223.396048)
		(stroke
			(width 0)
			(type default)
		)
		(fill no)
		(layer "In6.Cu")
	)
	(gr_rect
		(start 1.005332 -218.888056)
		(end 3.494532 -220.196156)
		(stroke
			(width 0)
			(type default)
		)
		(fill no)
		(layer "In6.Cu")
	)
	(gr_rect
		(start 1.005332 -215.688164)
		(end 3.494532 -216.99601)
		(stroke
			(width 0)
			(type default)
		)
		(fill no)
		(layer "In6.Cu")
	)
	(gr_rect
		(start 1.005332 -212.488018)
		(end 3.494532 -213.796118)
		(stroke
			(width 0)
			(type default)
		)
		(fill no)
		(layer "In6.Cu")
	)
	(gr_rect
		(start 1.005332 -209.288126)
		(end 3.494532 -210.596226)
		(stroke
			(width 0)
			(type default)
		)
		(fill no)
		(layer "In6.Cu")
	)
	(gr_rect
		(start 1.005332 -206.088234)
		(end 3.494532 -207.39608)
		(stroke
			(width 0)
			(type default)
		)
		(fill no)
		(layer "In6.Cu")
	)
	(gr_rect
		(start 1.005332 -202.888088)
		(end 3.494532 -204.196188)
		(stroke
			(width 0)
			(type default)
		)
		(fill no)
		(layer "In6.Cu")
	)
	(gr_rect
		(start 1.005332 -199.688196)
		(end 3.494532 -200.996042)
		(stroke
			(width 0)
			(type default)
		)
		(fill no)
		(layer "In6.Cu")
	)
	(gr_rect
		(start 1.005332 -194.088004)
		(end 3.494532 -195.396104)
		(stroke
			(width 0)
			(type default)
		)
		(fill no)
		(layer "In6.Cu")
	)
	(gr_rect
		(start 1.005332 -190.888112)
		(end 3.494532 -192.196212)
		(stroke
			(width 0)
			(type default)
		)
		(fill no)
		(layer "In6.Cu")
	)
	(gr_rect
		(start 1.005332 -182.888128)
		(end 3.494532 -184.196228)
		(stroke
			(width 0)
			(type default)
		)
		(fill no)
		(layer "In6.Cu")
	)
	(gr_rect
		(start 1.005332 -179.687982)
		(end 3.494532 -180.996082)
		(stroke
			(width 0)
			(type default)
		)
		(fill no)
		(layer "In6.Cu")
	)
	(gr_rect
		(start 1.005332 -176.48809)
		(end 3.494532 -177.79619)
		(stroke
			(width 0)
			(type default)
		)
		(fill no)
		(layer "In6.Cu")
	)
	(gr_rect
		(start 1.005332 -173.288198)
		(end 3.494532 -174.596044)
		(stroke
			(width 0)
			(type default)
		)
		(fill no)
		(layer "In6.Cu")
	)
	(gr_rect
		(start 1.005332 -170.088052)
		(end 3.494532 -171.396152)
		(stroke
			(width 0)
			(type default)
		)
		(fill no)
		(layer "In6.Cu")
	)
	(gr_rect
		(start 1.005332 -166.88816)
		(end 3.494532 -168.196006)
		(stroke
			(width 0)
			(type default)
		)
		(fill no)
		(layer "In6.Cu")
	)
	(gr_rect
		(start 1.005332 -163.688014)
		(end 3.494532 -164.996114)
		(stroke
			(width 0)
			(type default)
		)
		(fill no)
		(layer "In6.Cu")
	)
	(gr_rect
		(start 1.005332 -160.488122)
		(end 3.494532 -161.796222)
		(stroke
			(width 0)
			(type default)
		)
		(fill no)
		(layer "In6.Cu")
	)
	(gr_rect
		(start 1.005332 -157.28823)
		(end 3.494532 -158.596076)
		(stroke
			(width 0)
			(type default)
		)
		(fill no)
		(layer "In6.Cu")
	)
	(gr_rect
		(start 1.005332 -154.088084)
		(end 3.494532 -155.396184)
		(stroke
			(width 0)
			(type default)
		)
		(fill no)
		(layer "In6.Cu")
	)
	(gr_arc
		(start 4.400042 -421.44188)
		(mid 5.499862 -420.34206)
		(end 4.400042 -419.241986)
		(stroke
			(width 1.524)
			(type default)
		)
		(layer "In6.Cu")
	)
	(gr_line
		(start 4.400042 -419.241986)
		(end 0.500126 -419.241986)
		(stroke
			(width 1.524)
			(type default)
		)
		(layer "In6.Cu")
	)
	(gr_arc
		(start 4.400042 -315.442092)
		(mid 5.500116 -314.342018)
		(end 4.400042 -313.241944)
		(stroke
			(width 1.524)
			(type default)
		)
		(layer "In6.Cu")
	)
	(gr_line
		(start 4.400042 -313.241944)
		(end 0.500126 -313.241944)
		(stroke
			(width 1.524)
			(type default)
		)
		(layer "In6.Cu")
	)
	(gr_arc
		(start 4.400042 -189.44209)
		(mid 5.500116 -188.342016)
		(end 4.400042 -187.241942)
		(stroke
			(width 1.524)
			(type default)
		)
		(layer "In6.Cu")
	)
	(gr_line
		(start 4.400042 -187.241942)
		(end 0.500126 -187.241942)
		(stroke
			(width 1.524)
			(type default)
		)
		(layer "In6.Cu")
	)
	(gr_arc
		(start 4.56946 -445.54775)
		(mid 5.079873 -446.058544)
		(end 5.59054 -445.548004)
		(stroke
			(width 0.2)
			(type default)
		)
		(layer "In6.Cu")
	)
	(gr_line
		(start 4.56946 -444.735204)
		(end 4.56946 -445.54775)
		(stroke
			(width 0.2)
			(type default)
		)
		(layer "In6.Cu")
	)
	(gr_arc
		(start 4.56946 -442.347858)
		(mid 5.079873 -442.858652)
		(end 5.59054 -442.348112)
		(stroke
			(width 0.2)
			(type default)
		)
		(layer "In6.Cu")
	)
	(gr_line
		(start 4.56946 -441.535312)
		(end 4.56946 -442.347858)
		(stroke
			(width 0.2)
			(type default)
		)
		(layer "In6.Cu")
	)
	(gr_arc
		(start 4.56946 -439.147712)
		(mid 5.079873 -439.658506)
		(end 5.59054 -439.147966)
		(stroke
			(width 0.2)
			(type default)
		)
		(layer "In6.Cu")
	)
	(gr_line
		(start 4.56946 -438.335166)
		(end 4.56946 -439.147712)
		(stroke
			(width 0.2)
			(type default)
		)
		(layer "In6.Cu")
	)
	(gr_arc
		(start 4.56946 -435.94782)
		(mid 5.079873 -436.458614)
		(end 5.59054 -435.948074)
		(stroke
			(width 0.2)
			(type default)
		)
		(layer "In6.Cu")
	)
	(gr_line
		(start 4.56946 -435.135274)
		(end 4.56946 -435.94782)
		(stroke
			(width 0.2)
			(type default)
		)
		(layer "In6.Cu")
	)
	(gr_arc
		(start 4.56946 -430.347882)
		(mid 5.08 -430.858422)
		(end 5.59054 -430.347882)
		(stroke
			(width 0.2)
			(type default)
		)
		(layer "In6.Cu")
	)
	(gr_line
		(start 4.56946 -429.535082)
		(end 4.56946 -430.347882)
		(stroke
			(width 0.2)
			(type default)
		)
		(layer "In6.Cu")
	)
	(gr_arc
		(start 4.56946 -427.14799)
		(mid 5.08 -427.65853)
		(end 5.59054 -427.14799)
		(stroke
			(width 0.2)
			(type default)
		)
		(layer "In6.Cu")
	)
	(gr_line
		(start 4.56946 -426.33519)
		(end 4.56946 -427.14799)
		(stroke
			(width 0.2)
			(type default)
		)
		(layer "In6.Cu")
	)
	(gr_arc
		(start 4.56946 -423.948098)
		(mid 5.08 -424.458638)
		(end 5.59054 -423.948098)
		(stroke
			(width 0.2)
			(type default)
		)
		(layer "In6.Cu")
	)
	(gr_line
		(start 4.56946 -423.135298)
		(end 4.56946 -423.948098)
		(stroke
			(width 0.2)
			(type default)
		)
		(layer "In6.Cu")
	)
	(gr_arc
		(start 4.56946 -417.54806)
		(mid 5.08 -418.0586)
		(end 5.59054 -417.54806)
		(stroke
			(width 0.2)
			(type default)
		)
		(layer "In6.Cu")
	)
	(gr_line
		(start 4.56946 -416.73526)
		(end 4.56946 -417.54806)
		(stroke
			(width 0.2)
			(type default)
		)
		(layer "In6.Cu")
	)
	(gr_arc
		(start 4.56946 -414.34766)
		(mid 5.079873 -414.858454)
		(end 5.59054 -414.347914)
		(stroke
			(width 0.2)
			(type default)
		)
		(layer "In6.Cu")
	)
	(gr_line
		(start 4.56946 -413.535114)
		(end 4.56946 -414.34766)
		(stroke
			(width 0.2)
			(type default)
		)
		(layer "In6.Cu")
	)
	(gr_arc
		(start 4.56946 -411.147768)
		(mid 5.079873 -411.658562)
		(end 5.59054 -411.148022)
		(stroke
			(width 0.2)
			(type default)
		)
		(layer "In6.Cu")
	)
	(gr_line
		(start 4.56946 -410.335222)
		(end 4.56946 -411.147768)
		(stroke
			(width 0.2)
			(type default)
		)
		(layer "In6.Cu")
	)
	(gr_arc
		(start 4.56946 -407.947622)
		(mid 5.079873 -408.458416)
		(end 5.59054 -407.947876)
		(stroke
			(width 0.2)
			(type default)
		)
		(layer "In6.Cu")
	)
	(gr_line
		(start 4.56946 -407.135076)
		(end 4.56946 -407.947622)
		(stroke
			(width 0.2)
			(type default)
		)
		(layer "In6.Cu")
	)
	(gr_arc
		(start 4.56946 -404.74773)
		(mid 5.079873 -405.258524)
		(end 5.59054 -404.747984)
		(stroke
			(width 0.2)
			(type default)
		)
		(layer "In6.Cu")
	)
	(gr_line
		(start 4.56946 -403.935184)
		(end 4.56946 -404.74773)
		(stroke
			(width 0.2)
			(type default)
		)
		(layer "In6.Cu")
	)
	(gr_arc
		(start 4.56946 -399.148046)
		(mid 5.08 -399.658586)
		(end 5.59054 -399.148046)
		(stroke
			(width 0.2)
			(type default)
		)
		(layer "In6.Cu")
	)
	(gr_line
		(start 4.56946 -398.335246)
		(end 4.56946 -399.148046)
		(stroke
			(width 0.2)
			(type default)
		)
		(layer "In6.Cu")
	)
	(gr_arc
		(start 4.56946 -395.9479)
		(mid 5.08 -396.45844)
		(end 5.59054 -395.9479)
		(stroke
			(width 0.2)
			(type default)
		)
		(layer "In6.Cu")
	)
	(gr_line
		(start 4.56946 -395.1351)
		(end 4.56946 -395.9479)
		(stroke
			(width 0.2)
			(type default)
		)
		(layer "In6.Cu")
	)
	(gr_arc
		(start 4.56946 -392.748008)
		(mid 5.08 -393.258548)
		(end 5.59054 -392.748008)
		(stroke
			(width 0.2)
			(type default)
		)
		(layer "In6.Cu")
	)
	(gr_line
		(start 4.56946 -391.935208)
		(end 4.56946 -392.748008)
		(stroke
			(width 0.2)
			(type default)
		)
		(layer "In6.Cu")
	)
	(gr_arc
		(start 4.56946 -389.548116)
		(mid 5.08 -390.058656)
		(end 5.59054 -389.548116)
		(stroke
			(width 0.2)
			(type default)
		)
		(layer "In6.Cu")
	)
	(gr_line
		(start 4.56946 -388.735316)
		(end 4.56946 -389.548116)
		(stroke
			(width 0.2)
			(type default)
		)
		(layer "In6.Cu")
	)
	(gr_arc
		(start 4.56946 -358.74833)
		(mid 5.08 -359.25887)
		(end 5.59054 -358.74833)
		(stroke
			(width 0.2)
			(type default)
		)
		(layer "In6.Cu")
	)
	(gr_line
		(start 4.56946 -357.93553)
		(end 4.56946 -358.74833)
		(stroke
			(width 0.2)
			(type default)
		)
		(layer "In6.Cu")
	)
	(gr_arc
		(start 4.56946 -355.548184)
		(mid 5.08 -356.058724)
		(end 5.59054 -355.548184)
		(stroke
			(width 0.2)
			(type default)
		)
		(layer "In6.Cu")
	)
	(gr_line
		(start 4.56946 -354.735384)
		(end 4.56946 -355.548184)
		(stroke
			(width 0.2)
			(type default)
		)
		(layer "In6.Cu")
	)
	(gr_arc
		(start 4.56946 -352.348292)
		(mid 5.08 -352.858832)
		(end 5.59054 -352.348292)
		(stroke
			(width 0.2)
			(type default)
		)
		(layer "In6.Cu")
	)
	(gr_line
		(start 4.56946 -351.535492)
		(end 4.56946 -352.348292)
		(stroke
			(width 0.2)
			(type default)
		)
		(layer "In6.Cu")
	)
	(gr_arc
		(start 4.56946 -349.148146)
		(mid 5.08 -349.658686)
		(end 5.59054 -349.148146)
		(stroke
			(width 0.2)
			(type default)
		)
		(layer "In6.Cu")
	)
	(gr_line
		(start 4.56946 -348.335346)
		(end 4.56946 -349.148146)
		(stroke
			(width 0.2)
			(type default)
		)
		(layer "In6.Cu")
	)
	(gr_arc
		(start 4.56946 -345.948254)
		(mid 5.08 -346.458794)
		(end 5.59054 -345.948254)
		(stroke
			(width 0.2)
			(type default)
		)
		(layer "In6.Cu")
	)
	(gr_line
		(start 4.56946 -345.135454)
		(end 4.56946 -345.948254)
		(stroke
			(width 0.2)
			(type default)
		)
		(layer "In6.Cu")
	)
	(gr_arc
		(start 4.56946 -342.748108)
		(mid 5.08 -343.258648)
		(end 5.59054 -342.748108)
		(stroke
			(width 0.2)
			(type default)
		)
		(layer "In6.Cu")
	)
	(gr_line
		(start 4.56946 -341.935308)
		(end 4.56946 -342.748108)
		(stroke
			(width 0.2)
			(type default)
		)
		(layer "In6.Cu")
	)
	(gr_arc
		(start 4.56946 -339.548216)
		(mid 5.08 -340.058756)
		(end 5.59054 -339.548216)
		(stroke
			(width 0.2)
			(type default)
		)
		(layer "In6.Cu")
	)
	(gr_line
		(start 4.56946 -338.735416)
		(end 4.56946 -339.548216)
		(stroke
			(width 0.2)
			(type default)
		)
		(layer "In6.Cu")
	)
	(gr_arc
		(start 4.56946 -336.348324)
		(mid 5.08 -336.858864)
		(end 5.59054 -336.348324)
		(stroke
			(width 0.2)
			(type default)
		)
		(layer "In6.Cu")
	)
	(gr_line
		(start 4.56946 -335.535524)
		(end 4.56946 -336.348324)
		(stroke
			(width 0.2)
			(type default)
		)
		(layer "In6.Cu")
	)
	(gr_arc
		(start 4.56946 -330.748132)
		(mid 5.08 -331.258672)
		(end 5.59054 -330.748132)
		(stroke
			(width 0.2)
			(type default)
		)
		(layer "In6.Cu")
	)
	(gr_line
		(start 4.56946 -329.935332)
		(end 4.56946 -330.748132)
		(stroke
			(width 0.2)
			(type default)
		)
		(layer "In6.Cu")
	)
	(gr_arc
		(start 4.56946 -327.54824)
		(mid 5.08 -328.05878)
		(end 5.59054 -327.54824)
		(stroke
			(width 0.2)
			(type default)
		)
		(layer "In6.Cu")
	)
	(gr_line
		(start 4.56946 -326.73544)
		(end 4.56946 -327.54824)
		(stroke
			(width 0.2)
			(type default)
		)
		(layer "In6.Cu")
	)
	(gr_arc
		(start 4.56946 -324.348094)
		(mid 5.08 -324.858634)
		(end 5.59054 -324.348094)
		(stroke
			(width 0.2)
			(type default)
		)
		(layer "In6.Cu")
	)
	(gr_line
		(start 4.56946 -323.535294)
		(end 4.56946 -324.348094)
		(stroke
			(width 0.2)
			(type default)
		)
		(layer "In6.Cu")
	)
	(gr_arc
		(start 4.56946 -321.148202)
		(mid 5.08 -321.658742)
		(end 5.59054 -321.148202)
		(stroke
			(width 0.2)
			(type default)
		)
		(layer "In6.Cu")
	)
	(gr_line
		(start 4.56946 -320.335402)
		(end 4.56946 -321.148202)
		(stroke
			(width 0.2)
			(type default)
		)
		(layer "In6.Cu")
	)
	(gr_arc
		(start 4.56946 -317.94831)
		(mid 5.08 -318.45885)
		(end 5.59054 -317.94831)
		(stroke
			(width 0.2)
			(type default)
		)
		(layer "In6.Cu")
	)
	(gr_line
		(start 4.56946 -317.13551)
		(end 4.56946 -317.94831)
		(stroke
			(width 0.2)
			(type default)
		)
		(layer "In6.Cu")
	)
	(gr_arc
		(start 4.56946 -309.948326)
		(mid 5.08 -310.458866)
		(end 5.59054 -309.948326)
		(stroke
			(width 0.2)
			(type default)
		)
		(layer "In6.Cu")
	)
	(gr_line
		(start 4.56946 -309.135526)
		(end 4.56946 -309.948326)
		(stroke
			(width 0.2)
			(type default)
		)
		(layer "In6.Cu")
	)
	(gr_arc
		(start 4.56946 -306.74818)
		(mid 5.08 -307.25872)
		(end 5.59054 -306.74818)
		(stroke
			(width 0.2)
			(type default)
		)
		(layer "In6.Cu")
	)
	(gr_line
		(start 4.56946 -305.93538)
		(end 4.56946 -306.74818)
		(stroke
			(width 0.2)
			(type default)
		)
		(layer "In6.Cu")
	)
	(gr_arc
		(start 4.56946 -303.548288)
		(mid 5.08 -304.058828)
		(end 5.59054 -303.548288)
		(stroke
			(width 0.2)
			(type default)
		)
		(layer "In6.Cu")
	)
	(gr_line
		(start 4.56946 -302.735488)
		(end 4.56946 -303.548288)
		(stroke
			(width 0.2)
			(type default)
		)
		(layer "In6.Cu")
	)
	(gr_arc
		(start 4.56946 -300.348142)
		(mid 5.08 -300.858682)
		(end 5.59054 -300.348142)
		(stroke
			(width 0.2)
			(type default)
		)
		(layer "In6.Cu")
	)
	(gr_line
		(start 4.56946 -299.535342)
		(end 4.56946 -300.348142)
		(stroke
			(width 0.2)
			(type default)
		)
		(layer "In6.Cu")
	)
	(gr_arc
		(start 4.56946 -297.14825)
		(mid 5.08 -297.65879)
		(end 5.59054 -297.14825)
		(stroke
			(width 0.2)
			(type default)
		)
		(layer "In6.Cu")
	)
	(gr_line
		(start 4.56946 -296.33545)
		(end 4.56946 -297.14825)
		(stroke
			(width 0.2)
			(type default)
		)
		(layer "In6.Cu")
	)
	(gr_arc
		(start 4.56946 -293.948104)
		(mid 5.08 -294.458644)
		(end 5.59054 -293.948104)
		(stroke
			(width 0.2)
			(type default)
		)
		(layer "In6.Cu")
	)
	(gr_line
		(start 4.56946 -293.135304)
		(end 4.56946 -293.948104)
		(stroke
			(width 0.2)
			(type default)
		)
		(layer "In6.Cu")
	)
	(gr_arc
		(start 4.56946 -290.748212)
		(mid 5.08 -291.258752)
		(end 5.59054 -290.748212)
		(stroke
			(width 0.2)
			(type default)
		)
		(layer "In6.Cu")
	)
	(gr_line
		(start 4.56946 -289.935412)
		(end 4.56946 -290.748212)
		(stroke
			(width 0.2)
			(type default)
		)
		(layer "In6.Cu")
	)
	(gr_arc
		(start 4.56946 -284.348174)
		(mid 5.08 -284.858714)
		(end 5.59054 -284.348174)
		(stroke
			(width 0.2)
			(type default)
		)
		(layer "In6.Cu")
	)
	(gr_line
		(start 4.56946 -283.535374)
		(end 4.56946 -284.348174)
		(stroke
			(width 0.2)
			(type default)
		)
		(layer "In6.Cu")
	)
	(gr_arc
		(start 4.56946 -281.148282)
		(mid 5.08 -281.658822)
		(end 5.59054 -281.148282)
		(stroke
			(width 0.2)
			(type default)
		)
		(layer "In6.Cu")
	)
	(gr_line
		(start 4.56946 -280.335482)
		(end 4.56946 -281.148282)
		(stroke
			(width 0.2)
			(type default)
		)
		(layer "In6.Cu")
	)
	(gr_arc
		(start 4.56946 -232.748328)
		(mid 5.08 -233.258868)
		(end 5.59054 -232.748328)
		(stroke
			(width 0.2)
			(type default)
		)
		(layer "In6.Cu")
	)
	(gr_line
		(start 4.56946 -231.935528)
		(end 4.56946 -232.748328)
		(stroke
			(width 0.2)
			(type default)
		)
		(layer "In6.Cu")
	)
	(gr_arc
		(start 4.56946 -229.548182)
		(mid 5.08 -230.058722)
		(end 5.59054 -229.548182)
		(stroke
			(width 0.2)
			(type default)
		)
		(layer "In6.Cu")
	)
	(gr_line
		(start 4.56946 -228.735382)
		(end 4.56946 -229.548182)
		(stroke
			(width 0.2)
			(type default)
		)
		(layer "In6.Cu")
	)
	(gr_arc
		(start 4.56946 -223.148144)
		(mid 5.08 -223.658684)
		(end 5.59054 -223.148144)
		(stroke
			(width 0.2)
			(type default)
		)
		(layer "In6.Cu")
	)
	(gr_line
		(start 4.56946 -222.335344)
		(end 4.56946 -223.148144)
		(stroke
			(width 0.2)
			(type default)
		)
		(layer "In6.Cu")
	)
	(gr_arc
		(start 4.56946 -219.948252)
		(mid 5.08 -220.458792)
		(end 5.59054 -219.948252)
		(stroke
			(width 0.2)
			(type default)
		)
		(layer "In6.Cu")
	)
	(gr_line
		(start 4.56946 -219.135452)
		(end 4.56946 -219.948252)
		(stroke
			(width 0.2)
			(type default)
		)
		(layer "In6.Cu")
	)
	(gr_arc
		(start 4.56946 -216.748106)
		(mid 5.08 -217.258646)
		(end 5.59054 -216.748106)
		(stroke
			(width 0.2)
			(type default)
		)
		(layer "In6.Cu")
	)
	(gr_line
		(start 4.56946 -215.935306)
		(end 4.56946 -216.748106)
		(stroke
			(width 0.2)
			(type default)
		)
		(layer "In6.Cu")
	)
	(gr_arc
		(start 4.56946 -213.548214)
		(mid 5.08 -214.058754)
		(end 5.59054 -213.548214)
		(stroke
			(width 0.2)
			(type default)
		)
		(layer "In6.Cu")
	)
	(gr_line
		(start 4.56946 -212.735414)
		(end 4.56946 -213.548214)
		(stroke
			(width 0.2)
			(type default)
		)
		(layer "In6.Cu")
	)
	(gr_arc
		(start 4.56946 -210.348322)
		(mid 5.08 -210.858862)
		(end 5.59054 -210.348322)
		(stroke
			(width 0.2)
			(type default)
		)
		(layer "In6.Cu")
	)
	(gr_line
		(start 4.56946 -209.535522)
		(end 4.56946 -210.348322)
		(stroke
			(width 0.2)
			(type default)
		)
		(layer "In6.Cu")
	)
	(gr_arc
		(start 4.56946 -207.148176)
		(mid 5.08 -207.658716)
		(end 5.59054 -207.148176)
		(stroke
			(width 0.2)
			(type default)
		)
		(layer "In6.Cu")
	)
	(gr_line
		(start 4.56946 -206.335376)
		(end 4.56946 -207.148176)
		(stroke
			(width 0.2)
			(type default)
		)
		(layer "In6.Cu")
	)
	(gr_arc
		(start 4.56946 -203.948284)
		(mid 5.08 -204.458824)
		(end 5.59054 -203.948284)
		(stroke
			(width 0.2)
			(type default)
		)
		(layer "In6.Cu")
	)
	(gr_line
		(start 4.56946 -203.135484)
		(end 4.56946 -203.948284)
		(stroke
			(width 0.2)
			(type default)
		)
		(layer "In6.Cu")
	)
	(gr_arc
		(start 4.56946 -200.748138)
		(mid 5.08 -201.258678)
		(end 5.59054 -200.748138)
		(stroke
			(width 0.2)
			(type default)
		)
		(layer "In6.Cu")
	)
	(gr_line
		(start 4.56946 -199.935338)
		(end 4.56946 -200.748138)
		(stroke
			(width 0.2)
			(type default)
		)
		(layer "In6.Cu")
	)
	(gr_arc
		(start 4.56946 -195.1482)
		(mid 5.08 -195.65874)
		(end 5.59054 -195.1482)
		(stroke
			(width 0.2)
			(type default)
		)
		(layer "In6.Cu")
	)
	(gr_line
		(start 4.56946 -194.3354)
		(end 4.56946 -195.1482)
		(stroke
			(width 0.2)
			(type default)
		)
		(layer "In6.Cu")
	)
	(gr_arc
		(start 4.56946 -191.948308)
		(mid 5.08 -192.458848)
		(end 5.59054 -191.948308)
		(stroke
			(width 0.2)
			(type default)
		)
		(layer "In6.Cu")
	)
	(gr_line
		(start 4.56946 -191.135508)
		(end 4.56946 -191.948308)
		(stroke
			(width 0.2)
			(type default)
		)
		(layer "In6.Cu")
	)
	(gr_arc
		(start 4.56946 -183.948324)
		(mid 5.08 -184.458864)
		(end 5.59054 -183.948324)
		(stroke
			(width 0.2)
			(type default)
		)
		(layer "In6.Cu")
	)
	(gr_line
		(start 4.56946 -183.135524)
		(end 4.56946 -183.948324)
		(stroke
			(width 0.2)
			(type default)
		)
		(layer "In6.Cu")
	)
	(gr_arc
		(start 4.56946 -180.748178)
		(mid 5.08 -181.258718)
		(end 5.59054 -180.748178)
		(stroke
			(width 0.2)
			(type default)
		)
		(layer "In6.Cu")
	)
	(gr_line
		(start 4.56946 -179.935378)
		(end 4.56946 -180.748178)
		(stroke
			(width 0.2)
			(type default)
		)
		(layer "In6.Cu")
	)
	(gr_arc
		(start 4.56946 -177.548286)
		(mid 5.08 -178.058826)
		(end 5.59054 -177.548286)
		(stroke
			(width 0.2)
			(type default)
		)
		(layer "In6.Cu")
	)
	(gr_line
		(start 4.56946 -176.735486)
		(end 4.56946 -177.548286)
		(stroke
			(width 0.2)
			(type default)
		)
		(layer "In6.Cu")
	)
	(gr_arc
		(start 4.56946 -174.34814)
		(mid 5.08 -174.85868)
		(end 5.59054 -174.34814)
		(stroke
			(width 0.2)
			(type default)
		)
		(layer "In6.Cu")
	)
	(gr_line
		(start 4.56946 -173.53534)
		(end 4.56946 -174.34814)
		(stroke
			(width 0.2)
			(type default)
		)
		(layer "In6.Cu")
	)
	(gr_arc
		(start 4.56946 -171.148248)
		(mid 5.08 -171.658788)
		(end 5.59054 -171.148248)
		(stroke
			(width 0.2)
			(type default)
		)
		(layer "In6.Cu")
	)
	(gr_line
		(start 4.56946 -170.335448)
		(end 4.56946 -171.148248)
		(stroke
			(width 0.2)
			(type default)
		)
		(layer "In6.Cu")
	)
	(gr_arc
		(start 4.56946 -167.948102)
		(mid 5.08 -168.458642)
		(end 5.59054 -167.948102)
		(stroke
			(width 0.2)
			(type default)
		)
		(layer "In6.Cu")
	)
	(gr_line
		(start 4.56946 -167.135302)
		(end 4.56946 -167.948102)
		(stroke
			(width 0.2)
			(type default)
		)
		(layer "In6.Cu")
	)
	(gr_arc
		(start 4.56946 -164.74821)
		(mid 5.08 -165.25875)
		(end 5.59054 -164.74821)
		(stroke
			(width 0.2)
			(type default)
		)
		(layer "In6.Cu")
	)
	(gr_line
		(start 4.56946 -163.93541)
		(end 4.56946 -164.74821)
		(stroke
			(width 0.2)
			(type default)
		)
		(layer "In6.Cu")
	)
	(gr_arc
		(start 4.56946 -161.548318)
		(mid 5.08 -162.058858)
		(end 5.59054 -161.548318)
		(stroke
			(width 0.2)
			(type default)
		)
		(layer "In6.Cu")
	)
	(gr_line
		(start 4.56946 -160.735518)
		(end 4.56946 -161.548318)
		(stroke
			(width 0.2)
			(type default)
		)
		(layer "In6.Cu")
	)
	(gr_arc
		(start 4.56946 -158.348172)
		(mid 5.08 -158.858712)
		(end 5.59054 -158.348172)
		(stroke
			(width 0.2)
			(type default)
		)
		(layer "In6.Cu")
	)
	(gr_line
		(start 4.56946 -157.535372)
		(end 4.56946 -158.348172)
		(stroke
			(width 0.2)
			(type default)
		)
		(layer "In6.Cu")
	)
	(gr_arc
		(start 4.56946 -155.14828)
		(mid 5.08 -155.65882)
		(end 5.59054 -155.14828)
		(stroke
			(width 0.2)
			(type default)
		)
		(layer "In6.Cu")
	)
	(gr_line
		(start 4.56946 -154.33548)
		(end 4.56946 -155.14828)
		(stroke
			(width 0.2)
			(type default)
		)
		(layer "In6.Cu")
	)
	(gr_line
		(start 5.59054 -445.548004)
		(end 5.59054 -444.735204)
		(stroke
			(width 0.2)
			(type default)
		)
		(layer "In6.Cu")
	)
	(gr_arc
		(start 5.59054 -444.735204)
		(mid 5.08 -444.224664)
		(end 4.56946 -444.735204)
		(stroke
			(width 0.2)
			(type default)
		)
		(layer "In6.Cu")
	)
	(gr_line
		(start 5.59054 -442.348112)
		(end 5.59054 -441.535312)
		(stroke
			(width 0.2)
			(type default)
		)
		(layer "In6.Cu")
	)
	(gr_arc
		(start 5.59054 -441.535312)
		(mid 5.08 -441.024772)
		(end 4.56946 -441.535312)
		(stroke
			(width 0.2)
			(type default)
		)
		(layer "In6.Cu")
	)
	(gr_line
		(start 5.59054 -439.147966)
		(end 5.59054 -438.335166)
		(stroke
			(width 0.2)
			(type default)
		)
		(layer "In6.Cu")
	)
	(gr_arc
		(start 5.59054 -438.335166)
		(mid 5.08 -437.824626)
		(end 4.56946 -438.335166)
		(stroke
			(width 0.2)
			(type default)
		)
		(layer "In6.Cu")
	)
	(gr_line
		(start 5.59054 -435.948074)
		(end 5.59054 -435.135274)
		(stroke
			(width 0.2)
			(type default)
		)
		(layer "In6.Cu")
	)
	(gr_arc
		(start 5.59054 -435.135274)
		(mid 5.08 -434.624734)
		(end 4.56946 -435.135274)
		(stroke
			(width 0.2)
			(type default)
		)
		(layer "In6.Cu")
	)
	(gr_line
		(start 5.59054 -430.347882)
		(end 5.59054 -429.535336)
		(stroke
			(width 0.2)
			(type default)
		)
		(layer "In6.Cu")
	)
	(gr_arc
		(start 5.59054 -429.535336)
		(mid 5.080127 -429.024542)
		(end 4.56946 -429.535082)
		(stroke
			(width 0.2)
			(type default)
		)
		(layer "In6.Cu")
	)
	(gr_line
		(start 5.59054 -427.14799)
		(end 5.59054 -426.335444)
		(stroke
			(width 0.2)
			(type default)
		)
		(layer "In6.Cu")
	)
	(gr_arc
		(start 5.59054 -426.335444)
		(mid 5.080127 -425.82465)
		(end 4.56946 -426.33519)
		(stroke
			(width 0.2)
			(type default)
		)
		(layer "In6.Cu")
	)
	(gr_line
		(start 5.59054 -423.948098)
		(end 5.59054 -423.135552)
		(stroke
			(width 0.2)
			(type default)
		)
		(layer "In6.Cu")
	)
	(gr_arc
		(start 5.59054 -423.135552)
		(mid 5.080127 -422.624758)
		(end 4.56946 -423.135298)
		(stroke
			(width 0.2)
			(type default)
		)
		(layer "In6.Cu")
	)
	(gr_line
		(start 5.59054 -417.54806)
		(end 5.59054 -416.735514)
		(stroke
			(width 0.2)
			(type default)
		)
		(layer "In6.Cu")
	)
	(gr_arc
		(start 5.59054 -416.735514)
		(mid 5.080127 -416.22472)
		(end 4.56946 -416.73526)
		(stroke
			(width 0.2)
			(type default)
		)
		(layer "In6.Cu")
	)
	(gr_line
		(start 5.59054 -414.347914)
		(end 5.59054 -413.535114)
		(stroke
			(width 0.2)
			(type default)
		)
		(layer "In6.Cu")
	)
	(gr_arc
		(start 5.59054 -413.535114)
		(mid 5.08 -413.024574)
		(end 4.56946 -413.535114)
		(stroke
			(width 0.2)
			(type default)
		)
		(layer "In6.Cu")
	)
	(gr_line
		(start 5.59054 -411.148022)
		(end 5.59054 -410.335222)
		(stroke
			(width 0.2)
			(type default)
		)
		(layer "In6.Cu")
	)
	(gr_arc
		(start 5.59054 -410.335222)
		(mid 5.08 -409.824682)
		(end 4.56946 -410.335222)
		(stroke
			(width 0.2)
			(type default)
		)
		(layer "In6.Cu")
	)
	(gr_line
		(start 5.59054 -407.947876)
		(end 5.59054 -407.135076)
		(stroke
			(width 0.2)
			(type default)
		)
		(layer "In6.Cu")
	)
	(gr_arc
		(start 5.59054 -407.135076)
		(mid 5.08 -406.624536)
		(end 4.56946 -407.135076)
		(stroke
			(width 0.2)
			(type default)
		)
		(layer "In6.Cu")
	)
	(gr_line
		(start 5.59054 -404.747984)
		(end 5.59054 -403.935184)
		(stroke
			(width 0.2)
			(type default)
		)
		(layer "In6.Cu")
	)
	(gr_arc
		(start 5.59054 -403.935184)
		(mid 5.08 -403.424644)
		(end 4.56946 -403.935184)
		(stroke
			(width 0.2)
			(type default)
		)
		(layer "In6.Cu")
	)
	(gr_line
		(start 5.59054 -399.148046)
		(end 5.59054 -398.3355)
		(stroke
			(width 0.2)
			(type default)
		)
		(layer "In6.Cu")
	)
	(gr_arc
		(start 5.59054 -398.3355)
		(mid 5.080127 -397.824706)
		(end 4.56946 -398.335246)
		(stroke
			(width 0.2)
			(type default)
		)
		(layer "In6.Cu")
	)
	(gr_line
		(start 5.59054 -395.9479)
		(end 5.59054 -395.135354)
		(stroke
			(width 0.2)
			(type default)
		)
		(layer "In6.Cu")
	)
	(gr_arc
		(start 5.59054 -395.135354)
		(mid 5.080127 -394.62456)
		(end 4.56946 -395.1351)
		(stroke
			(width 0.2)
			(type default)
		)
		(layer "In6.Cu")
	)
	(gr_line
		(start 5.59054 -392.748008)
		(end 5.59054 -391.935462)
		(stroke
			(width 0.2)
			(type default)
		)
		(layer "In6.Cu")
	)
	(gr_arc
		(start 5.59054 -391.935462)
		(mid 5.080127 -391.424668)
		(end 4.56946 -391.935208)
		(stroke
			(width 0.2)
			(type default)
		)
		(layer "In6.Cu")
	)
	(gr_line
		(start 5.59054 -389.548116)
		(end 5.59054 -388.73557)
		(stroke
			(width 0.2)
			(type default)
		)
		(layer "In6.Cu")
	)
	(gr_arc
		(start 5.59054 -388.73557)
		(mid 5.080127 -388.224776)
		(end 4.56946 -388.735316)
		(stroke
			(width 0.2)
			(type default)
		)
		(layer "In6.Cu")
	)
	(gr_line
		(start 5.59054 -358.74833)
		(end 5.59054 -357.935784)
		(stroke
			(width 0.2)
			(type default)
		)
		(layer "In6.Cu")
	)
	(gr_arc
		(start 5.59054 -357.935784)
		(mid 5.080127 -357.42499)
		(end 4.56946 -357.93553)
		(stroke
			(width 0.2)
			(type default)
		)
		(layer "In6.Cu")
	)
	(gr_line
		(start 5.59054 -355.548184)
		(end 5.59054 -354.735638)
		(stroke
			(width 0.2)
			(type default)
		)
		(layer "In6.Cu")
	)
	(gr_arc
		(start 5.59054 -354.735638)
		(mid 5.080127 -354.224844)
		(end 4.56946 -354.735384)
		(stroke
			(width 0.2)
			(type default)
		)
		(layer "In6.Cu")
	)
	(gr_line
		(start 5.59054 -352.348292)
		(end 5.59054 -351.535746)
		(stroke
			(width 0.2)
			(type default)
		)
		(layer "In6.Cu")
	)
	(gr_arc
		(start 5.59054 -351.535746)
		(mid 5.080127 -351.024952)
		(end 4.56946 -351.535492)
		(stroke
			(width 0.2)
			(type default)
		)
		(layer "In6.Cu")
	)
	(gr_line
		(start 5.59054 -349.148146)
		(end 5.59054 -348.3356)
		(stroke
			(width 0.2)
			(type default)
		)
		(layer "In6.Cu")
	)
	(gr_arc
		(start 5.59054 -348.3356)
		(mid 5.080127 -347.824806)
		(end 4.56946 -348.335346)
		(stroke
			(width 0.2)
			(type default)
		)
		(layer "In6.Cu")
	)
	(gr_line
		(start 5.59054 -345.948254)
		(end 5.59054 -345.135708)
		(stroke
			(width 0.2)
			(type default)
		)
		(layer "In6.Cu")
	)
	(gr_arc
		(start 5.59054 -345.135708)
		(mid 5.080127 -344.624914)
		(end 4.56946 -345.135454)
		(stroke
			(width 0.2)
			(type default)
		)
		(layer "In6.Cu")
	)
	(gr_line
		(start 5.59054 -342.748108)
		(end 5.59054 -341.935562)
		(stroke
			(width 0.2)
			(type default)
		)
		(layer "In6.Cu")
	)
	(gr_arc
		(start 5.59054 -341.935562)
		(mid 5.080127 -341.424768)
		(end 4.56946 -341.935308)
		(stroke
			(width 0.2)
			(type default)
		)
		(layer "In6.Cu")
	)
	(gr_line
		(start 5.59054 -339.548216)
		(end 5.59054 -338.73567)
		(stroke
			(width 0.2)
			(type default)
		)
		(layer "In6.Cu")
	)
	(gr_arc
		(start 5.59054 -338.73567)
		(mid 5.080127 -338.224876)
		(end 4.56946 -338.735416)
		(stroke
			(width 0.2)
			(type default)
		)
		(layer "In6.Cu")
	)
	(gr_line
		(start 5.59054 -336.348324)
		(end 5.59054 -335.535778)
		(stroke
			(width 0.2)
			(type default)
		)
		(layer "In6.Cu")
	)
	(gr_arc
		(start 5.59054 -335.535778)
		(mid 5.080127 -335.024984)
		(end 4.56946 -335.535524)
		(stroke
			(width 0.2)
			(type default)
		)
		(layer "In6.Cu")
	)
	(gr_line
		(start 5.59054 -330.748132)
		(end 5.59054 -329.935586)
		(stroke
			(width 0.2)
			(type default)
		)
		(layer "In6.Cu")
	)
	(gr_arc
		(start 5.59054 -329.935586)
		(mid 5.080127 -329.424792)
		(end 4.56946 -329.935332)
		(stroke
			(width 0.2)
			(type default)
		)
		(layer "In6.Cu")
	)
	(gr_line
		(start 5.59054 -327.54824)
		(end 5.59054 -326.735694)
		(stroke
			(width 0.2)
			(type default)
		)
		(layer "In6.Cu")
	)
	(gr_arc
		(start 5.59054 -326.735694)
		(mid 5.080127 -326.2249)
		(end 4.56946 -326.73544)
		(stroke
			(width 0.2)
			(type default)
		)
		(layer "In6.Cu")
	)
	(gr_line
		(start 5.59054 -324.348094)
		(end 5.59054 -323.535548)
		(stroke
			(width 0.2)
			(type default)
		)
		(layer "In6.Cu")
	)
	(gr_arc
		(start 5.59054 -323.535548)
		(mid 5.080127 -323.024754)
		(end 4.56946 -323.535294)
		(stroke
			(width 0.2)
			(type default)
		)
		(layer "In6.Cu")
	)
	(gr_line
		(start 5.59054 -321.148202)
		(end 5.59054 -320.335656)
		(stroke
			(width 0.2)
			(type default)
		)
		(layer "In6.Cu")
	)
	(gr_arc
		(start 5.59054 -320.335656)
		(mid 5.080127 -319.824862)
		(end 4.56946 -320.335402)
		(stroke
			(width 0.2)
			(type default)
		)
		(layer "In6.Cu")
	)
	(gr_line
		(start 5.59054 -317.94831)
		(end 5.59054 -317.135764)
		(stroke
			(width 0.2)
			(type default)
		)
		(layer "In6.Cu")
	)
	(gr_arc
		(start 5.59054 -317.135764)
		(mid 5.080127 -316.62497)
		(end 4.56946 -317.13551)
		(stroke
			(width 0.2)
			(type default)
		)
		(layer "In6.Cu")
	)
	(gr_line
		(start 5.59054 -309.948326)
		(end 5.59054 -309.13578)
		(stroke
			(width 0.2)
			(type default)
		)
		(layer "In6.Cu")
	)
	(gr_arc
		(start 5.59054 -309.13578)
		(mid 5.080127 -308.624986)
		(end 4.56946 -309.135526)
		(stroke
			(width 0.2)
			(type default)
		)
		(layer "In6.Cu")
	)
	(gr_line
		(start 5.59054 -306.74818)
		(end 5.59054 -305.935634)
		(stroke
			(width 0.2)
			(type default)
		)
		(layer "In6.Cu")
	)
	(gr_arc
		(start 5.59054 -305.935634)
		(mid 5.080127 -305.42484)
		(end 4.56946 -305.93538)
		(stroke
			(width 0.2)
			(type default)
		)
		(layer "In6.Cu")
	)
	(gr_line
		(start 5.59054 -303.548288)
		(end 5.59054 -302.735742)
		(stroke
			(width 0.2)
			(type default)
		)
		(layer "In6.Cu")
	)
	(gr_arc
		(start 5.59054 -302.735742)
		(mid 5.080127 -302.224948)
		(end 4.56946 -302.735488)
		(stroke
			(width 0.2)
			(type default)
		)
		(layer "In6.Cu")
	)
	(gr_line
		(start 5.59054 -300.348142)
		(end 5.59054 -299.535596)
		(stroke
			(width 0.2)
			(type default)
		)
		(layer "In6.Cu")
	)
	(gr_arc
		(start 5.59054 -299.535596)
		(mid 5.080127 -299.024802)
		(end 4.56946 -299.535342)
		(stroke
			(width 0.2)
			(type default)
		)
		(layer "In6.Cu")
	)
	(gr_line
		(start 5.59054 -297.14825)
		(end 5.59054 -296.335704)
		(stroke
			(width 0.2)
			(type default)
		)
		(layer "In6.Cu")
	)
	(gr_arc
		(start 5.59054 -296.335704)
		(mid 5.080127 -295.82491)
		(end 4.56946 -296.33545)
		(stroke
			(width 0.2)
			(type default)
		)
		(layer "In6.Cu")
	)
	(gr_line
		(start 5.59054 -293.948104)
		(end 5.59054 -293.135558)
		(stroke
			(width 0.2)
			(type default)
		)
		(layer "In6.Cu")
	)
	(gr_arc
		(start 5.59054 -293.135558)
		(mid 5.080127 -292.624764)
		(end 4.56946 -293.135304)
		(stroke
			(width 0.2)
			(type default)
		)
		(layer "In6.Cu")
	)
	(gr_line
		(start 5.59054 -290.748212)
		(end 5.59054 -289.935666)
		(stroke
			(width 0.2)
			(type default)
		)
		(layer "In6.Cu")
	)
	(gr_arc
		(start 5.59054 -289.935666)
		(mid 5.080127 -289.424872)
		(end 4.56946 -289.935412)
		(stroke
			(width 0.2)
			(type default)
		)
		(layer "In6.Cu")
	)
	(gr_line
		(start 5.59054 -284.348174)
		(end 5.59054 -283.535628)
		(stroke
			(width 0.2)
			(type default)
		)
		(layer "In6.Cu")
	)
	(gr_arc
		(start 5.59054 -283.535628)
		(mid 5.080127 -283.024834)
		(end 4.56946 -283.535374)
		(stroke
			(width 0.2)
			(type default)
		)
		(layer "In6.Cu")
	)
	(gr_line
		(start 5.59054 -281.148282)
		(end 5.59054 -280.335736)
		(stroke
			(width 0.2)
			(type default)
		)
		(layer "In6.Cu")
	)
	(gr_arc
		(start 5.59054 -280.335736)
		(mid 5.080127 -279.824942)
		(end 4.56946 -280.335482)
		(stroke
			(width 0.2)
			(type default)
		)
		(layer "In6.Cu")
	)
	(gr_line
		(start 5.59054 -232.748328)
		(end 5.59054 -231.935782)
		(stroke
			(width 0.2)
			(type default)
		)
		(layer "In6.Cu")
	)
	(gr_arc
		(start 5.59054 -231.935782)
		(mid 5.080127 -231.424988)
		(end 4.56946 -231.935528)
		(stroke
			(width 0.2)
			(type default)
		)
		(layer "In6.Cu")
	)
	(gr_line
		(start 5.59054 -229.548182)
		(end 5.59054 -228.735636)
		(stroke
			(width 0.2)
			(type default)
		)
		(layer "In6.Cu")
	)
	(gr_arc
		(start 5.59054 -228.735636)
		(mid 5.080127 -228.224842)
		(end 4.56946 -228.735382)
		(stroke
			(width 0.2)
			(type default)
		)
		(layer "In6.Cu")
	)
	(gr_line
		(start 5.59054 -223.148144)
		(end 5.59054 -222.335598)
		(stroke
			(width 0.2)
			(type default)
		)
		(layer "In6.Cu")
	)
	(gr_arc
		(start 5.59054 -222.335598)
		(mid 5.080127 -221.824804)
		(end 4.56946 -222.335344)
		(stroke
			(width 0.2)
			(type default)
		)
		(layer "In6.Cu")
	)
	(gr_line
		(start 5.59054 -219.948252)
		(end 5.59054 -219.135706)
		(stroke
			(width 0.2)
			(type default)
		)
		(layer "In6.Cu")
	)
	(gr_arc
		(start 5.59054 -219.135706)
		(mid 5.080127 -218.624912)
		(end 4.56946 -219.135452)
		(stroke
			(width 0.2)
			(type default)
		)
		(layer "In6.Cu")
	)
	(gr_line
		(start 5.59054 -216.748106)
		(end 5.59054 -215.93556)
		(stroke
			(width 0.2)
			(type default)
		)
		(layer "In6.Cu")
	)
	(gr_arc
		(start 5.59054 -215.93556)
		(mid 5.080127 -215.424766)
		(end 4.56946 -215.935306)
		(stroke
			(width 0.2)
			(type default)
		)
		(layer "In6.Cu")
	)
	(gr_line
		(start 5.59054 -213.548214)
		(end 5.59054 -212.735668)
		(stroke
			(width 0.2)
			(type default)
		)
		(layer "In6.Cu")
	)
	(gr_arc
		(start 5.59054 -212.735668)
		(mid 5.080127 -212.224874)
		(end 4.56946 -212.735414)
		(stroke
			(width 0.2)
			(type default)
		)
		(layer "In6.Cu")
	)
	(gr_line
		(start 5.59054 -210.348322)
		(end 5.59054 -209.535776)
		(stroke
			(width 0.2)
			(type default)
		)
		(layer "In6.Cu")
	)
	(gr_arc
		(start 5.59054 -209.535776)
		(mid 5.080127 -209.024982)
		(end 4.56946 -209.535522)
		(stroke
			(width 0.2)
			(type default)
		)
		(layer "In6.Cu")
	)
	(gr_line
		(start 5.59054 -207.148176)
		(end 5.59054 -206.33563)
		(stroke
			(width 0.2)
			(type default)
		)
		(layer "In6.Cu")
	)
	(gr_arc
		(start 5.59054 -206.33563)
		(mid 5.080127 -205.824836)
		(end 4.56946 -206.335376)
		(stroke
			(width 0.2)
			(type default)
		)
		(layer "In6.Cu")
	)
	(gr_line
		(start 5.59054 -203.948284)
		(end 5.59054 -203.135738)
		(stroke
			(width 0.2)
			(type default)
		)
		(layer "In6.Cu")
	)
	(gr_arc
		(start 5.59054 -203.135738)
		(mid 5.080127 -202.624944)
		(end 4.56946 -203.135484)
		(stroke
			(width 0.2)
			(type default)
		)
		(layer "In6.Cu")
	)
	(gr_line
		(start 5.59054 -200.748138)
		(end 5.59054 -199.935592)
		(stroke
			(width 0.2)
			(type default)
		)
		(layer "In6.Cu")
	)
	(gr_arc
		(start 5.59054 -199.935592)
		(mid 5.080127 -199.424798)
		(end 4.56946 -199.935338)
		(stroke
			(width 0.2)
			(type default)
		)
		(layer "In6.Cu")
	)
	(gr_line
		(start 5.59054 -195.1482)
		(end 5.59054 -194.335654)
		(stroke
			(width 0.2)
			(type default)
		)
		(layer "In6.Cu")
	)
	(gr_arc
		(start 5.59054 -194.335654)
		(mid 5.080127 -193.82486)
		(end 4.56946 -194.3354)
		(stroke
			(width 0.2)
			(type default)
		)
		(layer "In6.Cu")
	)
	(gr_line
		(start 5.59054 -191.948308)
		(end 5.59054 -191.135762)
		(stroke
			(width 0.2)
			(type default)
		)
		(layer "In6.Cu")
	)
	(gr_arc
		(start 5.59054 -191.135762)
		(mid 5.080127 -190.624968)
		(end 4.56946 -191.135508)
		(stroke
			(width 0.2)
			(type default)
		)
		(layer "In6.Cu")
	)
	(gr_line
		(start 5.59054 -183.948324)
		(end 5.59054 -183.135778)
		(stroke
			(width 0.2)
			(type default)
		)
		(layer "In6.Cu")
	)
	(gr_arc
		(start 5.59054 -183.135778)
		(mid 5.080127 -182.624984)
		(end 4.56946 -183.135524)
		(stroke
			(width 0.2)
			(type default)
		)
		(layer "In6.Cu")
	)
	(gr_line
		(start 5.59054 -180.748178)
		(end 5.59054 -179.935632)
		(stroke
			(width 0.2)
			(type default)
		)
		(layer "In6.Cu")
	)
	(gr_arc
		(start 5.59054 -179.935632)
		(mid 5.080127 -179.424838)
		(end 4.56946 -179.935378)
		(stroke
			(width 0.2)
			(type default)
		)
		(layer "In6.Cu")
	)
	(gr_line
		(start 5.59054 -177.548286)
		(end 5.59054 -176.73574)
		(stroke
			(width 0.2)
			(type default)
		)
		(layer "In6.Cu")
	)
	(gr_arc
		(start 5.59054 -176.73574)
		(mid 5.080127 -176.224946)
		(end 4.56946 -176.735486)
		(stroke
			(width 0.2)
			(type default)
		)
		(layer "In6.Cu")
	)
	(gr_line
		(start 5.59054 -174.34814)
		(end 5.59054 -173.535594)
		(stroke
			(width 0.2)
			(type default)
		)
		(layer "In6.Cu")
	)
	(gr_arc
		(start 5.59054 -173.535594)
		(mid 5.080127 -173.0248)
		(end 4.56946 -173.53534)
		(stroke
			(width 0.2)
			(type default)
		)
		(layer "In6.Cu")
	)
	(gr_line
		(start 5.59054 -171.148248)
		(end 5.59054 -170.335702)
		(stroke
			(width 0.2)
			(type default)
		)
		(layer "In6.Cu")
	)
	(gr_arc
		(start 5.59054 -170.335702)
		(mid 5.080127 -169.824908)
		(end 4.56946 -170.335448)
		(stroke
			(width 0.2)
			(type default)
		)
		(layer "In6.Cu")
	)
	(gr_line
		(start 5.59054 -167.948102)
		(end 5.59054 -167.135556)
		(stroke
			(width 0.2)
			(type default)
		)
		(layer "In6.Cu")
	)
	(gr_arc
		(start 5.59054 -167.135556)
		(mid 5.080127 -166.624762)
		(end 4.56946 -167.135302)
		(stroke
			(width 0.2)
			(type default)
		)
		(layer "In6.Cu")
	)
	(gr_line
		(start 5.59054 -164.74821)
		(end 5.59054 -163.935664)
		(stroke
			(width 0.2)
			(type default)
		)
		(layer "In6.Cu")
	)
	(gr_arc
		(start 5.59054 -163.935664)
		(mid 5.080127 -163.42487)
		(end 4.56946 -163.93541)
		(stroke
			(width 0.2)
			(type default)
		)
		(layer "In6.Cu")
	)
	(gr_line
		(start 5.59054 -161.548318)
		(end 5.59054 -160.735772)
		(stroke
			(width 0.2)
			(type default)
		)
		(layer "In6.Cu")
	)
	(gr_arc
		(start 5.59054 -160.735772)
		(mid 5.080127 -160.224978)
		(end 4.56946 -160.735518)
		(stroke
			(width 0.2)
			(type default)
		)
		(layer "In6.Cu")
	)
	(gr_line
		(start 5.59054 -158.348172)
		(end 5.59054 -157.535626)
		(stroke
			(width 0.2)
			(type default)
		)
		(layer "In6.Cu")
	)
	(gr_arc
		(start 5.59054 -157.535626)
		(mid 5.080127 -157.024832)
		(end 4.56946 -157.535372)
		(stroke
			(width 0.2)
			(type default)
		)
		(layer "In6.Cu")
	)
	(gr_line
		(start 5.59054 -155.14828)
		(end 5.59054 -154.335734)
		(stroke
			(width 0.2)
			(type default)
		)
		(layer "In6.Cu")
	)
	(gr_arc
		(start 5.59054 -154.335734)
		(mid 5.080127 -153.82494)
		(end 4.56946 -154.33548)
		(stroke
			(width 0.2)
			(type default)
		)
		(layer "In6.Cu")
	)
	(gr_line
		(start 6.477 -449.978272)
		(end 7.2898 -449.978272)
		(stroke
			(width 0.2)
			(type default)
		)
		(layer "In6.Cu")
	)
	(gr_arc
		(start 6.477254 -448.957192)
		(mid 5.96646 -449.467605)
		(end 6.477 -449.978272)
		(stroke
			(width 0.2)
			(type default)
		)
		(layer "In6.Cu")
	)
	(gr_arc
		(start 6.481826 -447.196718)
		(mid 6.992239 -447.707512)
		(end 7.502906 -447.196972)
		(stroke
			(width 0.2)
			(type default)
		)
		(layer "In6.Cu")
	)
	(gr_line
		(start 6.481826 -446.384172)
		(end 6.481826 -447.196718)
		(stroke
			(width 0.2)
			(type default)
		)
		(layer "In6.Cu")
	)
	(gr_arc
		(start 6.481826 -443.996826)
		(mid 6.992239 -444.50762)
		(end 7.502906 -443.99708)
		(stroke
			(width 0.2)
			(type default)
		)
		(layer "In6.Cu")
	)
	(gr_line
		(start 6.481826 -443.18428)
		(end 6.481826 -443.996826)
		(stroke
			(width 0.2)
			(type default)
		)
		(layer "In6.Cu")
	)
	(gr_arc
		(start 6.481826 -440.79668)
		(mid 6.992239 -441.307474)
		(end 7.502906 -440.796934)
		(stroke
			(width 0.2)
			(type default)
		)
		(layer "In6.Cu")
	)
	(gr_line
		(start 6.481826 -439.984134)
		(end 6.481826 -440.79668)
		(stroke
			(width 0.2)
			(type default)
		)
		(layer "In6.Cu")
	)
	(gr_arc
		(start 6.481826 -437.596788)
		(mid 6.992239 -438.107582)
		(end 7.502906 -437.597042)
		(stroke
			(width 0.2)
			(type default)
		)
		(layer "In6.Cu")
	)
	(gr_line
		(start 6.481826 -436.784242)
		(end 6.481826 -437.596788)
		(stroke
			(width 0.2)
			(type default)
		)
		(layer "In6.Cu")
	)
	(gr_arc
		(start 6.481826 -431.997104)
		(mid 6.992366 -432.507644)
		(end 7.502906 -431.997104)
		(stroke
			(width 0.2)
			(type default)
		)
		(layer "In6.Cu")
	)
	(gr_line
		(start 6.481826 -431.184304)
		(end 6.481826 -431.997104)
		(stroke
			(width 0.2)
			(type default)
		)
		(layer "In6.Cu")
	)
	(gr_arc
		(start 6.481826 -428.796958)
		(mid 6.992366 -429.307498)
		(end 7.502906 -428.796958)
		(stroke
			(width 0.2)
			(type default)
		)
		(layer "In6.Cu")
	)
	(gr_line
		(start 6.481826 -427.984158)
		(end 6.481826 -428.796958)
		(stroke
			(width 0.2)
			(type default)
		)
		(layer "In6.Cu")
	)
	(gr_arc
		(start 6.481826 -425.597066)
		(mid 6.992366 -426.107606)
		(end 7.502906 -425.597066)
		(stroke
			(width 0.2)
			(type default)
		)
		(layer "In6.Cu")
	)
	(gr_line
		(start 6.481826 -424.784266)
		(end 6.481826 -425.597066)
		(stroke
			(width 0.2)
			(type default)
		)
		(layer "In6.Cu")
	)
	(gr_arc
		(start 6.481826 -415.948622)
		(mid 6.992366 -416.459162)
		(end 7.502906 -415.948622)
		(stroke
			(width 0.2)
			(type default)
		)
		(layer "In6.Cu")
	)
	(gr_line
		(start 6.481826 -415.135822)
		(end 6.481826 -415.948622)
		(stroke
			(width 0.2)
			(type default)
		)
		(layer "In6.Cu")
	)
	(gr_arc
		(start 6.481826 -412.748222)
		(mid 6.992239 -413.259016)
		(end 7.502906 -412.748476)
		(stroke
			(width 0.2)
			(type default)
		)
		(layer "In6.Cu")
	)
	(gr_line
		(start 6.481826 -411.935676)
		(end 6.481826 -412.748222)
		(stroke
			(width 0.2)
			(type default)
		)
		(layer "In6.Cu")
	)
	(gr_arc
		(start 6.481826 -409.54833)
		(mid 6.992239 -410.059124)
		(end 7.502906 -409.548584)
		(stroke
			(width 0.2)
			(type default)
		)
		(layer "In6.Cu")
	)
	(gr_line
		(start 6.481826 -408.735784)
		(end 6.481826 -409.54833)
		(stroke
			(width 0.2)
			(type default)
		)
		(layer "In6.Cu")
	)
	(gr_arc
		(start 6.481826 -406.348184)
		(mid 6.992239 -406.858978)
		(end 7.502906 -406.348438)
		(stroke
			(width 0.2)
			(type default)
		)
		(layer "In6.Cu")
	)
	(gr_line
		(start 6.481826 -405.535638)
		(end 6.481826 -406.348184)
		(stroke
			(width 0.2)
			(type default)
		)
		(layer "In6.Cu")
	)
	(gr_arc
		(start 6.481826 -403.148292)
		(mid 6.992239 -403.659086)
		(end 7.502906 -403.148546)
		(stroke
			(width 0.2)
			(type default)
		)
		(layer "In6.Cu")
	)
	(gr_line
		(start 6.481826 -402.335746)
		(end 6.481826 -403.148292)
		(stroke
			(width 0.2)
			(type default)
		)
		(layer "In6.Cu")
	)
	(gr_arc
		(start 6.481826 -397.548608)
		(mid 6.992366 -398.059148)
		(end 7.502906 -397.548608)
		(stroke
			(width 0.2)
			(type default)
		)
		(layer "In6.Cu")
	)
	(gr_line
		(start 6.481826 -396.735808)
		(end 6.481826 -397.548608)
		(stroke
			(width 0.2)
			(type default)
		)
		(layer "In6.Cu")
	)
	(gr_arc
		(start 6.481826 -394.348462)
		(mid 6.992366 -394.859002)
		(end 7.502906 -394.348462)
		(stroke
			(width 0.2)
			(type default)
		)
		(layer "In6.Cu")
	)
	(gr_line
		(start 6.481826 -393.535662)
		(end 6.481826 -394.348462)
		(stroke
			(width 0.2)
			(type default)
		)
		(layer "In6.Cu")
	)
	(gr_arc
		(start 6.481826 -391.14857)
		(mid 6.992366 -391.65911)
		(end 7.502906 -391.14857)
		(stroke
			(width 0.2)
			(type default)
		)
		(layer "In6.Cu")
	)
	(gr_line
		(start 6.481826 -390.33577)
		(end 6.481826 -391.14857)
		(stroke
			(width 0.2)
			(type default)
		)
		(layer "In6.Cu")
	)
	(gr_arc
		(start 6.481826 -387.948424)
		(mid 6.992366 -388.458964)
		(end 7.502906 -387.948424)
		(stroke
			(width 0.2)
			(type default)
		)
		(layer "In6.Cu")
	)
	(gr_line
		(start 6.481826 -387.135624)
		(end 6.481826 -387.948424)
		(stroke
			(width 0.2)
			(type default)
		)
		(layer "In6.Cu")
	)
	(gr_arc
		(start 6.481826 -357.148384)
		(mid 6.992239 -357.659178)
		(end 7.502906 -357.148638)
		(stroke
			(width 0.2)
			(type default)
		)
		(layer "In6.Cu")
	)
	(gr_line
		(start 6.481826 -356.335838)
		(end 6.481826 -357.148384)
		(stroke
			(width 0.2)
			(type default)
		)
		(layer "In6.Cu")
	)
	(gr_arc
		(start 6.481826 -353.948746)
		(mid 6.992366 -354.459286)
		(end 7.502906 -353.948746)
		(stroke
			(width 0.2)
			(type default)
		)
		(layer "In6.Cu")
	)
	(gr_line
		(start 6.481826 -353.135946)
		(end 6.481826 -353.948746)
		(stroke
			(width 0.2)
			(type default)
		)
		(layer "In6.Cu")
	)
	(gr_arc
		(start 6.481826 -350.748346)
		(mid 6.992239 -351.25914)
		(end 7.502906 -350.7486)
		(stroke
			(width 0.2)
			(type default)
		)
		(layer "In6.Cu")
	)
	(gr_line
		(start 6.481826 -349.9358)
		(end 6.481826 -350.748346)
		(stroke
			(width 0.2)
			(type default)
		)
		(layer "In6.Cu")
	)
	(gr_arc
		(start 6.481826 -347.548454)
		(mid 6.992239 -348.059248)
		(end 7.502906 -347.548708)
		(stroke
			(width 0.2)
			(type default)
		)
		(layer "In6.Cu")
	)
	(gr_line
		(start 6.481826 -346.735908)
		(end 6.481826 -347.548454)
		(stroke
			(width 0.2)
			(type default)
		)
		(layer "In6.Cu")
	)
	(gr_arc
		(start 6.481826 -344.399616)
		(mid 6.992366 -344.910156)
		(end 7.502906 -344.399616)
		(stroke
			(width 0.2)
			(type default)
		)
		(layer "In6.Cu")
	)
	(gr_line
		(start 6.481826 -343.586816)
		(end 6.481826 -344.399616)
		(stroke
			(width 0.2)
			(type default)
		)
		(layer "In6.Cu")
	)
	(gr_arc
		(start 6.481826 -341.19947)
		(mid 6.992366 -341.71001)
		(end 7.502906 -341.19947)
		(stroke
			(width 0.2)
			(type default)
		)
		(layer "In6.Cu")
	)
	(gr_line
		(start 6.481826 -340.38667)
		(end 6.481826 -341.19947)
		(stroke
			(width 0.2)
			(type default)
		)
		(layer "In6.Cu")
	)
	(gr_arc
		(start 6.481826 -337.999578)
		(mid 6.992366 -338.510118)
		(end 7.502906 -337.999578)
		(stroke
			(width 0.2)
			(type default)
		)
		(layer "In6.Cu")
	)
	(gr_line
		(start 6.481826 -337.186778)
		(end 6.481826 -337.999578)
		(stroke
			(width 0.2)
			(type default)
		)
		(layer "In6.Cu")
	)
	(gr_arc
		(start 6.481826 -334.799432)
		(mid 6.992366 -335.309972)
		(end 7.502906 -334.799432)
		(stroke
			(width 0.2)
			(type default)
		)
		(layer "In6.Cu")
	)
	(gr_line
		(start 6.481826 -333.986632)
		(end 6.481826 -334.799432)
		(stroke
			(width 0.2)
			(type default)
		)
		(layer "In6.Cu")
	)
	(gr_arc
		(start 6.481826 -329.14844)
		(mid 6.992239 -329.659234)
		(end 7.502906 -329.148694)
		(stroke
			(width 0.2)
			(type default)
		)
		(layer "In6.Cu")
	)
	(gr_line
		(start 6.481826 -328.335894)
		(end 6.481826 -329.14844)
		(stroke
			(width 0.2)
			(type default)
		)
		(layer "In6.Cu")
	)
	(gr_arc
		(start 6.481826 -325.948548)
		(mid 6.992239 -326.459342)
		(end 7.502906 -325.948802)
		(stroke
			(width 0.2)
			(type default)
		)
		(layer "In6.Cu")
	)
	(gr_line
		(start 6.481826 -325.136002)
		(end 6.481826 -325.948548)
		(stroke
			(width 0.2)
			(type default)
		)
		(layer "In6.Cu")
	)
	(gr_arc
		(start 6.481826 -322.748402)
		(mid 6.992239 -323.259196)
		(end 7.502906 -322.748656)
		(stroke
			(width 0.2)
			(type default)
		)
		(layer "In6.Cu")
	)
	(gr_line
		(start 6.481826 -321.935856)
		(end 6.481826 -322.748402)
		(stroke
			(width 0.2)
			(type default)
		)
		(layer "In6.Cu")
	)
	(gr_arc
		(start 6.481826 -319.54851)
		(mid 6.992239 -320.059304)
		(end 7.502906 -319.548764)
		(stroke
			(width 0.2)
			(type default)
		)
		(layer "In6.Cu")
	)
	(gr_line
		(start 6.481826 -318.735964)
		(end 6.481826 -319.54851)
		(stroke
			(width 0.2)
			(type default)
		)
		(layer "In6.Cu")
	)
	(gr_arc
		(start 6.481826 -311.548526)
		(mid 6.992239 -312.05932)
		(end 7.502906 -311.54878)
		(stroke
			(width 0.2)
			(type default)
		)
		(layer "In6.Cu")
	)
	(gr_line
		(start 6.481826 -310.73598)
		(end 6.481826 -311.548526)
		(stroke
			(width 0.2)
			(type default)
		)
		(layer "In6.Cu")
	)
	(gr_arc
		(start 6.481826 -308.34838)
		(mid 6.992239 -308.859174)
		(end 7.502906 -308.348634)
		(stroke
			(width 0.2)
			(type default)
		)
		(layer "In6.Cu")
	)
	(gr_line
		(start 6.481826 -307.535834)
		(end 6.481826 -308.34838)
		(stroke
			(width 0.2)
			(type default)
		)
		(layer "In6.Cu")
	)
	(gr_arc
		(start 6.481826 -305.148488)
		(mid 6.992239 -305.659282)
		(end 7.502906 -305.148742)
		(stroke
			(width 0.2)
			(type default)
		)
		(layer "In6.Cu")
	)
	(gr_line
		(start 6.481826 -304.335942)
		(end 6.481826 -305.148488)
		(stroke
			(width 0.2)
			(type default)
		)
		(layer "In6.Cu")
	)
	(gr_arc
		(start 6.481826 -301.948342)
		(mid 6.992239 -302.459136)
		(end 7.502906 -301.948596)
		(stroke
			(width 0.2)
			(type default)
		)
		(layer "In6.Cu")
	)
	(gr_line
		(start 6.481826 -301.135796)
		(end 6.481826 -301.948342)
		(stroke
			(width 0.2)
			(type default)
		)
		(layer "In6.Cu")
	)
	(gr_arc
		(start 6.481826 -298.74845)
		(mid 6.992239 -299.259244)
		(end 7.502906 -298.748704)
		(stroke
			(width 0.2)
			(type default)
		)
		(layer "In6.Cu")
	)
	(gr_line
		(start 6.481826 -297.935904)
		(end 6.481826 -298.74845)
		(stroke
			(width 0.2)
			(type default)
		)
		(layer "In6.Cu")
	)
	(gr_arc
		(start 6.481826 -295.548558)
		(mid 6.992239 -296.059352)
		(end 7.502906 -295.548812)
		(stroke
			(width 0.2)
			(type default)
		)
		(layer "In6.Cu")
	)
	(gr_line
		(start 6.481826 -294.736012)
		(end 6.481826 -295.548558)
		(stroke
			(width 0.2)
			(type default)
		)
		(layer "In6.Cu")
	)
	(gr_arc
		(start 6.481826 -292.348412)
		(mid 6.992239 -292.859206)
		(end 7.502906 -292.348666)
		(stroke
			(width 0.2)
			(type default)
		)
		(layer "In6.Cu")
	)
	(gr_line
		(start 6.481826 -291.535866)
		(end 6.481826 -292.348412)
		(stroke
			(width 0.2)
			(type default)
		)
		(layer "In6.Cu")
	)
	(gr_arc
		(start 6.481826 -289.148774)
		(mid 6.992366 -289.659314)
		(end 7.502906 -289.148774)
		(stroke
			(width 0.2)
			(type default)
		)
		(layer "In6.Cu")
	)
	(gr_line
		(start 6.481826 -288.335974)
		(end 6.481826 -289.148774)
		(stroke
			(width 0.2)
			(type default)
		)
		(layer "In6.Cu")
	)
	(gr_arc
		(start 6.481826 -282.799536)
		(mid 6.992366 -283.310076)
		(end 7.502906 -282.799536)
		(stroke
			(width 0.2)
			(type default)
		)
		(layer "In6.Cu")
	)
	(gr_line
		(start 6.481826 -281.986736)
		(end 6.481826 -282.799536)
		(stroke
			(width 0.2)
			(type default)
		)
		(layer "In6.Cu")
	)
	(gr_arc
		(start 6.481826 -279.59939)
		(mid 6.992366 -280.10993)
		(end 7.502906 -279.59939)
		(stroke
			(width 0.2)
			(type default)
		)
		(layer "In6.Cu")
	)
	(gr_line
		(start 6.481826 -278.78659)
		(end 6.481826 -279.59939)
		(stroke
			(width 0.2)
			(type default)
		)
		(layer "In6.Cu")
	)
	(gr_arc
		(start 6.481826 -231.148636)
		(mid 6.992366 -231.659176)
		(end 7.502906 -231.148636)
		(stroke
			(width 0.2)
			(type default)
		)
		(layer "In6.Cu")
	)
	(gr_line
		(start 6.481826 -230.335836)
		(end 6.481826 -231.148636)
		(stroke
			(width 0.2)
			(type default)
		)
		(layer "In6.Cu")
	)
	(gr_arc
		(start 6.481826 -227.948744)
		(mid 6.992366 -228.459284)
		(end 7.502906 -227.948744)
		(stroke
			(width 0.2)
			(type default)
		)
		(layer "In6.Cu")
	)
	(gr_line
		(start 6.481826 -227.135944)
		(end 6.481826 -227.948744)
		(stroke
			(width 0.2)
			(type default)
		)
		(layer "In6.Cu")
	)
	(gr_arc
		(start 6.481826 -224.710498)
		(mid 6.992366 -225.221038)
		(end 7.502906 -224.710498)
		(stroke
			(width 0.2)
			(type default)
		)
		(layer "In6.Cu")
	)
	(gr_line
		(start 6.481826 -223.897698)
		(end 6.481826 -224.710498)
		(stroke
			(width 0.2)
			(type default)
		)
		(layer "In6.Cu")
	)
	(gr_arc
		(start 6.481826 -221.497652)
		(mid 6.992239 -222.008446)
		(end 7.502906 -221.497906)
		(stroke
			(width 0.2)
			(type default)
		)
		(layer "In6.Cu")
	)
	(gr_line
		(start 6.481826 -220.685106)
		(end 6.481826 -221.497652)
		(stroke
			(width 0.2)
			(type default)
		)
		(layer "In6.Cu")
	)
	(gr_arc
		(start 6.481826 -218.298014)
		(mid 6.992366 -218.808554)
		(end 7.502906 -218.298014)
		(stroke
			(width 0.2)
			(type default)
		)
		(layer "In6.Cu")
	)
	(gr_line
		(start 6.481826 -217.485214)
		(end 6.481826 -218.298014)
		(stroke
			(width 0.2)
			(type default)
		)
		(layer "In6.Cu")
	)
	(gr_arc
		(start 6.481826 -215.097868)
		(mid 6.992366 -215.608408)
		(end 7.502906 -215.097868)
		(stroke
			(width 0.2)
			(type default)
		)
		(layer "In6.Cu")
	)
	(gr_line
		(start 6.481826 -214.285068)
		(end 6.481826 -215.097868)
		(stroke
			(width 0.2)
			(type default)
		)
		(layer "In6.Cu")
	)
	(gr_arc
		(start 6.481826 -211.948776)
		(mid 6.992366 -212.459316)
		(end 7.502906 -211.948776)
		(stroke
			(width 0.2)
			(type default)
		)
		(layer "In6.Cu")
	)
	(gr_line
		(start 6.481826 -211.135976)
		(end 6.481826 -211.948776)
		(stroke
			(width 0.2)
			(type default)
		)
		(layer "In6.Cu")
	)
	(gr_arc
		(start 6.481826 -208.74863)
		(mid 6.992366 -209.25917)
		(end 7.502906 -208.74863)
		(stroke
			(width 0.2)
			(type default)
		)
		(layer "In6.Cu")
	)
	(gr_line
		(start 6.481826 -207.93583)
		(end 6.481826 -208.74863)
		(stroke
			(width 0.2)
			(type default)
		)
		(layer "In6.Cu")
	)
	(gr_arc
		(start 6.481826 -205.548738)
		(mid 6.992366 -206.059278)
		(end 7.502906 -205.548738)
		(stroke
			(width 0.2)
			(type default)
		)
		(layer "In6.Cu")
	)
	(gr_line
		(start 6.481826 -204.735938)
		(end 6.481826 -205.548738)
		(stroke
			(width 0.2)
			(type default)
		)
		(layer "In6.Cu")
	)
	(gr_arc
		(start 6.481826 -202.348592)
		(mid 6.992366 -202.859132)
		(end 7.502906 -202.348592)
		(stroke
			(width 0.2)
			(type default)
		)
		(layer "In6.Cu")
	)
	(gr_line
		(start 6.481826 -201.535792)
		(end 6.481826 -202.348592)
		(stroke
			(width 0.2)
			(type default)
		)
		(layer "In6.Cu")
	)
	(gr_arc
		(start 6.481826 -196.748654)
		(mid 6.992366 -197.259194)
		(end 7.502906 -196.748654)
		(stroke
			(width 0.2)
			(type default)
		)
		(layer "In6.Cu")
	)
	(gr_line
		(start 6.481826 -195.935854)
		(end 6.481826 -196.748654)
		(stroke
			(width 0.2)
			(type default)
		)
		(layer "In6.Cu")
	)
	(gr_arc
		(start 6.481826 -193.548762)
		(mid 6.992366 -194.059302)
		(end 7.502906 -193.548762)
		(stroke
			(width 0.2)
			(type default)
		)
		(layer "In6.Cu")
	)
	(gr_line
		(start 6.481826 -192.735962)
		(end 6.481826 -193.548762)
		(stroke
			(width 0.2)
			(type default)
		)
		(layer "In6.Cu")
	)
	(gr_arc
		(start 6.481826 -185.548778)
		(mid 6.992366 -186.059318)
		(end 7.502906 -185.548778)
		(stroke
			(width 0.2)
			(type default)
		)
		(layer "In6.Cu")
	)
	(gr_line
		(start 6.481826 -184.735978)
		(end 6.481826 -185.548778)
		(stroke
			(width 0.2)
			(type default)
		)
		(layer "In6.Cu")
	)
	(gr_arc
		(start 6.481826 -182.348632)
		(mid 6.992366 -182.859172)
		(end 7.502906 -182.348632)
		(stroke
			(width 0.2)
			(type default)
		)
		(layer "In6.Cu")
	)
	(gr_line
		(start 6.481826 -181.535832)
		(end 6.481826 -182.348632)
		(stroke
			(width 0.2)
			(type default)
		)
		(layer "In6.Cu")
	)
	(gr_arc
		(start 6.481826 -179.19954)
		(mid 6.992366 -179.71008)
		(end 7.502906 -179.19954)
		(stroke
			(width 0.2)
			(type default)
		)
		(layer "In6.Cu")
	)
	(gr_line
		(start 6.481826 -178.38674)
		(end 6.481826 -179.19954)
		(stroke
			(width 0.2)
			(type default)
		)
		(layer "In6.Cu")
	)
	(gr_arc
		(start 6.481826 -175.999394)
		(mid 6.992366 -176.509934)
		(end 7.502906 -175.999394)
		(stroke
			(width 0.2)
			(type default)
		)
		(layer "In6.Cu")
	)
	(gr_line
		(start 6.481826 -175.186594)
		(end 6.481826 -175.999394)
		(stroke
			(width 0.2)
			(type default)
		)
		(layer "In6.Cu")
	)
	(gr_arc
		(start 6.481826 -172.799502)
		(mid 6.992366 -173.310042)
		(end 7.502906 -172.799502)
		(stroke
			(width 0.2)
			(type default)
		)
		(layer "In6.Cu")
	)
	(gr_line
		(start 6.481826 -171.986702)
		(end 6.481826 -172.799502)
		(stroke
			(width 0.2)
			(type default)
		)
		(layer "In6.Cu")
	)
	(gr_arc
		(start 6.481826 -169.59961)
		(mid 6.992366 -170.11015)
		(end 7.502906 -169.59961)
		(stroke
			(width 0.2)
			(type default)
		)
		(layer "In6.Cu")
	)
	(gr_line
		(start 6.481826 -168.78681)
		(end 6.481826 -169.59961)
		(stroke
			(width 0.2)
			(type default)
		)
		(layer "In6.Cu")
	)
	(gr_arc
		(start 6.481826 -163.199572)
		(mid 6.992366 -163.710112)
		(end 7.502906 -163.199572)
		(stroke
			(width 0.2)
			(type default)
		)
		(layer "In6.Cu")
	)
	(gr_line
		(start 6.481826 -162.386772)
		(end 6.481826 -163.199572)
		(stroke
			(width 0.2)
			(type default)
		)
		(layer "In6.Cu")
	)
	(gr_arc
		(start 6.481826 -159.999426)
		(mid 6.992366 -160.509966)
		(end 7.502906 -159.999426)
		(stroke
			(width 0.2)
			(type default)
		)
		(layer "In6.Cu")
	)
	(gr_line
		(start 6.481826 -159.186626)
		(end 6.481826 -159.999426)
		(stroke
			(width 0.2)
			(type default)
		)
		(layer "In6.Cu")
	)
	(gr_arc
		(start 6.481826 -156.786834)
		(mid 6.992366 -157.297374)
		(end 7.502906 -156.786834)
		(stroke
			(width 0.2)
			(type default)
		)
		(layer "In6.Cu")
	)
	(gr_line
		(start 6.481826 -155.974034)
		(end 6.481826 -156.786834)
		(stroke
			(width 0.2)
			(type default)
		)
		(layer "In6.Cu")
	)
	(gr_arc
		(start 6.481826 -153.599388)
		(mid 6.992366 -154.109928)
		(end 7.502906 -153.599388)
		(stroke
			(width 0.2)
			(type default)
		)
		(layer "In6.Cu")
	)
	(gr_line
		(start 6.481826 -152.786588)
		(end 6.481826 -153.599388)
		(stroke
			(width 0.2)
			(type default)
		)
		(layer "In6.Cu")
	)
	(gr_arc
		(start 7.2898 -449.978272)
		(mid 7.80034 -449.467732)
		(end 7.2898 -448.957192)
		(stroke
			(width 0.2)
			(type default)
		)
		(layer "In6.Cu")
	)
	(gr_line
		(start 7.2898 -448.957192)
		(end 6.477254 -448.957192)
		(stroke
			(width 0.2)
			(type default)
		)
		(layer "In6.Cu")
	)
	(gr_line
		(start 7.502906 -447.196972)
		(end 7.502906 -446.384172)
		(stroke
			(width 0.2)
			(type default)
		)
		(layer "In6.Cu")
	)
	(gr_arc
		(start 7.502906 -446.384172)
		(mid 6.992366 -445.873632)
		(end 6.481826 -446.384172)
		(stroke
			(width 0.2)
			(type default)
		)
		(layer "In6.Cu")
	)
	(gr_line
		(start 7.502906 -443.99708)
		(end 7.502906 -443.18428)
		(stroke
			(width 0.2)
			(type default)
		)
		(layer "In6.Cu")
	)
	(gr_arc
		(start 7.502906 -443.18428)
		(mid 6.992366 -442.67374)
		(end 6.481826 -443.18428)
		(stroke
			(width 0.2)
			(type default)
		)
		(layer "In6.Cu")
	)
	(gr_line
		(start 7.502906 -440.796934)
		(end 7.502906 -439.984134)
		(stroke
			(width 0.2)
			(type default)
		)
		(layer "In6.Cu")
	)
	(gr_arc
		(start 7.502906 -439.984134)
		(mid 6.992366 -439.473594)
		(end 6.481826 -439.984134)
		(stroke
			(width 0.2)
			(type default)
		)
		(layer "In6.Cu")
	)
	(gr_line
		(start 7.502906 -437.597042)
		(end 7.502906 -436.784242)
		(stroke
			(width 0.2)
			(type default)
		)
		(layer "In6.Cu")
	)
	(gr_arc
		(start 7.502906 -436.784242)
		(mid 6.992366 -436.273702)
		(end 6.481826 -436.784242)
		(stroke
			(width 0.2)
			(type default)
		)
		(layer "In6.Cu")
	)
	(gr_line
		(start 7.502906 -431.997104)
		(end 7.502906 -431.184558)
		(stroke
			(width 0.2)
			(type default)
		)
		(layer "In6.Cu")
	)
	(gr_arc
		(start 7.502906 -431.184558)
		(mid 6.992493 -430.673764)
		(end 6.481826 -431.184304)
		(stroke
			(width 0.2)
			(type default)
		)
		(layer "In6.Cu")
	)
	(gr_line
		(start 7.502906 -428.796958)
		(end 7.502906 -427.984412)
		(stroke
			(width 0.2)
			(type default)
		)
		(layer "In6.Cu")
	)
	(gr_arc
		(start 7.502906 -427.984412)
		(mid 6.992493 -427.473618)
		(end 6.481826 -427.984158)
		(stroke
			(width 0.2)
			(type default)
		)
		(layer "In6.Cu")
	)
	(gr_line
		(start 7.502906 -425.597066)
		(end 7.502906 -424.78452)
		(stroke
			(width 0.2)
			(type default)
		)
		(layer "In6.Cu")
	)
	(gr_arc
		(start 7.502906 -424.78452)
		(mid 6.992493 -424.273726)
		(end 6.481826 -424.784266)
		(stroke
			(width 0.2)
			(type default)
		)
		(layer "In6.Cu")
	)
	(gr_line
		(start 7.502906 -415.948622)
		(end 7.502906 -415.136076)
		(stroke
			(width 0.2)
			(type default)
		)
		(layer "In6.Cu")
	)
	(gr_arc
		(start 7.502906 -415.136076)
		(mid 6.992493 -414.625282)
		(end 6.481826 -415.135822)
		(stroke
			(width 0.2)
			(type default)
		)
		(layer "In6.Cu")
	)
	(gr_line
		(start 7.502906 -412.748476)
		(end 7.502906 -411.935676)
		(stroke
			(width 0.2)
			(type default)
		)
		(layer "In6.Cu")
	)
	(gr_arc
		(start 7.502906 -411.935676)
		(mid 6.992366 -411.425136)
		(end 6.481826 -411.935676)
		(stroke
			(width 0.2)
			(type default)
		)
		(layer "In6.Cu")
	)
	(gr_line
		(start 7.502906 -409.548584)
		(end 7.502906 -408.735784)
		(stroke
			(width 0.2)
			(type default)
		)
		(layer "In6.Cu")
	)
	(gr_arc
		(start 7.502906 -408.735784)
		(mid 6.992366 -408.225244)
		(end 6.481826 -408.735784)
		(stroke
			(width 0.2)
			(type default)
		)
		(layer "In6.Cu")
	)
	(gr_line
		(start 7.502906 -406.348438)
		(end 7.502906 -405.535638)
		(stroke
			(width 0.2)
			(type default)
		)
		(layer "In6.Cu")
	)
	(gr_arc
		(start 7.502906 -405.535638)
		(mid 6.992366 -405.025098)
		(end 6.481826 -405.535638)
		(stroke
			(width 0.2)
			(type default)
		)
		(layer "In6.Cu")
	)
	(gr_line
		(start 7.502906 -403.148546)
		(end 7.502906 -402.335746)
		(stroke
			(width 0.2)
			(type default)
		)
		(layer "In6.Cu")
	)
	(gr_arc
		(start 7.502906 -402.335746)
		(mid 6.992366 -401.825206)
		(end 6.481826 -402.335746)
		(stroke
			(width 0.2)
			(type default)
		)
		(layer "In6.Cu")
	)
	(gr_line
		(start 7.502906 -397.548608)
		(end 7.502906 -396.736062)
		(stroke
			(width 0.2)
			(type default)
		)
		(layer "In6.Cu")
	)
	(gr_arc
		(start 7.502906 -396.736062)
		(mid 6.992493 -396.225268)
		(end 6.481826 -396.735808)
		(stroke
			(width 0.2)
			(type default)
		)
		(layer "In6.Cu")
	)
	(gr_line
		(start 7.502906 -394.348462)
		(end 7.502906 -393.535916)
		(stroke
			(width 0.2)
			(type default)
		)
		(layer "In6.Cu")
	)
	(gr_arc
		(start 7.502906 -393.535916)
		(mid 6.992493 -393.025122)
		(end 6.481826 -393.535662)
		(stroke
			(width 0.2)
			(type default)
		)
		(layer "In6.Cu")
	)
	(gr_line
		(start 7.502906 -391.14857)
		(end 7.502906 -390.336024)
		(stroke
			(width 0.2)
			(type default)
		)
		(layer "In6.Cu")
	)
	(gr_arc
		(start 7.502906 -390.336024)
		(mid 6.992493 -389.82523)
		(end 6.481826 -390.33577)
		(stroke
			(width 0.2)
			(type default)
		)
		(layer "In6.Cu")
	)
	(gr_line
		(start 7.502906 -387.948424)
		(end 7.502906 -387.135878)
		(stroke
			(width 0.2)
			(type default)
		)
		(layer "In6.Cu")
	)
	(gr_arc
		(start 7.502906 -387.135878)
		(mid 6.992493 -386.625084)
		(end 6.481826 -387.135624)
		(stroke
			(width 0.2)
			(type default)
		)
		(layer "In6.Cu")
	)
	(gr_line
		(start 7.502906 -357.148638)
		(end 7.502906 -356.335838)
		(stroke
			(width 0.2)
			(type default)
		)
		(layer "In6.Cu")
	)
	(gr_arc
		(start 7.502906 -356.335838)
		(mid 6.992366 -355.825298)
		(end 6.481826 -356.335838)
		(stroke
			(width 0.2)
			(type default)
		)
		(layer "In6.Cu")
	)
	(gr_line
		(start 7.502906 -353.948746)
		(end 7.502906 -353.1362)
		(stroke
			(width 0.2)
			(type default)
		)
		(layer "In6.Cu")
	)
	(gr_arc
		(start 7.502906 -353.1362)
		(mid 6.992493 -352.625406)
		(end 6.481826 -353.135946)
		(stroke
			(width 0.2)
			(type default)
		)
		(layer "In6.Cu")
	)
	(gr_line
		(start 7.502906 -350.7486)
		(end 7.502906 -349.9358)
		(stroke
			(width 0.2)
			(type default)
		)
		(layer "In6.Cu")
	)
	(gr_arc
		(start 7.502906 -349.9358)
		(mid 6.992366 -349.42526)
		(end 6.481826 -349.9358)
		(stroke
			(width 0.2)
			(type default)
		)
		(layer "In6.Cu")
	)
	(gr_line
		(start 7.502906 -347.548708)
		(end 7.502906 -346.735908)
		(stroke
			(width 0.2)
			(type default)
		)
		(layer "In6.Cu")
	)
	(gr_arc
		(start 7.502906 -346.735908)
		(mid 6.992366 -346.225368)
		(end 6.481826 -346.735908)
		(stroke
			(width 0.2)
			(type default)
		)
		(layer "In6.Cu")
	)
	(gr_line
		(start 7.502906 -344.399616)
		(end 7.502906 -343.58707)
		(stroke
			(width 0.2)
			(type default)
		)
		(layer "In6.Cu")
	)
	(gr_arc
		(start 7.502906 -343.58707)
		(mid 6.992493 -343.076276)
		(end 6.481826 -343.586816)
		(stroke
			(width 0.2)
			(type default)
		)
		(layer "In6.Cu")
	)
	(gr_line
		(start 7.502906 -341.19947)
		(end 7.502906 -340.386924)
		(stroke
			(width 0.2)
			(type default)
		)
		(layer "In6.Cu")
	)
	(gr_arc
		(start 7.502906 -340.386924)
		(mid 6.992493 -339.87613)
		(end 6.481826 -340.38667)
		(stroke
			(width 0.2)
			(type default)
		)
		(layer "In6.Cu")
	)
	(gr_line
		(start 7.502906 -337.999578)
		(end 7.502906 -337.187032)
		(stroke
			(width 0.2)
			(type default)
		)
		(layer "In6.Cu")
	)
	(gr_arc
		(start 7.502906 -337.187032)
		(mid 6.992493 -336.676238)
		(end 6.481826 -337.186778)
		(stroke
			(width 0.2)
			(type default)
		)
		(layer "In6.Cu")
	)
	(gr_line
		(start 7.502906 -334.799432)
		(end 7.502906 -333.986886)
		(stroke
			(width 0.2)
			(type default)
		)
		(layer "In6.Cu")
	)
	(gr_arc
		(start 7.502906 -333.986886)
		(mid 6.992493 -333.476092)
		(end 6.481826 -333.986632)
		(stroke
			(width 0.2)
			(type default)
		)
		(layer "In6.Cu")
	)
	(gr_line
		(start 7.502906 -329.148694)
		(end 7.502906 -328.335894)
		(stroke
			(width 0.2)
			(type default)
		)
		(layer "In6.Cu")
	)
	(gr_arc
		(start 7.502906 -328.335894)
		(mid 6.992366 -327.825354)
		(end 6.481826 -328.335894)
		(stroke
			(width 0.2)
			(type default)
		)
		(layer "In6.Cu")
	)
	(gr_line
		(start 7.502906 -325.948802)
		(end 7.502906 -325.136002)
		(stroke
			(width 0.2)
			(type default)
		)
		(layer "In6.Cu")
	)
	(gr_arc
		(start 7.502906 -325.136002)
		(mid 6.992366 -324.625462)
		(end 6.481826 -325.136002)
		(stroke
			(width 0.2)
			(type default)
		)
		(layer "In6.Cu")
	)
	(gr_line
		(start 7.502906 -322.748656)
		(end 7.502906 -321.935856)
		(stroke
			(width 0.2)
			(type default)
		)
		(layer "In6.Cu")
	)
	(gr_arc
		(start 7.502906 -321.935856)
		(mid 6.992366 -321.425316)
		(end 6.481826 -321.935856)
		(stroke
			(width 0.2)
			(type default)
		)
		(layer "In6.Cu")
	)
	(gr_line
		(start 7.502906 -319.548764)
		(end 7.502906 -318.735964)
		(stroke
			(width 0.2)
			(type default)
		)
		(layer "In6.Cu")
	)
	(gr_arc
		(start 7.502906 -318.735964)
		(mid 6.992366 -318.225424)
		(end 6.481826 -318.735964)
		(stroke
			(width 0.2)
			(type default)
		)
		(layer "In6.Cu")
	)
	(gr_line
		(start 7.502906 -311.54878)
		(end 7.502906 -310.73598)
		(stroke
			(width 0.2)
			(type default)
		)
		(layer "In6.Cu")
	)
	(gr_arc
		(start 7.502906 -310.73598)
		(mid 6.992366 -310.22544)
		(end 6.481826 -310.73598)
		(stroke
			(width 0.2)
			(type default)
		)
		(layer "In6.Cu")
	)
	(gr_line
		(start 7.502906 -308.348634)
		(end 7.502906 -307.535834)
		(stroke
			(width 0.2)
			(type default)
		)
		(layer "In6.Cu")
	)
	(gr_arc
		(start 7.502906 -307.535834)
		(mid 6.992366 -307.025294)
		(end 6.481826 -307.535834)
		(stroke
			(width 0.2)
			(type default)
		)
		(layer "In6.Cu")
	)
	(gr_line
		(start 7.502906 -305.148742)
		(end 7.502906 -304.335942)
		(stroke
			(width 0.2)
			(type default)
		)
		(layer "In6.Cu")
	)
	(gr_arc
		(start 7.502906 -304.335942)
		(mid 6.992366 -303.825402)
		(end 6.481826 -304.335942)
		(stroke
			(width 0.2)
			(type default)
		)
		(layer "In6.Cu")
	)
	(gr_line
		(start 7.502906 -301.948596)
		(end 7.502906 -301.135796)
		(stroke
			(width 0.2)
			(type default)
		)
		(layer "In6.Cu")
	)
	(gr_arc
		(start 7.502906 -301.135796)
		(mid 6.992366 -300.625256)
		(end 6.481826 -301.135796)
		(stroke
			(width 0.2)
			(type default)
		)
		(layer "In6.Cu")
	)
	(gr_line
		(start 7.502906 -298.748704)
		(end 7.502906 -297.935904)
		(stroke
			(width 0.2)
			(type default)
		)
		(layer "In6.Cu")
	)
	(gr_arc
		(start 7.502906 -297.935904)
		(mid 6.992366 -297.425364)
		(end 6.481826 -297.935904)
		(stroke
			(width 0.2)
			(type default)
		)
		(layer "In6.Cu")
	)
	(gr_line
		(start 7.502906 -295.548812)
		(end 7.502906 -294.736012)
		(stroke
			(width 0.2)
			(type default)
		)
		(layer "In6.Cu")
	)
	(gr_arc
		(start 7.502906 -294.736012)
		(mid 6.992366 -294.225472)
		(end 6.481826 -294.736012)
		(stroke
			(width 0.2)
			(type default)
		)
		(layer "In6.Cu")
	)
	(gr_line
		(start 7.502906 -292.348666)
		(end 7.502906 -291.535866)
		(stroke
			(width 0.2)
			(type default)
		)
		(layer "In6.Cu")
	)
	(gr_arc
		(start 7.502906 -291.535866)
		(mid 6.992366 -291.025326)
		(end 6.481826 -291.535866)
		(stroke
			(width 0.2)
			(type default)
		)
		(layer "In6.Cu")
	)
	(gr_line
		(start 7.502906 -289.148774)
		(end 7.502906 -288.336228)
		(stroke
			(width 0.2)
			(type default)
		)
		(layer "In6.Cu")
	)
	(gr_arc
		(start 7.502906 -288.336228)
		(mid 6.992493 -287.825434)
		(end 6.481826 -288.335974)
		(stroke
			(width 0.2)
			(type default)
		)
		(layer "In6.Cu")
	)
	(gr_line
		(start 7.502906 -282.799536)
		(end 7.502906 -281.98699)
		(stroke
			(width 0.2)
			(type default)
		)
		(layer "In6.Cu")
	)
	(gr_arc
		(start 7.502906 -281.98699)
		(mid 6.992493 -281.476196)
		(end 6.481826 -281.986736)
		(stroke
			(width 0.2)
			(type default)
		)
		(layer "In6.Cu")
	)
	(gr_line
		(start 7.502906 -279.59939)
		(end 7.502906 -278.786844)
		(stroke
			(width 0.2)
			(type default)
		)
		(layer "In6.Cu")
	)
	(gr_arc
		(start 7.502906 -278.786844)
		(mid 6.992493 -278.27605)
		(end 6.481826 -278.78659)
		(stroke
			(width 0.2)
			(type default)
		)
		(layer "In6.Cu")
	)
	(gr_line
		(start 7.502906 -231.148636)
		(end 7.502906 -230.33609)
		(stroke
			(width 0.2)
			(type default)
		)
		(layer "In6.Cu")
	)
	(gr_arc
		(start 7.502906 -230.33609)
		(mid 6.992493 -229.825296)
		(end 6.481826 -230.335836)
		(stroke
			(width 0.2)
			(type default)
		)
		(layer "In6.Cu")
	)
	(gr_line
		(start 7.502906 -227.948744)
		(end 7.502906 -227.136198)
		(stroke
			(width 0.2)
			(type default)
		)
		(layer "In6.Cu")
	)
	(gr_arc
		(start 7.502906 -227.136198)
		(mid 6.992493 -226.625404)
		(end 6.481826 -227.135944)
		(stroke
			(width 0.2)
			(type default)
		)
		(layer "In6.Cu")
	)
	(gr_line
		(start 7.502906 -224.710498)
		(end 7.502906 -223.897952)
		(stroke
			(width 0.2)
			(type default)
		)
		(layer "In6.Cu")
	)
	(gr_arc
		(start 7.502906 -223.897952)
		(mid 6.992493 -223.387158)
		(end 6.481826 -223.897698)
		(stroke
			(width 0.2)
			(type default)
		)
		(layer "In6.Cu")
	)
	(gr_line
		(start 7.502906 -221.497906)
		(end 7.502906 -220.685106)
		(stroke
			(width 0.2)
			(type default)
		)
		(layer "In6.Cu")
	)
	(gr_arc
		(start 7.502906 -220.685106)
		(mid 6.992366 -220.174566)
		(end 6.481826 -220.685106)
		(stroke
			(width 0.2)
			(type default)
		)
		(layer "In6.Cu")
	)
	(gr_line
		(start 7.502906 -218.298014)
		(end 7.502906 -217.485468)
		(stroke
			(width 0.2)
			(type default)
		)
		(layer "In6.Cu")
	)
	(gr_arc
		(start 7.502906 -217.485468)
		(mid 6.992493 -216.974674)
		(end 6.481826 -217.485214)
		(stroke
			(width 0.2)
			(type default)
		)
		(layer "In6.Cu")
	)
	(gr_line
		(start 7.502906 -215.097868)
		(end 7.502906 -214.285322)
		(stroke
			(width 0.2)
			(type default)
		)
		(layer "In6.Cu")
	)
	(gr_arc
		(start 7.502906 -214.285322)
		(mid 6.992493 -213.774528)
		(end 6.481826 -214.285068)
		(stroke
			(width 0.2)
			(type default)
		)
		(layer "In6.Cu")
	)
	(gr_line
		(start 7.502906 -211.948776)
		(end 7.502906 -211.13623)
		(stroke
			(width 0.2)
			(type default)
		)
		(layer "In6.Cu")
	)
	(gr_arc
		(start 7.502906 -211.13623)
		(mid 6.992493 -210.625436)
		(end 6.481826 -211.135976)
		(stroke
			(width 0.2)
			(type default)
		)
		(layer "In6.Cu")
	)
	(gr_line
		(start 7.502906 -208.74863)
		(end 7.502906 -207.936084)
		(stroke
			(width 0.2)
			(type default)
		)
		(layer "In6.Cu")
	)
	(gr_arc
		(start 7.502906 -207.936084)
		(mid 6.992493 -207.42529)
		(end 6.481826 -207.93583)
		(stroke
			(width 0.2)
			(type default)
		)
		(layer "In6.Cu")
	)
	(gr_line
		(start 7.502906 -205.548738)
		(end 7.502906 -204.736192)
		(stroke
			(width 0.2)
			(type default)
		)
		(layer "In6.Cu")
	)
	(gr_arc
		(start 7.502906 -204.736192)
		(mid 6.992493 -204.225398)
		(end 6.481826 -204.735938)
		(stroke
			(width 0.2)
			(type default)
		)
		(layer "In6.Cu")
	)
	(gr_line
		(start 7.502906 -202.348592)
		(end 7.502906 -201.536046)
		(stroke
			(width 0.2)
			(type default)
		)
		(layer "In6.Cu")
	)
	(gr_arc
		(start 7.502906 -201.536046)
		(mid 6.992493 -201.025252)
		(end 6.481826 -201.535792)
		(stroke
			(width 0.2)
			(type default)
		)
		(layer "In6.Cu")
	)
	(gr_line
		(start 7.502906 -196.748654)
		(end 7.502906 -195.936108)
		(stroke
			(width 0.2)
			(type default)
		)
		(layer "In6.Cu")
	)
	(gr_arc
		(start 7.502906 -195.936108)
		(mid 6.992493 -195.425314)
		(end 6.481826 -195.935854)
		(stroke
			(width 0.2)
			(type default)
		)
		(layer "In6.Cu")
	)
	(gr_line
		(start 7.502906 -193.548762)
		(end 7.502906 -192.736216)
		(stroke
			(width 0.2)
			(type default)
		)
		(layer "In6.Cu")
	)
	(gr_arc
		(start 7.502906 -192.736216)
		(mid 6.992493 -192.225422)
		(end 6.481826 -192.735962)
		(stroke
			(width 0.2)
			(type default)
		)
		(layer "In6.Cu")
	)
	(gr_line
		(start 7.502906 -185.548778)
		(end 7.502906 -184.736232)
		(stroke
			(width 0.2)
			(type default)
		)
		(layer "In6.Cu")
	)
	(gr_arc
		(start 7.502906 -184.736232)
		(mid 6.992493 -184.225438)
		(end 6.481826 -184.735978)
		(stroke
			(width 0.2)
			(type default)
		)
		(layer "In6.Cu")
	)
	(gr_line
		(start 7.502906 -182.348632)
		(end 7.502906 -181.536086)
		(stroke
			(width 0.2)
			(type default)
		)
		(layer "In6.Cu")
	)
	(gr_arc
		(start 7.502906 -181.536086)
		(mid 6.992493 -181.025292)
		(end 6.481826 -181.535832)
		(stroke
			(width 0.2)
			(type default)
		)
		(layer "In6.Cu")
	)
	(gr_line
		(start 7.502906 -179.19954)
		(end 7.502906 -178.386994)
		(stroke
			(width 0.2)
			(type default)
		)
		(layer "In6.Cu")
	)
	(gr_arc
		(start 7.502906 -178.386994)
		(mid 6.992493 -177.8762)
		(end 6.481826 -178.38674)
		(stroke
			(width 0.2)
			(type default)
		)
		(layer "In6.Cu")
	)
	(gr_line
		(start 7.502906 -175.999394)
		(end 7.502906 -175.186848)
		(stroke
			(width 0.2)
			(type default)
		)
		(layer "In6.Cu")
	)
	(gr_arc
		(start 7.502906 -175.186848)
		(mid 6.992493 -174.676054)
		(end 6.481826 -175.186594)
		(stroke
			(width 0.2)
			(type default)
		)
		(layer "In6.Cu")
	)
	(gr_line
		(start 7.502906 -172.799502)
		(end 7.502906 -171.986956)
		(stroke
			(width 0.2)
			(type default)
		)
		(layer "In6.Cu")
	)
	(gr_arc
		(start 7.502906 -171.986956)
		(mid 6.992493 -171.476162)
		(end 6.481826 -171.986702)
		(stroke
			(width 0.2)
			(type default)
		)
		(layer "In6.Cu")
	)
	(gr_line
		(start 7.502906 -169.59961)
		(end 7.502906 -168.787064)
		(stroke
			(width 0.2)
			(type default)
		)
		(layer "In6.Cu")
	)
	(gr_arc
		(start 7.502906 -168.787064)
		(mid 6.992493 -168.27627)
		(end 6.481826 -168.78681)
		(stroke
			(width 0.2)
			(type default)
		)
		(layer "In6.Cu")
	)
	(gr_line
		(start 7.502906 -163.199572)
		(end 7.502906 -162.387026)
		(stroke
			(width 0.2)
			(type default)
		)
		(layer "In6.Cu")
	)
	(gr_arc
		(start 7.502906 -162.387026)
		(mid 6.992493 -161.876232)
		(end 6.481826 -162.386772)
		(stroke
			(width 0.2)
			(type default)
		)
		(layer "In6.Cu")
	)
	(gr_line
		(start 7.502906 -159.999426)
		(end 7.502906 -159.18688)
		(stroke
			(width 0.2)
			(type default)
		)
		(layer "In6.Cu")
	)
	(gr_arc
		(start 7.502906 -159.18688)
		(mid 6.992493 -158.676086)
		(end 6.481826 -159.186626)
		(stroke
			(width 0.2)
			(type default)
		)
		(layer "In6.Cu")
	)
	(gr_line
		(start 7.502906 -156.786834)
		(end 7.502906 -155.974288)
		(stroke
			(width 0.2)
			(type default)
		)
		(layer "In6.Cu")
	)
	(gr_arc
		(start 7.502906 -155.974288)
		(mid 6.992493 -155.463494)
		(end 6.481826 -155.974034)
		(stroke
			(width 0.2)
			(type default)
		)
		(layer "In6.Cu")
	)
	(gr_line
		(start 7.502906 -153.599388)
		(end 7.502906 -152.786842)
		(stroke
			(width 0.2)
			(type default)
		)
		(layer "In6.Cu")
	)
	(gr_arc
		(start 7.502906 -152.786842)
		(mid 6.992493 -152.276048)
		(end 6.481826 -152.786588)
		(stroke
			(width 0.2)
			(type default)
		)
		(layer "In6.Cu")
	)
	(gr_line
		(start 8.382254 -386.113782)
		(end 9.1948 -386.113782)
		(stroke
			(width 0.2)
			(type default)
		)
		(layer "In6.Cu")
	)
	(gr_arc
		(start 8.382254 -385.092702)
		(mid 7.871714 -385.603242)
		(end 8.382254 -386.113782)
		(stroke
			(width 0.2)
			(type default)
		)
		(layer "In6.Cu")
	)
	(gr_arc
		(start 9.1948 -386.113782)
		(mid 9.705594 -385.603369)
		(end 9.195054 -385.092702)
		(stroke
			(width 0.2)
			(type default)
		)
		(layer "In6.Cu")
	)
	(gr_line
		(start 9.195054 -385.092702)
		(end 8.382254 -385.092702)
		(stroke
			(width 0.2)
			(type default)
		)
		(layer "In6.Cu")
	)
	(gr_arc
		(start 16.76146 -445.415924)
		(mid 17.271873 -445.926718)
		(end 17.78254 -445.416178)
		(stroke
			(width 0.2)
			(type default)
		)
		(layer "In6.Cu")
	)
	(gr_line
		(start 16.76146 -444.603378)
		(end 16.76146 -445.415924)
		(stroke
			(width 0.2)
			(type default)
		)
		(layer "In6.Cu")
	)
	(gr_arc
		(start 16.76146 -342.415876)
		(mid 17.271873 -342.92667)
		(end 17.78254 -342.41613)
		(stroke
			(width 0.2)
			(type default)
		)
		(layer "In6.Cu")
	)
	(gr_line
		(start 16.76146 -341.60333)
		(end 16.76146 -342.415876)
		(stroke
			(width 0.2)
			(type default)
		)
		(layer "In6.Cu")
	)
	(gr_arc
		(start 16.76146 -239.415828)
		(mid 17.271873 -239.926622)
		(end 17.78254 -239.416082)
		(stroke
			(width 0.2)
			(type default)
		)
		(layer "In6.Cu")
	)
	(gr_line
		(start 16.76146 -238.603282)
		(end 16.76146 -239.415828)
		(stroke
			(width 0.2)
			(type default)
		)
		(layer "In6.Cu")
	)
	(gr_arc
		(start 16.76146 -136.41578)
		(mid 17.271873 -136.926574)
		(end 17.78254 -136.416034)
		(stroke
			(width 0.2)
			(type default)
		)
		(layer "In6.Cu")
	)
	(gr_line
		(start 16.76146 -135.603234)
		(end 16.76146 -136.41578)
		(stroke
			(width 0.2)
			(type default)
		)
		(layer "In6.Cu")
	)
	(gr_arc
		(start 16.76146 -33.415986)
		(mid 17.272 -33.926526)
		(end 17.78254 -33.415986)
		(stroke
			(width 0.2)
			(type default)
		)
		(layer "In6.Cu")
	)
	(gr_line
		(start 16.76146 -32.603186)
		(end 16.76146 -33.415986)
		(stroke
			(width 0.2)
			(type default)
		)
		(layer "In6.Cu")
	)
	(gr_line
		(start 17.78254 -445.416178)
		(end 17.78254 -444.603378)
		(stroke
			(width 0.2)
			(type default)
		)
		(layer "In6.Cu")
	)
	(gr_arc
		(start 17.78254 -444.603378)
		(mid 17.272 -444.092838)
		(end 16.76146 -444.603378)
		(stroke
			(width 0.2)
			(type default)
		)
		(layer "In6.Cu")
	)
	(gr_line
		(start 17.78254 -342.41613)
		(end 17.78254 -341.60333)
		(stroke
			(width 0.2)
			(type default)
		)
		(layer "In6.Cu")
	)
	(gr_arc
		(start 17.78254 -341.60333)
		(mid 17.272 -341.09279)
		(end 16.76146 -341.60333)
		(stroke
			(width 0.2)
			(type default)
		)
		(layer "In6.Cu")
	)
	(gr_line
		(start 17.78254 -239.416082)
		(end 17.78254 -238.603282)
		(stroke
			(width 0.2)
			(type default)
		)
		(layer "In6.Cu")
	)
	(gr_arc
		(start 17.78254 -238.603282)
		(mid 17.272 -238.092742)
		(end 16.76146 -238.603282)
		(stroke
			(width 0.2)
			(type default)
		)
		(layer "In6.Cu")
	)
	(gr_line
		(start 17.78254 -136.416034)
		(end 17.78254 -135.603234)
		(stroke
			(width 0.2)
			(type default)
		)
		(layer "In6.Cu")
	)
	(gr_arc
		(start 17.78254 -135.603234)
		(mid 17.272 -135.092694)
		(end 16.76146 -135.603234)
		(stroke
			(width 0.2)
			(type default)
		)
		(layer "In6.Cu")
	)
	(gr_line
		(start 17.78254 -33.415986)
		(end 17.78254 -32.60344)
		(stroke
			(width 0.2)
			(type default)
		)
		(layer "In6.Cu")
	)
	(gr_arc
		(start 17.78254 -32.60344)
		(mid 17.272127 -32.092646)
		(end 16.76146 -32.603186)
		(stroke
			(width 0.2)
			(type default)
		)
		(layer "In6.Cu")
	)
	(gr_arc
		(start 24.66086 -449.168774)
		(mid 25.273 -449.780914)
		(end 25.88514 -449.168774)
		(stroke
			(width 0.2)
			(type default)
		)
		(layer "In6.Cu")
	)
	(gr_line
		(start 24.66086 -448.051174)
		(end 24.66086 -449.168774)
		(stroke
			(width 0.2)
			(type default)
		)
		(layer "In6.Cu")
	)
	(gr_arc
		(start 24.66086 -436.368952)
		(mid 25.273 -436.981092)
		(end 25.88514 -436.368952)
		(stroke
			(width 0.2)
			(type default)
		)
		(layer "In6.Cu")
	)
	(gr_line
		(start 24.66086 -435.251352)
		(end 24.66086 -436.368952)
		(stroke
			(width 0.2)
			(type default)
		)
		(layer "In6.Cu")
	)
	(gr_arc
		(start 24.66086 -431.56886)
		(mid 25.273 -432.181)
		(end 25.88514 -431.56886)
		(stroke
			(width 0.2)
			(type default)
		)
		(layer "In6.Cu")
	)
	(gr_line
		(start 24.66086 -430.45126)
		(end 24.66086 -431.56886)
		(stroke
			(width 0.2)
			(type default)
		)
		(layer "In6.Cu")
	)
	(gr_arc
		(start 24.66086 -426.768768)
		(mid 25.273 -427.380908)
		(end 25.88514 -426.768768)
		(stroke
			(width 0.2)
			(type default)
		)
		(layer "In6.Cu")
	)
	(gr_line
		(start 24.66086 -425.651168)
		(end 24.66086 -426.768768)
		(stroke
			(width 0.2)
			(type default)
		)
		(layer "In6.Cu")
	)
	(gr_arc
		(start 24.66086 -346.168726)
		(mid 25.273 -346.780866)
		(end 25.88514 -346.168726)
		(stroke
			(width 0.2)
			(type default)
		)
		(layer "In6.Cu")
	)
	(gr_line
		(start 24.66086 -345.051126)
		(end 24.66086 -346.168726)
		(stroke
			(width 0.2)
			(type default)
		)
		(layer "In6.Cu")
	)
	(gr_arc
		(start 24.66086 -333.36865)
		(mid 25.272873 -333.981044)
		(end 25.88514 -333.368904)
		(stroke
			(width 0.2)
			(type default)
		)
		(layer "In6.Cu")
	)
	(gr_line
		(start 24.66086 -332.251304)
		(end 24.66086 -333.36865)
		(stroke
			(width 0.2)
			(type default)
		)
		(layer "In6.Cu")
	)
	(gr_arc
		(start 24.66086 -328.568558)
		(mid 25.272873 -329.180952)
		(end 25.88514 -328.568812)
		(stroke
			(width 0.2)
			(type default)
		)
		(layer "In6.Cu")
	)
	(gr_line
		(start 24.66086 -327.451212)
		(end 24.66086 -328.568558)
		(stroke
			(width 0.2)
			(type default)
		)
		(layer "In6.Cu")
	)
	(gr_arc
		(start 24.66086 -323.768466)
		(mid 25.272873 -324.38086)
		(end 25.88514 -323.76872)
		(stroke
			(width 0.2)
			(type default)
		)
		(layer "In6.Cu")
	)
	(gr_line
		(start 24.66086 -322.65112)
		(end 24.66086 -323.768466)
		(stroke
			(width 0.2)
			(type default)
		)
		(layer "In6.Cu")
	)
	(gr_arc
		(start 24.66086 -243.168424)
		(mid 25.272873 -243.780818)
		(end 25.88514 -243.168678)
		(stroke
			(width 0.2)
			(type default)
		)
		(layer "In6.Cu")
	)
	(gr_line
		(start 24.66086 -242.051078)
		(end 24.66086 -243.168424)
		(stroke
			(width 0.2)
			(type default)
		)
		(layer "In6.Cu")
	)
	(gr_arc
		(start 24.66086 -230.368602)
		(mid 25.272873 -230.980996)
		(end 25.88514 -230.368856)
		(stroke
			(width 0.2)
			(type default)
		)
		(layer "In6.Cu")
	)
	(gr_line
		(start 24.66086 -229.251256)
		(end 24.66086 -230.368602)
		(stroke
			(width 0.2)
			(type default)
		)
		(layer "In6.Cu")
	)
	(gr_arc
		(start 24.66086 -225.56851)
		(mid 25.272873 -226.180904)
		(end 25.88514 -225.568764)
		(stroke
			(width 0.2)
			(type default)
		)
		(layer "In6.Cu")
	)
	(gr_line
		(start 24.66086 -224.451164)
		(end 24.66086 -225.56851)
		(stroke
			(width 0.2)
			(type default)
		)
		(layer "In6.Cu")
	)
	(gr_arc
		(start 24.66086 -220.768672)
		(mid 25.273 -221.380812)
		(end 25.88514 -220.768672)
		(stroke
			(width 0.2)
			(type default)
		)
		(layer "In6.Cu")
	)
	(gr_line
		(start 24.66086 -219.651072)
		(end 24.66086 -220.768672)
		(stroke
			(width 0.2)
			(type default)
		)
		(layer "In6.Cu")
	)
	(gr_arc
		(start 24.66086 -140.16863)
		(mid 25.273 -140.78077)
		(end 25.88514 -140.16863)
		(stroke
			(width 0.2)
			(type default)
		)
		(layer "In6.Cu")
	)
	(gr_line
		(start 24.66086 -139.05103)
		(end 24.66086 -140.16863)
		(stroke
			(width 0.2)
			(type default)
		)
		(layer "In6.Cu")
	)
	(gr_arc
		(start 24.66086 -127.368554)
		(mid 25.272873 -127.980948)
		(end 25.88514 -127.368808)
		(stroke
			(width 0.2)
			(type default)
		)
		(layer "In6.Cu")
	)
	(gr_line
		(start 24.66086 -126.251208)
		(end 24.66086 -127.368554)
		(stroke
			(width 0.2)
			(type default)
		)
		(layer "In6.Cu")
	)
	(gr_arc
		(start 24.66086 -122.568462)
		(mid 25.272873 -123.180856)
		(end 25.88514 -122.568716)
		(stroke
			(width 0.2)
			(type default)
		)
		(layer "In6.Cu")
	)
	(gr_line
		(start 24.66086 -121.451116)
		(end 24.66086 -122.568462)
		(stroke
			(width 0.2)
			(type default)
		)
		(layer "In6.Cu")
	)
	(gr_arc
		(start 24.66086 -117.768624)
		(mid 25.273 -118.380764)
		(end 25.88514 -117.768624)
		(stroke
			(width 0.2)
			(type default)
		)
		(layer "In6.Cu")
	)
	(gr_line
		(start 24.66086 -116.651024)
		(end 24.66086 -117.768624)
		(stroke
			(width 0.2)
			(type default)
		)
		(layer "In6.Cu")
	)
	(gr_arc
		(start 24.66086 -37.168328)
		(mid 25.272873 -37.780722)
		(end 25.88514 -37.168582)
		(stroke
			(width 0.2)
			(type default)
		)
		(layer "In6.Cu")
	)
	(gr_line
		(start 24.66086 -36.050982)
		(end 24.66086 -37.168328)
		(stroke
			(width 0.2)
			(type default)
		)
		(layer "In6.Cu")
	)
	(gr_arc
		(start 24.66086 -24.368506)
		(mid 25.272873 -24.9809)
		(end 25.88514 -24.36876)
		(stroke
			(width 0.2)
			(type default)
		)
		(layer "In6.Cu")
	)
	(gr_line
		(start 24.66086 -23.25116)
		(end 24.66086 -24.368506)
		(stroke
			(width 0.2)
			(type default)
		)
		(layer "In6.Cu")
	)
	(gr_arc
		(start 24.66086 -19.568414)
		(mid 25.272873 -20.180808)
		(end 25.88514 -19.568668)
		(stroke
			(width 0.2)
			(type default)
		)
		(layer "In6.Cu")
	)
	(gr_line
		(start 24.66086 -18.451068)
		(end 24.66086 -19.568414)
		(stroke
			(width 0.2)
			(type default)
		)
		(layer "In6.Cu")
	)
	(gr_arc
		(start 24.66086 -14.793976)
		(mid 25.273 -15.406116)
		(end 25.88514 -14.793976)
		(stroke
			(width 0.2)
			(type default)
		)
		(layer "In6.Cu")
	)
	(gr_line
		(start 24.66086 -13.676376)
		(end 24.66086 -14.793976)
		(stroke
			(width 0.2)
			(type default)
		)
		(layer "In6.Cu")
	)
	(gr_line
		(start 25.88514 -449.168774)
		(end 25.88514 -448.051428)
		(stroke
			(width 0.2)
			(type default)
		)
		(layer "In6.Cu")
	)
	(gr_arc
		(start 25.88514 -448.051428)
		(mid 25.273127 -447.439034)
		(end 24.66086 -448.051174)
		(stroke
			(width 0.2)
			(type default)
		)
		(layer "In6.Cu")
	)
	(gr_line
		(start 25.88514 -436.368952)
		(end 25.88514 -435.251606)
		(stroke
			(width 0.2)
			(type default)
		)
		(layer "In6.Cu")
	)
	(gr_arc
		(start 25.88514 -435.251606)
		(mid 25.273127 -434.639212)
		(end 24.66086 -435.251352)
		(stroke
			(width 0.2)
			(type default)
		)
		(layer "In6.Cu")
	)
	(gr_line
		(start 25.88514 -431.56886)
		(end 25.88514 -430.451514)
		(stroke
			(width 0.2)
			(type default)
		)
		(layer "In6.Cu")
	)
	(gr_arc
		(start 25.88514 -430.451514)
		(mid 25.273127 -429.83912)
		(end 24.66086 -430.45126)
		(stroke
			(width 0.2)
			(type default)
		)
		(layer "In6.Cu")
	)
	(gr_line
		(start 25.88514 -426.768768)
		(end 25.88514 -425.651422)
		(stroke
			(width 0.2)
			(type default)
		)
		(layer "In6.Cu")
	)
	(gr_arc
		(start 25.88514 -425.651422)
		(mid 25.273127 -425.039028)
		(end 24.66086 -425.651168)
		(stroke
			(width 0.2)
			(type default)
		)
		(layer "In6.Cu")
	)
	(gr_line
		(start 25.88514 -346.168726)
		(end 25.88514 -345.05138)
		(stroke
			(width 0.2)
			(type default)
		)
		(layer "In6.Cu")
	)
	(gr_arc
		(start 25.88514 -345.05138)
		(mid 25.273127 -344.438986)
		(end 24.66086 -345.051126)
		(stroke
			(width 0.2)
			(type default)
		)
		(layer "In6.Cu")
	)
	(gr_line
		(start 25.88514 -333.368904)
		(end 25.88514 -332.251304)
		(stroke
			(width 0.2)
			(type default)
		)
		(layer "In6.Cu")
	)
	(gr_arc
		(start 25.88514 -332.251304)
		(mid 25.273 -331.639164)
		(end 24.66086 -332.251304)
		(stroke
			(width 0.2)
			(type default)
		)
		(layer "In6.Cu")
	)
	(gr_line
		(start 25.88514 -328.568812)
		(end 25.88514 -327.451212)
		(stroke
			(width 0.2)
			(type default)
		)
		(layer "In6.Cu")
	)
	(gr_arc
		(start 25.88514 -327.451212)
		(mid 25.273 -326.839072)
		(end 24.66086 -327.451212)
		(stroke
			(width 0.2)
			(type default)
		)
		(layer "In6.Cu")
	)
	(gr_line
		(start 25.88514 -323.76872)
		(end 25.88514 -322.65112)
		(stroke
			(width 0.2)
			(type default)
		)
		(layer "In6.Cu")
	)
	(gr_arc
		(start 25.88514 -322.65112)
		(mid 25.273 -322.03898)
		(end 24.66086 -322.65112)
		(stroke
			(width 0.2)
			(type default)
		)
		(layer "In6.Cu")
	)
	(gr_line
		(start 25.88514 -243.168678)
		(end 25.88514 -242.051078)
		(stroke
			(width 0.2)
			(type default)
		)
		(layer "In6.Cu")
	)
	(gr_arc
		(start 25.88514 -242.051078)
		(mid 25.273 -241.438938)
		(end 24.66086 -242.051078)
		(stroke
			(width 0.2)
			(type default)
		)
		(layer "In6.Cu")
	)
	(gr_line
		(start 25.88514 -230.368856)
		(end 25.88514 -229.251256)
		(stroke
			(width 0.2)
			(type default)
		)
		(layer "In6.Cu")
	)
	(gr_arc
		(start 25.88514 -229.251256)
		(mid 25.273 -228.639116)
		(end 24.66086 -229.251256)
		(stroke
			(width 0.2)
			(type default)
		)
		(layer "In6.Cu")
	)
	(gr_line
		(start 25.88514 -225.568764)
		(end 25.88514 -224.451164)
		(stroke
			(width 0.2)
			(type default)
		)
		(layer "In6.Cu")
	)
	(gr_arc
		(start 25.88514 -224.451164)
		(mid 25.273 -223.839024)
		(end 24.66086 -224.451164)
		(stroke
			(width 0.2)
			(type default)
		)
		(layer "In6.Cu")
	)
	(gr_line
		(start 25.88514 -220.768672)
		(end 25.88514 -219.651326)
		(stroke
			(width 0.2)
			(type default)
		)
		(layer "In6.Cu")
	)
	(gr_arc
		(start 25.88514 -219.651326)
		(mid 25.273127 -219.038932)
		(end 24.66086 -219.651072)
		(stroke
			(width 0.2)
			(type default)
		)
		(layer "In6.Cu")
	)
	(gr_line
		(start 25.88514 -140.16863)
		(end 25.88514 -139.051284)
		(stroke
			(width 0.2)
			(type default)
		)
		(layer "In6.Cu")
	)
	(gr_arc
		(start 25.88514 -139.051284)
		(mid 25.273127 -138.43889)
		(end 24.66086 -139.05103)
		(stroke
			(width 0.2)
			(type default)
		)
		(layer "In6.Cu")
	)
	(gr_line
		(start 25.88514 -127.368808)
		(end 25.88514 -126.251208)
		(stroke
			(width 0.2)
			(type default)
		)
		(layer "In6.Cu")
	)
	(gr_arc
		(start 25.88514 -126.251208)
		(mid 25.273 -125.639068)
		(end 24.66086 -126.251208)
		(stroke
			(width 0.2)
			(type default)
		)
		(layer "In6.Cu")
	)
	(gr_line
		(start 25.88514 -122.568716)
		(end 25.88514 -121.451116)
		(stroke
			(width 0.2)
			(type default)
		)
		(layer "In6.Cu")
	)
	(gr_arc
		(start 25.88514 -121.451116)
		(mid 25.273 -120.838976)
		(end 24.66086 -121.451116)
		(stroke
			(width 0.2)
			(type default)
		)
		(layer "In6.Cu")
	)
	(gr_line
		(start 25.88514 -117.768624)
		(end 25.88514 -116.651278)
		(stroke
			(width 0.2)
			(type default)
		)
		(layer "In6.Cu")
	)
	(gr_arc
		(start 25.88514 -116.651278)
		(mid 25.273127 -116.038884)
		(end 24.66086 -116.651024)
		(stroke
			(width 0.2)
			(type default)
		)
		(layer "In6.Cu")
	)
	(gr_line
		(start 25.88514 -37.168582)
		(end 25.88514 -36.050982)
		(stroke
			(width 0.2)
			(type default)
		)
		(layer "In6.Cu")
	)
	(gr_arc
		(start 25.88514 -36.050982)
		(mid 25.273 -35.438842)
		(end 24.66086 -36.050982)
		(stroke
			(width 0.2)
			(type default)
		)
		(layer "In6.Cu")
	)
	(gr_line
		(start 25.88514 -24.36876)
		(end 25.88514 -23.25116)
		(stroke
			(width 0.2)
			(type default)
		)
		(layer "In6.Cu")
	)
	(gr_arc
		(start 25.88514 -23.25116)
		(mid 25.273 -22.63902)
		(end 24.66086 -23.25116)
		(stroke
			(width 0.2)
			(type default)
		)
		(layer "In6.Cu")
	)
	(gr_line
		(start 25.88514 -19.568668)
		(end 25.88514 -18.451068)
		(stroke
			(width 0.2)
			(type default)
		)
		(layer "In6.Cu")
	)
	(gr_arc
		(start 25.88514 -18.451068)
		(mid 25.273 -17.838928)
		(end 24.66086 -18.451068)
		(stroke
			(width 0.2)
			(type default)
		)
		(layer "In6.Cu")
	)
	(gr_line
		(start 25.88514 -14.793976)
		(end 25.88514 -13.67663)
		(stroke
			(width 0.2)
			(type default)
		)
		(layer "In6.Cu")
	)
	(gr_arc
		(start 25.88514 -13.67663)
		(mid 25.273127 -13.064236)
		(end 24.66086 -13.676376)
		(stroke
			(width 0.2)
			(type default)
		)
		(layer "In6.Cu")
	)
	(gr_arc
		(start 26.15946 -451.41642)
		(mid 26.67 -451.92696)
		(end 27.18054 -451.41642)
		(stroke
			(width 0.2)
			(type default)
		)
		(layer "In6.Cu")
	)
	(gr_line
		(start 26.15946 -450.60362)
		(end 26.15946 -451.41642)
		(stroke
			(width 0.2)
			(type default)
		)
		(layer "In6.Cu")
	)
	(gr_arc
		(start 26.15946 -438.616344)
		(mid 26.67 -439.126884)
		(end 27.18054 -438.616344)
		(stroke
			(width 0.2)
			(type default)
		)
		(layer "In6.Cu")
	)
	(gr_line
		(start 26.15946 -437.803544)
		(end 26.15946 -438.616344)
		(stroke
			(width 0.2)
			(type default)
		)
		(layer "In6.Cu")
	)
	(gr_arc
		(start 26.15946 -433.816506)
		(mid 26.67 -434.327046)
		(end 27.18054 -433.816506)
		(stroke
			(width 0.2)
			(type default)
		)
		(layer "In6.Cu")
	)
	(gr_line
		(start 26.15946 -433.003706)
		(end 26.15946 -433.816506)
		(stroke
			(width 0.2)
			(type default)
		)
		(layer "In6.Cu")
	)
	(gr_arc
		(start 26.15946 -429.016414)
		(mid 26.67 -429.526954)
		(end 27.18054 -429.016414)
		(stroke
			(width 0.2)
			(type default)
		)
		(layer "In6.Cu")
	)
	(gr_line
		(start 26.15946 -428.203614)
		(end 26.15946 -429.016414)
		(stroke
			(width 0.2)
			(type default)
		)
		(layer "In6.Cu")
	)
	(gr_arc
		(start 26.15946 -348.416118)
		(mid 26.669873 -348.926912)
		(end 27.18054 -348.416372)
		(stroke
			(width 0.2)
			(type default)
		)
		(layer "In6.Cu")
	)
	(gr_line
		(start 26.15946 -347.603572)
		(end 26.15946 -348.416118)
		(stroke
			(width 0.2)
			(type default)
		)
		(layer "In6.Cu")
	)
	(gr_arc
		(start 26.15946 -335.616042)
		(mid 26.669873 -336.126836)
		(end 27.18054 -335.616296)
		(stroke
			(width 0.2)
			(type default)
		)
		(layer "In6.Cu")
	)
	(gr_line
		(start 26.15946 -334.803496)
		(end 26.15946 -335.616042)
		(stroke
			(width 0.2)
			(type default)
		)
		(layer "In6.Cu")
	)
	(gr_arc
		(start 26.15946 -330.816204)
		(mid 26.669873 -331.326998)
		(end 27.18054 -330.816458)
		(stroke
			(width 0.2)
			(type default)
		)
		(layer "In6.Cu")
	)
	(gr_line
		(start 26.15946 -330.003658)
		(end 26.15946 -330.816204)
		(stroke
			(width 0.2)
			(type default)
		)
		(layer "In6.Cu")
	)
	(gr_arc
		(start 26.15946 -326.016112)
		(mid 26.669873 -326.526906)
		(end 27.18054 -326.016366)
		(stroke
			(width 0.2)
			(type default)
		)
		(layer "In6.Cu")
	)
	(gr_line
		(start 26.15946 -325.203566)
		(end 26.15946 -326.016112)
		(stroke
			(width 0.2)
			(type default)
		)
		(layer "In6.Cu")
	)
	(gr_arc
		(start 26.15946 -245.41607)
		(mid 26.669873 -245.926864)
		(end 27.18054 -245.416324)
		(stroke
			(width 0.2)
			(type default)
		)
		(layer "In6.Cu")
	)
	(gr_line
		(start 26.15946 -244.603524)
		(end 26.15946 -245.41607)
		(stroke
			(width 0.2)
			(type default)
		)
		(layer "In6.Cu")
	)
	(gr_arc
		(start 26.15946 -232.615994)
		(mid 26.669873 -233.126788)
		(end 27.18054 -232.616248)
		(stroke
			(width 0.2)
			(type default)
		)
		(layer "In6.Cu")
	)
	(gr_line
		(start 26.15946 -231.803448)
		(end 26.15946 -232.615994)
		(stroke
			(width 0.2)
			(type default)
		)
		(layer "In6.Cu")
	)
	(gr_arc
		(start 26.15946 -227.816156)
		(mid 26.669873 -228.32695)
		(end 27.18054 -227.81641)
		(stroke
			(width 0.2)
			(type default)
		)
		(layer "In6.Cu")
	)
	(gr_line
		(start 26.15946 -227.00361)
		(end 26.15946 -227.816156)
		(stroke
			(width 0.2)
			(type default)
		)
		(layer "In6.Cu")
	)
	(gr_arc
		(start 26.15946 -223.016064)
		(mid 26.669873 -223.526858)
		(end 27.18054 -223.016318)
		(stroke
			(width 0.2)
			(type default)
		)
		(layer "In6.Cu")
	)
	(gr_line
		(start 26.15946 -222.203518)
		(end 26.15946 -223.016064)
		(stroke
			(width 0.2)
			(type default)
		)
		(layer "In6.Cu")
	)
	(gr_arc
		(start 26.15946 -142.416022)
		(mid 26.669873 -142.926816)
		(end 27.18054 -142.416276)
		(stroke
			(width 0.2)
			(type default)
		)
		(layer "In6.Cu")
	)
	(gr_line
		(start 26.15946 -141.603476)
		(end 26.15946 -142.416022)
		(stroke
			(width 0.2)
			(type default)
		)
		(layer "In6.Cu")
	)
	(gr_arc
		(start 26.15946 -129.615946)
		(mid 26.669873 -130.12674)
		(end 27.18054 -129.6162)
		(stroke
			(width 0.2)
			(type default)
		)
		(layer "In6.Cu")
	)
	(gr_line
		(start 26.15946 -128.8034)
		(end 26.15946 -129.615946)
		(stroke
			(width 0.2)
			(type default)
		)
		(layer "In6.Cu")
	)
	(gr_arc
		(start 26.15946 -124.816108)
		(mid 26.669873 -125.326902)
		(end 27.18054 -124.816362)
		(stroke
			(width 0.2)
			(type default)
		)
		(layer "In6.Cu")
	)
	(gr_line
		(start 26.15946 -124.003562)
		(end 26.15946 -124.816108)
		(stroke
			(width 0.2)
			(type default)
		)
		(layer "In6.Cu")
	)
	(gr_arc
		(start 26.15946 -120.016016)
		(mid 26.669873 -120.52681)
		(end 27.18054 -120.01627)
		(stroke
			(width 0.2)
			(type default)
		)
		(layer "In6.Cu")
	)
	(gr_line
		(start 26.15946 -119.20347)
		(end 26.15946 -120.016016)
		(stroke
			(width 0.2)
			(type default)
		)
		(layer "In6.Cu")
	)
	(gr_arc
		(start 26.15946 -39.415974)
		(mid 26.669873 -39.926768)
		(end 27.18054 -39.416228)
		(stroke
			(width 0.2)
			(type default)
		)
		(layer "In6.Cu")
	)
	(gr_line
		(start 26.15946 -38.603428)
		(end 26.15946 -39.415974)
		(stroke
			(width 0.2)
			(type default)
		)
		(layer "In6.Cu")
	)
	(gr_arc
		(start 26.15946 -26.615898)
		(mid 26.669873 -27.126692)
		(end 27.18054 -26.616152)
		(stroke
			(width 0.2)
			(type default)
		)
		(layer "In6.Cu")
	)
	(gr_line
		(start 26.15946 -25.803352)
		(end 26.15946 -26.615898)
		(stroke
			(width 0.2)
			(type default)
		)
		(layer "In6.Cu")
	)
	(gr_arc
		(start 26.15946 -21.81606)
		(mid 26.669873 -22.326854)
		(end 27.18054 -21.816314)
		(stroke
			(width 0.2)
			(type default)
		)
		(layer "In6.Cu")
	)
	(gr_line
		(start 26.15946 -21.003514)
		(end 26.15946 -21.81606)
		(stroke
			(width 0.2)
			(type default)
		)
		(layer "In6.Cu")
	)
	(gr_arc
		(start 26.15946 -17.015968)
		(mid 26.669873 -17.526762)
		(end 27.18054 -17.016222)
		(stroke
			(width 0.2)
			(type default)
		)
		(layer "In6.Cu")
	)
	(gr_line
		(start 26.15946 -16.203422)
		(end 26.15946 -17.015968)
		(stroke
			(width 0.2)
			(type default)
		)
		(layer "In6.Cu")
	)
	(gr_line
		(start 27.18054 -451.41642)
		(end 27.18054 -450.603874)
		(stroke
			(width 0.2)
			(type default)
		)
		(layer "In6.Cu")
	)
	(gr_arc
		(start 27.18054 -450.603874)
		(mid 26.670127 -450.09308)
		(end 26.15946 -450.60362)
		(stroke
			(width 0.2)
			(type default)
		)
		(layer "In6.Cu")
	)
	(gr_line
		(start 27.18054 -438.616344)
		(end 27.18054 -437.803798)
		(stroke
			(width 0.2)
			(type default)
		)
		(layer "In6.Cu")
	)
	(gr_arc
		(start 27.18054 -437.803798)
		(mid 26.670127 -437.293004)
		(end 26.15946 -437.803544)
		(stroke
			(width 0.2)
			(type default)
		)
		(layer "In6.Cu")
	)
	(gr_line
		(start 27.18054 -433.816506)
		(end 27.18054 -433.00396)
		(stroke
			(width 0.2)
			(type default)
		)
		(layer "In6.Cu")
	)
	(gr_arc
		(start 27.18054 -433.00396)
		(mid 26.670127 -432.493166)
		(end 26.15946 -433.003706)
		(stroke
			(width 0.2)
			(type default)
		)
		(layer "In6.Cu")
	)
	(gr_line
		(start 27.18054 -429.016414)
		(end 27.18054 -428.203868)
		(stroke
			(width 0.2)
			(type default)
		)
		(layer "In6.Cu")
	)
	(gr_arc
		(start 27.18054 -428.203868)
		(mid 26.670127 -427.693074)
		(end 26.15946 -428.203614)
		(stroke
			(width 0.2)
			(type default)
		)
		(layer "In6.Cu")
	)
	(gr_line
		(start 27.18054 -348.416372)
		(end 27.18054 -347.603572)
		(stroke
			(width 0.2)
			(type default)
		)
		(layer "In6.Cu")
	)
	(gr_arc
		(start 27.18054 -347.603572)
		(mid 26.67 -347.093032)
		(end 26.15946 -347.603572)
		(stroke
			(width 0.2)
			(type default)
		)
		(layer "In6.Cu")
	)
	(gr_line
		(start 27.18054 -335.616296)
		(end 27.18054 -334.803496)
		(stroke
			(width 0.2)
			(type default)
		)
		(layer "In6.Cu")
	)
	(gr_arc
		(start 27.18054 -334.803496)
		(mid 26.67 -334.292956)
		(end 26.15946 -334.803496)
		(stroke
			(width 0.2)
			(type default)
		)
		(layer "In6.Cu")
	)
	(gr_line
		(start 27.18054 -330.816458)
		(end 27.18054 -330.003658)
		(stroke
			(width 0.2)
			(type default)
		)
		(layer "In6.Cu")
	)
	(gr_arc
		(start 27.18054 -330.003658)
		(mid 26.67 -329.493118)
		(end 26.15946 -330.003658)
		(stroke
			(width 0.2)
			(type default)
		)
		(layer "In6.Cu")
	)
	(gr_line
		(start 27.18054 -326.016366)
		(end 27.18054 -325.203566)
		(stroke
			(width 0.2)
			(type default)
		)
		(layer "In6.Cu")
	)
	(gr_arc
		(start 27.18054 -325.203566)
		(mid 26.67 -324.693026)
		(end 26.15946 -325.203566)
		(stroke
			(width 0.2)
			(type default)
		)
		(layer "In6.Cu")
	)
	(gr_line
		(start 27.18054 -245.416324)
		(end 27.18054 -244.603524)
		(stroke
			(width 0.2)
			(type default)
		)
		(layer "In6.Cu")
	)
	(gr_arc
		(start 27.18054 -244.603524)
		(mid 26.67 -244.092984)
		(end 26.15946 -244.603524)
		(stroke
			(width 0.2)
			(type default)
		)
		(layer "In6.Cu")
	)
	(gr_line
		(start 27.18054 -232.616248)
		(end 27.18054 -231.803448)
		(stroke
			(width 0.2)
			(type default)
		)
		(layer "In6.Cu")
	)
	(gr_arc
		(start 27.18054 -231.803448)
		(mid 26.67 -231.292908)
		(end 26.15946 -231.803448)
		(stroke
			(width 0.2)
			(type default)
		)
		(layer "In6.Cu")
	)
	(gr_line
		(start 27.18054 -227.81641)
		(end 27.18054 -227.00361)
		(stroke
			(width 0.2)
			(type default)
		)
		(layer "In6.Cu")
	)
	(gr_arc
		(start 27.18054 -227.00361)
		(mid 26.67 -226.49307)
		(end 26.15946 -227.00361)
		(stroke
			(width 0.2)
			(type default)
		)
		(layer "In6.Cu")
	)
	(gr_line
		(start 27.18054 -223.016318)
		(end 27.18054 -222.203518)
		(stroke
			(width 0.2)
			(type default)
		)
		(layer "In6.Cu")
	)
	(gr_arc
		(start 27.18054 -222.203518)
		(mid 26.67 -221.692978)
		(end 26.15946 -222.203518)
		(stroke
			(width 0.2)
			(type default)
		)
		(layer "In6.Cu")
	)
	(gr_line
		(start 27.18054 -142.416276)
		(end 27.18054 -141.603476)
		(stroke
			(width 0.2)
			(type default)
		)
		(layer "In6.Cu")
	)
	(gr_arc
		(start 27.18054 -141.603476)
		(mid 26.67 -141.092936)
		(end 26.15946 -141.603476)
		(stroke
			(width 0.2)
			(type default)
		)
		(layer "In6.Cu")
	)
	(gr_line
		(start 27.18054 -129.6162)
		(end 27.18054 -128.8034)
		(stroke
			(width 0.2)
			(type default)
		)
		(layer "In6.Cu")
	)
	(gr_arc
		(start 27.18054 -128.8034)
		(mid 26.67 -128.29286)
		(end 26.15946 -128.8034)
		(stroke
			(width 0.2)
			(type default)
		)
		(layer "In6.Cu")
	)
	(gr_line
		(start 27.18054 -124.816362)
		(end 27.18054 -124.003562)
		(stroke
			(width 0.2)
			(type default)
		)
		(layer "In6.Cu")
	)
	(gr_arc
		(start 27.18054 -124.003562)
		(mid 26.67 -123.493022)
		(end 26.15946 -124.003562)
		(stroke
			(width 0.2)
			(type default)
		)
		(layer "In6.Cu")
	)
	(gr_line
		(start 27.18054 -120.01627)
		(end 27.18054 -119.20347)
		(stroke
			(width 0.2)
			(type default)
		)
		(layer "In6.Cu")
	)
	(gr_arc
		(start 27.18054 -119.20347)
		(mid 26.67 -118.69293)
		(end 26.15946 -119.20347)
		(stroke
			(width 0.2)
			(type default)
		)
		(layer "In6.Cu")
	)
	(gr_line
		(start 27.18054 -39.416228)
		(end 27.18054 -38.603428)
		(stroke
			(width 0.2)
			(type default)
		)
		(layer "In6.Cu")
	)
	(gr_arc
		(start 27.18054 -38.603428)
		(mid 26.67 -38.092888)
		(end 26.15946 -38.603428)
		(stroke
			(width 0.2)
			(type default)
		)
		(layer "In6.Cu")
	)
	(gr_line
		(start 27.18054 -26.616152)
		(end 27.18054 -25.803352)
		(stroke
			(width 0.2)
			(type default)
		)
		(layer "In6.Cu")
	)
	(gr_arc
		(start 27.18054 -25.803352)
		(mid 26.67 -25.292812)
		(end 26.15946 -25.803352)
		(stroke
			(width 0.2)
			(type default)
		)
		(layer "In6.Cu")
	)
	(gr_line
		(start 27.18054 -21.816314)
		(end 27.18054 -21.003514)
		(stroke
			(width 0.2)
			(type default)
		)
		(layer "In6.Cu")
	)
	(gr_arc
		(start 27.18054 -21.003514)
		(mid 26.67 -20.492974)
		(end 26.15946 -21.003514)
		(stroke
			(width 0.2)
			(type default)
		)
		(layer "In6.Cu")
	)
	(gr_line
		(start 27.18054 -17.016222)
		(end 27.18054 -16.203422)
		(stroke
			(width 0.2)
			(type default)
		)
		(layer "In6.Cu")
	)
	(gr_arc
		(start 27.18054 -16.203422)
		(mid 26.67 -15.692882)
		(end 26.15946 -16.203422)
		(stroke
			(width 0.2)
			(type default)
		)
		(layer "In6.Cu")
	)
	(gr_line
		(start 30.80004 0)
		(end 32.33674 -3.019552)
		(stroke
			(width 1.524)
			(type default)
		)
		(layer "In6.Cu")
	)
	(gr_arc
		(start 30.98546 -136.416542)
		(mid 31.496 -136.927082)
		(end 32.00654 -136.416542)
		(stroke
			(width 0.2)
			(type default)
		)
		(layer "In6.Cu")
	)
	(gr_line
		(start 30.98546 -135.603742)
		(end 30.98546 -136.416542)
		(stroke
			(width 0.2)
			(type default)
		)
		(layer "In6.Cu")
	)
	(gr_arc
		(start 30.98546 -33.415986)
		(mid 31.496 -33.926526)
		(end 32.00654 -33.415986)
		(stroke
			(width 0.2)
			(type default)
		)
		(layer "In6.Cu")
	)
	(gr_line
		(start 30.98546 -32.603186)
		(end 30.98546 -33.415986)
		(stroke
			(width 0.2)
			(type default)
		)
		(layer "In6.Cu")
	)
	(gr_arc
		(start 31.23946 -445.397636)
		(mid 31.75 -445.908176)
		(end 32.26054 -445.397636)
		(stroke
			(width 0.2)
			(type default)
		)
		(layer "In6.Cu")
	)
	(gr_line
		(start 31.23946 -444.584836)
		(end 31.23946 -445.397636)
		(stroke
			(width 0.2)
			(type default)
		)
		(layer "In6.Cu")
	)
	(gr_line
		(start 32.00654 -136.416542)
		(end 32.00654 -135.603996)
		(stroke
			(width 0.2)
			(type default)
		)
		(layer "In6.Cu")
	)
	(gr_arc
		(start 32.00654 -135.603996)
		(mid 31.496127 -135.093202)
		(end 30.98546 -135.603742)
		(stroke
			(width 0.2)
			(type default)
		)
		(layer "In6.Cu")
	)
	(gr_line
		(start 32.00654 -33.415986)
		(end 32.00654 -32.60344)
		(stroke
			(width 0.2)
			(type default)
		)
		(layer "In6.Cu")
	)
	(gr_arc
		(start 32.00654 -32.60344)
		(mid 31.496127 -32.092646)
		(end 30.98546 -32.603186)
		(stroke
			(width 0.2)
			(type default)
		)
		(layer "In6.Cu")
	)
	(gr_line
		(start 32.26054 -445.397636)
		(end 32.26054 -444.58509)
		(stroke
			(width 0.2)
			(type default)
		)
		(layer "In6.Cu")
	)
	(gr_arc
		(start 32.26054 -444.58509)
		(mid 31.750127 -444.074296)
		(end 31.23946 -444.584836)
		(stroke
			(width 0.2)
			(type default)
		)
		(layer "In6.Cu")
	)
	(gr_arc
		(start 32.38246 -342.397334)
		(mid 32.893 -342.907874)
		(end 33.40354 -342.397334)
		(stroke
			(width 0.2)
			(type default)
		)
		(layer "In6.Cu")
	)
	(gr_line
		(start 32.38246 -341.584534)
		(end 32.38246 -342.397334)
		(stroke
			(width 0.2)
			(type default)
		)
		(layer "In6.Cu")
	)
	(gr_arc
		(start 32.500062 -4.500118)
		(mid 34.000186 -6.000242)
		(end 35.500056 -4.500118)
		(stroke
			(width 1.524)
			(type default)
		)
		(layer "In6.Cu")
	)
	(gr_arc
		(start 32.500062 -3.700018)
		(mid 32.458636 -3.350129)
		(end 32.33674 -3.019552)
		(stroke
			(width 1.524)
			(type default)
		)
		(layer "In6.Cu")
	)
	(gr_line
		(start 32.500062 -3.700018)
		(end 32.500062 -4.500118)
		(stroke
			(width 1.524)
			(type default)
		)
		(layer "In6.Cu")
	)
	(gr_line
		(start 33.40354 -342.397334)
		(end 33.40354 -341.584788)
		(stroke
			(width 0.2)
			(type default)
		)
		(layer "In6.Cu")
	)
	(gr_arc
		(start 33.40354 -341.584788)
		(mid 32.893127 -341.073994)
		(end 32.38246 -341.584534)
		(stroke
			(width 0.2)
			(type default)
		)
		(layer "In6.Cu")
	)
	(gr_arc
		(start 34.81959 -489.796328)
		(mid 35.330003 -490.307122)
		(end 35.84067 -489.796582)
		(stroke
			(width 0.2)
			(type default)
		)
		(layer "In6.Cu")
	)
	(gr_line
		(start 34.81959 -488.983782)
		(end 34.81959 -489.796328)
		(stroke
			(width 0.2)
			(type default)
		)
		(layer "In6.Cu")
	)
	(gr_arc
		(start 34.81959 -484.996236)
		(mid 35.330003 -485.50703)
		(end 35.84067 -484.99649)
		(stroke
			(width 0.2)
			(type default)
		)
		(layer "In6.Cu")
	)
	(gr_line
		(start 34.81959 -484.18369)
		(end 34.81959 -484.996236)
		(stroke
			(width 0.2)
			(type default)
		)
		(layer "In6.Cu")
	)
	(gr_arc
		(start 34.81959 -480.196398)
		(mid 35.330003 -480.707192)
		(end 35.84067 -480.196652)
		(stroke
			(width 0.2)
			(type default)
		)
		(layer "In6.Cu")
	)
	(gr_line
		(start 34.81959 -479.383852)
		(end 34.81959 -480.196398)
		(stroke
			(width 0.2)
			(type default)
		)
		(layer "In6.Cu")
	)
	(gr_arc
		(start 34.81959 -467.396322)
		(mid 35.330003 -467.907116)
		(end 35.84067 -467.396576)
		(stroke
			(width 0.2)
			(type default)
		)
		(layer "In6.Cu")
	)
	(gr_line
		(start 34.81959 -466.583776)
		(end 34.81959 -467.396322)
		(stroke
			(width 0.2)
			(type default)
		)
		(layer "In6.Cu")
	)
	(gr_arc
		(start 34.81959 -386.796534)
		(mid 35.33013 -387.307074)
		(end 35.84067 -386.796534)
		(stroke
			(width 0.2)
			(type default)
		)
		(layer "In6.Cu")
	)
	(gr_line
		(start 34.81959 -385.983734)
		(end 34.81959 -386.796534)
		(stroke
			(width 0.2)
			(type default)
		)
		(layer "In6.Cu")
	)
	(gr_arc
		(start 34.81959 -381.996442)
		(mid 35.33013 -382.506982)
		(end 35.84067 -381.996442)
		(stroke
			(width 0.2)
			(type default)
		)
		(layer "In6.Cu")
	)
	(gr_line
		(start 34.81959 -381.183642)
		(end 34.81959 -381.996442)
		(stroke
			(width 0.2)
			(type default)
		)
		(layer "In6.Cu")
	)
	(gr_arc
		(start 34.81959 -377.196604)
		(mid 35.33013 -377.707144)
		(end 35.84067 -377.196604)
		(stroke
			(width 0.2)
			(type default)
		)
		(layer "In6.Cu")
	)
	(gr_line
		(start 34.81959 -376.383804)
		(end 34.81959 -377.196604)
		(stroke
			(width 0.2)
			(type default)
		)
		(layer "In6.Cu")
	)
	(gr_arc
		(start 34.81959 -364.396528)
		(mid 35.33013 -364.907068)
		(end 35.84067 -364.396528)
		(stroke
			(width 0.2)
			(type default)
		)
		(layer "In6.Cu")
	)
	(gr_line
		(start 34.81959 -363.583728)
		(end 34.81959 -364.396528)
		(stroke
			(width 0.2)
			(type default)
		)
		(layer "In6.Cu")
	)
	(gr_arc
		(start 34.81959 -283.796486)
		(mid 35.33013 -284.307026)
		(end 35.84067 -283.796486)
		(stroke
			(width 0.2)
			(type default)
		)
		(layer "In6.Cu")
	)
	(gr_line
		(start 34.81959 -282.983686)
		(end 34.81959 -283.796486)
		(stroke
			(width 0.2)
			(type default)
		)
		(layer "In6.Cu")
	)
	(gr_arc
		(start 34.81959 -278.996394)
		(mid 35.33013 -279.506934)
		(end 35.84067 -278.996394)
		(stroke
			(width 0.2)
			(type default)
		)
		(layer "In6.Cu")
	)
	(gr_line
		(start 34.81959 -278.183594)
		(end 34.81959 -278.996394)
		(stroke
			(width 0.2)
			(type default)
		)
		(layer "In6.Cu")
	)
	(gr_arc
		(start 34.81959 -274.196556)
		(mid 35.33013 -274.707096)
		(end 35.84067 -274.196556)
		(stroke
			(width 0.2)
			(type default)
		)
		(layer "In6.Cu")
	)
	(gr_line
		(start 34.81959 -273.383756)
		(end 34.81959 -274.196556)
		(stroke
			(width 0.2)
			(type default)
		)
		(layer "In6.Cu")
	)
	(gr_arc
		(start 34.81959 -261.39648)
		(mid 35.33013 -261.90702)
		(end 35.84067 -261.39648)
		(stroke
			(width 0.2)
			(type default)
		)
		(layer "In6.Cu")
	)
	(gr_line
		(start 34.81959 -260.58368)
		(end 34.81959 -261.39648)
		(stroke
			(width 0.2)
			(type default)
		)
		(layer "In6.Cu")
	)
	(gr_arc
		(start 34.81959 -180.796438)
		(mid 35.33013 -181.306978)
		(end 35.84067 -180.796438)
		(stroke
			(width 0.2)
			(type default)
		)
		(layer "In6.Cu")
	)
	(gr_line
		(start 34.81959 -179.983638)
		(end 34.81959 -180.796438)
		(stroke
			(width 0.2)
			(type default)
		)
		(layer "In6.Cu")
	)
	(gr_arc
		(start 34.81959 -175.996346)
		(mid 35.33013 -176.506886)
		(end 35.84067 -175.996346)
		(stroke
			(width 0.2)
			(type default)
		)
		(layer "In6.Cu")
	)
	(gr_line
		(start 34.81959 -175.183546)
		(end 34.81959 -175.996346)
		(stroke
			(width 0.2)
			(type default)
		)
		(layer "In6.Cu")
	)
	(gr_arc
		(start 34.81959 -171.196508)
		(mid 35.33013 -171.707048)
		(end 35.84067 -171.196508)
		(stroke
			(width 0.2)
			(type default)
		)
		(layer "In6.Cu")
	)
	(gr_line
		(start 34.81959 -170.383708)
		(end 34.81959 -171.196508)
		(stroke
			(width 0.2)
			(type default)
		)
		(layer "In6.Cu")
	)
	(gr_arc
		(start 34.81959 -158.396432)
		(mid 35.33013 -158.906972)
		(end 35.84067 -158.396432)
		(stroke
			(width 0.2)
			(type default)
		)
		(layer "In6.Cu")
	)
	(gr_line
		(start 34.81959 -157.583632)
		(end 34.81959 -158.396432)
		(stroke
			(width 0.2)
			(type default)
		)
		(layer "In6.Cu")
	)
	(gr_arc
		(start 34.81959 -77.79639)
		(mid 35.33013 -78.30693)
		(end 35.84067 -77.79639)
		(stroke
			(width 0.2)
			(type default)
		)
		(layer "In6.Cu")
	)
	(gr_line
		(start 34.81959 -76.98359)
		(end 34.81959 -77.79639)
		(stroke
			(width 0.2)
			(type default)
		)
		(layer "In6.Cu")
	)
	(gr_arc
		(start 34.81959 -72.996298)
		(mid 35.33013 -73.506838)
		(end 35.84067 -72.996298)
		(stroke
			(width 0.2)
			(type default)
		)
		(layer "In6.Cu")
	)
	(gr_line
		(start 34.81959 -72.183498)
		(end 34.81959 -72.996298)
		(stroke
			(width 0.2)
			(type default)
		)
		(layer "In6.Cu")
	)
	(gr_arc
		(start 34.81959 -68.19646)
		(mid 35.33013 -68.707)
		(end 35.84067 -68.19646)
		(stroke
			(width 0.2)
			(type default)
		)
		(layer "In6.Cu")
	)
	(gr_line
		(start 34.81959 -67.38366)
		(end 34.81959 -68.19646)
		(stroke
			(width 0.2)
			(type default)
		)
		(layer "In6.Cu")
	)
	(gr_arc
		(start 34.81959 -55.396384)
		(mid 35.33013 -55.906924)
		(end 35.84067 -55.396384)
		(stroke
			(width 0.2)
			(type default)
		)
		(layer "In6.Cu")
	)
	(gr_line
		(start 34.81959 -54.583584)
		(end 34.81959 -55.396384)
		(stroke
			(width 0.2)
			(type default)
		)
		(layer "In6.Cu")
	)
	(gr_line
		(start 35.500056 -4.500118)
		(end 35.500056 -3.700018)
		(stroke
			(width 1.524)
			(type default)
		)
		(layer "In6.Cu")
	)
	(gr_arc
		(start 35.663124 -3.019552)
		(mid 35.541364 -3.350145)
		(end 35.500056 -3.700018)
		(stroke
			(width 1.524)
			(type default)
		)
		(layer "In6.Cu")
	)
	(gr_line
		(start 35.663124 -3.019552)
		(end 37.200078 0)
		(stroke
			(width 1.524)
			(type default)
		)
		(layer "In6.Cu")
	)
	(gr_line
		(start 35.84067 -489.796582)
		(end 35.84067 -488.983782)
		(stroke
			(width 0.2)
			(type default)
		)
		(layer "In6.Cu")
	)
	(gr_arc
		(start 35.84067 -488.983782)
		(mid 35.33013 -488.473242)
		(end 34.81959 -488.983782)
		(stroke
			(width 0.2)
			(type default)
		)
		(layer "In6.Cu")
	)
	(gr_line
		(start 35.84067 -484.99649)
		(end 35.84067 -484.18369)
		(stroke
			(width 0.2)
			(type default)
		)
		(layer "In6.Cu")
	)
	(gr_arc
		(start 35.84067 -484.18369)
		(mid 35.33013 -483.67315)
		(end 34.81959 -484.18369)
		(stroke
			(width 0.2)
			(type default)
		)
		(layer "In6.Cu")
	)
	(gr_line
		(start 35.84067 -480.196652)
		(end 35.84067 -479.383852)
		(stroke
			(width 0.2)
			(type default)
		)
		(layer "In6.Cu")
	)
	(gr_arc
		(start 35.84067 -479.383852)
		(mid 35.33013 -478.873312)
		(end 34.81959 -479.383852)
		(stroke
			(width 0.2)
			(type default)
		)
		(layer "In6.Cu")
	)
	(gr_line
		(start 35.84067 -467.396576)
		(end 35.84067 -466.583776)
		(stroke
			(width 0.2)
			(type default)
		)
		(layer "In6.Cu")
	)
	(gr_arc
		(start 35.84067 -466.583776)
		(mid 35.33013 -466.073236)
		(end 34.81959 -466.583776)
		(stroke
			(width 0.2)
			(type default)
		)
		(layer "In6.Cu")
	)
	(gr_line
		(start 35.84067 -386.796534)
		(end 35.84067 -385.983988)
		(stroke
			(width 0.2)
			(type default)
		)
		(layer "In6.Cu")
	)
	(gr_arc
		(start 35.84067 -385.983988)
		(mid 35.330257 -385.473194)
		(end 34.81959 -385.983734)
		(stroke
			(width 0.2)
			(type default)
		)
		(layer "In6.Cu")
	)
	(gr_line
		(start 35.84067 -381.996442)
		(end 35.84067 -381.183896)
		(stroke
			(width 0.2)
			(type default)
		)
		(layer "In6.Cu")
	)
	(gr_arc
		(start 35.84067 -381.183896)
		(mid 35.330257 -380.673102)
		(end 34.81959 -381.183642)
		(stroke
			(width 0.2)
			(type default)
		)
		(layer "In6.Cu")
	)
	(gr_line
		(start 35.84067 -377.196604)
		(end 35.84067 -376.384058)
		(stroke
			(width 0.2)
			(type default)
		)
		(layer "In6.Cu")
	)
	(gr_arc
		(start 35.84067 -376.384058)
		(mid 35.330257 -375.873264)
		(end 34.81959 -376.383804)
		(stroke
			(width 0.2)
			(type default)
		)
		(layer "In6.Cu")
	)
	(gr_line
		(start 35.84067 -364.396528)
		(end 35.84067 -363.583982)
		(stroke
			(width 0.2)
			(type default)
		)
		(layer "In6.Cu")
	)
	(gr_arc
		(start 35.84067 -363.583982)
		(mid 35.330257 -363.073188)
		(end 34.81959 -363.583728)
		(stroke
			(width 0.2)
			(type default)
		)
		(layer "In6.Cu")
	)
	(gr_line
		(start 35.84067 -283.796486)
		(end 35.84067 -282.98394)
		(stroke
			(width 0.2)
			(type default)
		)
		(layer "In6.Cu")
	)
	(gr_arc
		(start 35.84067 -282.98394)
		(mid 35.330257 -282.473146)
		(end 34.81959 -282.983686)
		(stroke
			(width 0.2)
			(type default)
		)
		(layer "In6.Cu")
	)
	(gr_line
		(start 35.84067 -278.996394)
		(end 35.84067 -278.183848)
		(stroke
			(width 0.2)
			(type default)
		)
		(layer "In6.Cu")
	)
	(gr_arc
		(start 35.84067 -278.183848)
		(mid 35.330257 -277.673054)
		(end 34.81959 -278.183594)
		(stroke
			(width 0.2)
			(type default)
		)
		(layer "In6.Cu")
	)
	(gr_line
		(start 35.84067 -274.196556)
		(end 35.84067 -273.38401)
		(stroke
			(width 0.2)
			(type default)
		)
		(layer "In6.Cu")
	)
	(gr_arc
		(start 35.84067 -273.38401)
		(mid 35.330257 -272.873216)
		(end 34.81959 -273.383756)
		(stroke
			(width 0.2)
			(type default)
		)
		(layer "In6.Cu")
	)
	(gr_line
		(start 35.84067 -261.39648)
		(end 35.84067 -260.583934)
		(stroke
			(width 0.2)
			(type default)
		)
		(layer "In6.Cu")
	)
	(gr_arc
		(start 35.84067 -260.583934)
		(mid 35.330257 -260.07314)
		(end 34.81959 -260.58368)
		(stroke
			(width 0.2)
			(type default)
		)
		(layer "In6.Cu")
	)
	(gr_line
		(start 35.84067 -180.796438)
		(end 35.84067 -179.983892)
		(stroke
			(width 0.2)
			(type default)
		)
		(layer "In6.Cu")
	)
	(gr_arc
		(start 35.84067 -179.983892)
		(mid 35.330257 -179.473098)
		(end 34.81959 -179.983638)
		(stroke
			(width 0.2)
			(type default)
		)
		(layer "In6.Cu")
	)
	(gr_line
		(start 35.84067 -175.996346)
		(end 35.84067 -175.1838)
		(stroke
			(width 0.2)
			(type default)
		)
		(layer "In6.Cu")
	)
	(gr_arc
		(start 35.84067 -175.1838)
		(mid 35.330257 -174.673006)
		(end 34.81959 -175.183546)
		(stroke
			(width 0.2)
			(type default)
		)
		(layer "In6.Cu")
	)
	(gr_line
		(start 35.84067 -171.196508)
		(end 35.84067 -170.383962)
		(stroke
			(width 0.2)
			(type default)
		)
		(layer "In6.Cu")
	)
	(gr_arc
		(start 35.84067 -170.383962)
		(mid 35.330257 -169.873168)
		(end 34.81959 -170.383708)
		(stroke
			(width 0.2)
			(type default)
		)
		(layer "In6.Cu")
	)
	(gr_line
		(start 35.84067 -158.396432)
		(end 35.84067 -157.583886)
		(stroke
			(width 0.2)
			(type default)
		)
		(layer "In6.Cu")
	)
	(gr_arc
		(start 35.84067 -157.583886)
		(mid 35.330257 -157.073092)
		(end 34.81959 -157.583632)
		(stroke
			(width 0.2)
			(type default)
		)
		(layer "In6.Cu")
	)
	(gr_line
		(start 35.84067 -77.79639)
		(end 35.84067 -76.983844)
		(stroke
			(width 0.2)
			(type default)
		)
		(layer "In6.Cu")
	)
	(gr_arc
		(start 35.84067 -76.983844)
		(mid 35.330257 -76.47305)
		(end 34.81959 -76.98359)
		(stroke
			(width 0.2)
			(type default)
		)
		(layer "In6.Cu")
	)
	(gr_line
		(start 35.84067 -72.996298)
		(end 35.84067 -72.183752)
		(stroke
			(width 0.2)
			(type default)
		)
		(layer "In6.Cu")
	)
	(gr_arc
		(start 35.84067 -72.183752)
		(mid 35.330257 -71.672958)
		(end 34.81959 -72.183498)
		(stroke
			(width 0.2)
			(type default)
		)
		(layer "In6.Cu")
	)
	(gr_line
		(start 35.84067 -68.19646)
		(end 35.84067 -67.383914)
		(stroke
			(width 0.2)
			(type default)
		)
		(layer "In6.Cu")
	)
	(gr_arc
		(start 35.84067 -67.383914)
		(mid 35.330257 -66.87312)
		(end 34.81959 -67.38366)
		(stroke
			(width 0.2)
			(type default)
		)
		(layer "In6.Cu")
	)
	(gr_line
		(start 35.84067 -55.396384)
		(end 35.84067 -54.583838)
		(stroke
			(width 0.2)
			(type default)
		)
		(layer "In6.Cu")
	)
	(gr_arc
		(start 35.84067 -54.583838)
		(mid 35.330257 -54.073044)
		(end 34.81959 -54.583584)
		(stroke
			(width 0.2)
			(type default)
		)
		(layer "In6.Cu")
	)
	(gr_arc
		(start 36.11499 -492.348774)
		(mid 36.727003 -492.961168)
		(end 37.33927 -492.349028)
		(stroke
			(width 0.2)
			(type default)
		)
		(layer "In6.Cu")
	)
	(gr_line
		(start 36.11499 -491.231428)
		(end 36.11499 -492.348774)
		(stroke
			(width 0.2)
			(type default)
		)
		(layer "In6.Cu")
	)
	(gr_arc
		(start 36.11499 -487.548936)
		(mid 36.72713 -488.161076)
		(end 37.33927 -487.548936)
		(stroke
			(width 0.2)
			(type default)
		)
		(layer "In6.Cu")
	)
	(gr_line
		(start 36.11499 -486.431336)
		(end 36.11499 -487.548936)
		(stroke
			(width 0.2)
			(type default)
		)
		(layer "In6.Cu")
	)
	(gr_arc
		(start 36.11499 -482.74859)
		(mid 36.727003 -483.360984)
		(end 37.33927 -482.748844)
		(stroke
			(width 0.2)
			(type default)
		)
		(layer "In6.Cu")
	)
	(gr_line
		(start 36.11499 -481.631244)
		(end 36.11499 -482.74859)
		(stroke
			(width 0.2)
			(type default)
		)
		(layer "In6.Cu")
	)
	(gr_arc
		(start 36.11499 -469.948768)
		(mid 36.727003 -470.561162)
		(end 37.33927 -469.949022)
		(stroke
			(width 0.2)
			(type default)
		)
		(layer "In6.Cu")
	)
	(gr_line
		(start 36.11499 -468.831422)
		(end 36.11499 -469.948768)
		(stroke
			(width 0.2)
			(type default)
		)
		(layer "In6.Cu")
	)
	(gr_arc
		(start 36.11499 -389.34898)
		(mid 36.72713 -389.96112)
		(end 37.33927 -389.34898)
		(stroke
			(width 0.2)
			(type default)
		)
		(layer "In6.Cu")
	)
	(gr_line
		(start 36.11499 -388.23138)
		(end 36.11499 -389.34898)
		(stroke
			(width 0.2)
			(type default)
		)
		(layer "In6.Cu")
	)
	(gr_arc
		(start 36.11499 -384.548888)
		(mid 36.72713 -385.161028)
		(end 37.33927 -384.548888)
		(stroke
			(width 0.2)
			(type default)
		)
		(layer "In6.Cu")
	)
	(gr_line
		(start 36.11499 -383.431288)
		(end 36.11499 -384.548888)
		(stroke
			(width 0.2)
			(type default)
		)
		(layer "In6.Cu")
	)
	(gr_arc
		(start 36.11499 -379.748796)
		(mid 36.72713 -380.360936)
		(end 37.33927 -379.748796)
		(stroke
			(width 0.2)
			(type default)
		)
		(layer "In6.Cu")
	)
	(gr_line
		(start 36.11499 -378.631196)
		(end 36.11499 -379.748796)
		(stroke
			(width 0.2)
			(type default)
		)
		(layer "In6.Cu")
	)
	(gr_arc
		(start 36.11499 -366.948974)
		(mid 36.72713 -367.561114)
		(end 37.33927 -366.948974)
		(stroke
			(width 0.2)
			(type default)
		)
		(layer "In6.Cu")
	)
	(gr_line
		(start 36.11499 -365.831374)
		(end 36.11499 -366.948974)
		(stroke
			(width 0.2)
			(type default)
		)
		(layer "In6.Cu")
	)
	(gr_arc
		(start 36.11499 -286.348932)
		(mid 36.72713 -286.961072)
		(end 37.33927 -286.348932)
		(stroke
			(width 0.2)
			(type default)
		)
		(layer "In6.Cu")
	)
	(gr_line
		(start 36.11499 -285.231332)
		(end 36.11499 -286.348932)
		(stroke
			(width 0.2)
			(type default)
		)
		(layer "In6.Cu")
	)
	(gr_arc
		(start 36.11499 -281.54884)
		(mid 36.72713 -282.16098)
		(end 37.33927 -281.54884)
		(stroke
			(width 0.2)
			(type default)
		)
		(layer "In6.Cu")
	)
	(gr_line
		(start 36.11499 -280.43124)
		(end 36.11499 -281.54884)
		(stroke
			(width 0.2)
			(type default)
		)
		(layer "In6.Cu")
	)
	(gr_arc
		(start 36.11499 -276.748748)
		(mid 36.72713 -277.360888)
		(end 37.33927 -276.748748)
		(stroke
			(width 0.2)
			(type default)
		)
		(layer "In6.Cu")
	)
	(gr_line
		(start 36.11499 -275.631148)
		(end 36.11499 -276.748748)
		(stroke
			(width 0.2)
			(type default)
		)
		(layer "In6.Cu")
	)
	(gr_arc
		(start 36.11499 -263.948926)
		(mid 36.72713 -264.561066)
		(end 37.33927 -263.948926)
		(stroke
			(width 0.2)
			(type default)
		)
		(layer "In6.Cu")
	)
	(gr_line
		(start 36.11499 -262.831326)
		(end 36.11499 -263.948926)
		(stroke
			(width 0.2)
			(type default)
		)
		(layer "In6.Cu")
	)
	(gr_arc
		(start 36.11499 -183.348884)
		(mid 36.72713 -183.961024)
		(end 37.33927 -183.348884)
		(stroke
			(width 0.2)
			(type default)
		)
		(layer "In6.Cu")
	)
	(gr_line
		(start 36.11499 -182.231284)
		(end 36.11499 -183.348884)
		(stroke
			(width 0.2)
			(type default)
		)
		(layer "In6.Cu")
	)
	(gr_arc
		(start 36.11499 -178.548792)
		(mid 36.72713 -179.160932)
		(end 37.33927 -178.548792)
		(stroke
			(width 0.2)
			(type default)
		)
		(layer "In6.Cu")
	)
	(gr_line
		(start 36.11499 -177.431192)
		(end 36.11499 -178.548792)
		(stroke
			(width 0.2)
			(type default)
		)
		(layer "In6.Cu")
	)
	(gr_arc
		(start 36.11499 -173.7487)
		(mid 36.72713 -174.36084)
		(end 37.33927 -173.7487)
		(stroke
			(width 0.2)
			(type default)
		)
		(layer "In6.Cu")
	)
	(gr_line
		(start 36.11499 -172.6311)
		(end 36.11499 -173.7487)
		(stroke
			(width 0.2)
			(type default)
		)
		(layer "In6.Cu")
	)
	(gr_arc
		(start 36.11499 -160.948878)
		(mid 36.72713 -161.561018)
		(end 37.33927 -160.948878)
		(stroke
			(width 0.2)
			(type default)
		)
		(layer "In6.Cu")
	)
	(gr_line
		(start 36.11499 -159.831278)
		(end 36.11499 -160.948878)
		(stroke
			(width 0.2)
			(type default)
		)
		(layer "In6.Cu")
	)
	(gr_arc
		(start 36.11499 -80.348836)
		(mid 36.72713 -80.960976)
		(end 37.33927 -80.348836)
		(stroke
			(width 0.2)
			(type default)
		)
		(layer "In6.Cu")
	)
	(gr_line
		(start 36.11499 -79.231236)
		(end 36.11499 -80.348836)
		(stroke
			(width 0.2)
			(type default)
		)
		(layer "In6.Cu")
	)
	(gr_arc
		(start 36.11499 -75.548744)
		(mid 36.72713 -76.160884)
		(end 37.33927 -75.548744)
		(stroke
			(width 0.2)
			(type default)
		)
		(layer "In6.Cu")
	)
	(gr_line
		(start 36.11499 -74.431144)
		(end 36.11499 -75.548744)
		(stroke
			(width 0.2)
			(type default)
		)
		(layer "In6.Cu")
	)
	(gr_arc
		(start 36.11499 -70.748652)
		(mid 36.72713 -71.360792)
		(end 37.33927 -70.748652)
		(stroke
			(width 0.2)
			(type default)
		)
		(layer "In6.Cu")
	)
	(gr_line
		(start 36.11499 -69.631052)
		(end 36.11499 -70.748652)
		(stroke
			(width 0.2)
			(type default)
		)
		(layer "In6.Cu")
	)
	(gr_arc
		(start 36.11499 -57.94883)
		(mid 36.72713 -58.56097)
		(end 37.33927 -57.94883)
		(stroke
			(width 0.2)
			(type default)
		)
		(layer "In6.Cu")
	)
	(gr_line
		(start 36.11499 -56.83123)
		(end 36.11499 -57.94883)
		(stroke
			(width 0.2)
			(type default)
		)
		(layer "In6.Cu")
	)
	(gr_line
		(start 37.200078 0)
		(end 262.50011 0)
		(stroke
			(width 1.524)
			(type default)
		)
		(layer "In6.Cu")
	)
	(gr_line
		(start 37.33927 -492.349028)
		(end 37.33927 -491.231428)
		(stroke
			(width 0.2)
			(type default)
		)
		(layer "In6.Cu")
	)
	(gr_arc
		(start 37.33927 -491.231428)
		(mid 36.72713 -490.619288)
		(end 36.11499 -491.231428)
		(stroke
			(width 0.2)
			(type default)
		)
		(layer "In6.Cu")
	)
	(gr_line
		(start 37.33927 -487.548936)
		(end 37.33927 -486.43159)
		(stroke
			(width 0.2)
			(type default)
		)
		(layer "In6.Cu")
	)
	(gr_arc
		(start 37.33927 -486.43159)
		(mid 36.727257 -485.819196)
		(end 36.11499 -486.431336)
		(stroke
			(width 0.2)
			(type default)
		)
		(layer "In6.Cu")
	)
	(gr_line
		(start 37.33927 -482.748844)
		(end 37.33927 -481.631244)
		(stroke
			(width 0.2)
			(type default)
		)
		(layer "In6.Cu")
	)
	(gr_arc
		(start 37.33927 -481.631244)
		(mid 36.72713 -481.019104)
		(end 36.11499 -481.631244)
		(stroke
			(width 0.2)
			(type default)
		)
		(layer "In6.Cu")
	)
	(gr_line
		(start 37.33927 -469.949022)
		(end 37.33927 -468.831422)
		(stroke
			(width 0.2)
			(type default)
		)
		(layer "In6.Cu")
	)
	(gr_arc
		(start 37.33927 -468.831422)
		(mid 36.72713 -468.219282)
		(end 36.11499 -468.831422)
		(stroke
			(width 0.2)
			(type default)
		)
		(layer "In6.Cu")
	)
	(gr_line
		(start 37.33927 -389.34898)
		(end 37.33927 -388.231634)
		(stroke
			(width 0.2)
			(type default)
		)
		(layer "In6.Cu")
	)
	(gr_arc
		(start 37.33927 -388.231634)
		(mid 36.727257 -387.61924)
		(end 36.11499 -388.23138)
		(stroke
			(width 0.2)
			(type default)
		)
		(layer "In6.Cu")
	)
	(gr_line
		(start 37.33927 -384.548888)
		(end 37.33927 -383.431542)
		(stroke
			(width 0.2)
			(type default)
		)
		(layer "In6.Cu")
	)
	(gr_arc
		(start 37.33927 -383.431542)
		(mid 36.727257 -382.819148)
		(end 36.11499 -383.431288)
		(stroke
			(width 0.2)
			(type default)
		)
		(layer "In6.Cu")
	)
	(gr_line
		(start 37.33927 -379.748796)
		(end 37.33927 -378.63145)
		(stroke
			(width 0.2)
			(type default)
		)
		(layer "In6.Cu")
	)
	(gr_arc
		(start 37.33927 -378.63145)
		(mid 36.727257 -378.019056)
		(end 36.11499 -378.631196)
		(stroke
			(width 0.2)
			(type default)
		)
		(layer "In6.Cu")
	)
	(gr_line
		(start 37.33927 -366.948974)
		(end 37.33927 -365.831628)
		(stroke
			(width 0.2)
			(type default)
		)
		(layer "In6.Cu")
	)
	(gr_arc
		(start 37.33927 -365.831628)
		(mid 36.727257 -365.219234)
		(end 36.11499 -365.831374)
		(stroke
			(width 0.2)
			(type default)
		)
		(layer "In6.Cu")
	)
	(gr_line
		(start 37.33927 -286.348932)
		(end 37.33927 -285.231586)
		(stroke
			(width 0.2)
			(type default)
		)
		(layer "In6.Cu")
	)
	(gr_arc
		(start 37.33927 -285.231586)
		(mid 36.727257 -284.619192)
		(end 36.11499 -285.231332)
		(stroke
			(width 0.2)
			(type default)
		)
		(layer "In6.Cu")
	)
	(gr_line
		(start 37.33927 -281.54884)
		(end 37.33927 -280.431494)
		(stroke
			(width 0.2)
			(type default)
		)
		(layer "In6.Cu")
	)
	(gr_arc
		(start 37.33927 -280.431494)
		(mid 36.727257 -279.8191)
		(end 36.11499 -280.43124)
		(stroke
			(width 0.2)
			(type default)
		)
		(layer "In6.Cu")
	)
	(gr_line
		(start 37.33927 -276.748748)
		(end 37.33927 -275.631402)
		(stroke
			(width 0.2)
			(type default)
		)
		(layer "In6.Cu")
	)
	(gr_arc
		(start 37.33927 -275.631402)
		(mid 36.727257 -275.019008)
		(end 36.11499 -275.631148)
		(stroke
			(width 0.2)
			(type default)
		)
		(layer "In6.Cu")
	)
	(gr_line
		(start 37.33927 -263.948926)
		(end 37.33927 -262.83158)
		(stroke
			(width 0.2)
			(type default)
		)
		(layer "In6.Cu")
	)
	(gr_arc
		(start 37.33927 -262.83158)
		(mid 36.727257 -262.219186)
		(end 36.11499 -262.831326)
		(stroke
			(width 0.2)
			(type default)
		)
		(layer "In6.Cu")
	)
	(gr_line
		(start 37.33927 -183.348884)
		(end 37.33927 -182.231538)
		(stroke
			(width 0.2)
			(type default)
		)
		(layer "In6.Cu")
	)
	(gr_arc
		(start 37.33927 -182.231538)
		(mid 36.727257 -181.619144)
		(end 36.11499 -182.231284)
		(stroke
			(width 0.2)
			(type default)
		)
		(layer "In6.Cu")
	)
	(gr_line
		(start 37.33927 -178.548792)
		(end 37.33927 -177.431446)
		(stroke
			(width 0.2)
			(type default)
		)
		(layer "In6.Cu")
	)
	(gr_arc
		(start 37.33927 -177.431446)
		(mid 36.727257 -176.819052)
		(end 36.11499 -177.431192)
		(stroke
			(width 0.2)
			(type default)
		)
		(layer "In6.Cu")
	)
	(gr_line
		(start 37.33927 -173.7487)
		(end 37.33927 -172.631354)
		(stroke
			(width 0.2)
			(type default)
		)
		(layer "In6.Cu")
	)
	(gr_arc
		(start 37.33927 -172.631354)
		(mid 36.727257 -172.01896)
		(end 36.11499 -172.6311)
		(stroke
			(width 0.2)
			(type default)
		)
		(layer "In6.Cu")
	)
	(gr_line
		(start 37.33927 -160.948878)
		(end 37.33927 -159.831532)
		(stroke
			(width 0.2)
			(type default)
		)
		(layer "In6.Cu")
	)
	(gr_arc
		(start 37.33927 -159.831532)
		(mid 36.727257 -159.219138)
		(end 36.11499 -159.831278)
		(stroke
			(width 0.2)
			(type default)
		)
		(layer "In6.Cu")
	)
	(gr_line
		(start 37.33927 -80.348836)
		(end 37.33927 -79.23149)
		(stroke
			(width 0.2)
			(type default)
		)
		(layer "In6.Cu")
	)
	(gr_arc
		(start 37.33927 -79.23149)
		(mid 36.727257 -78.619096)
		(end 36.11499 -79.231236)
		(stroke
			(width 0.2)
			(type default)
		)
		(layer "In6.Cu")
	)
	(gr_line
		(start 37.33927 -75.548744)
		(end 37.33927 -74.431398)
		(stroke
			(width 0.2)
			(type default)
		)
		(layer "In6.Cu")
	)
	(gr_arc
		(start 37.33927 -74.431398)
		(mid 36.727257 -73.819004)
		(end 36.11499 -74.431144)
		(stroke
			(width 0.2)
			(type default)
		)
		(layer "In6.Cu")
	)
	(gr_line
		(start 37.33927 -70.748652)
		(end 37.33927 -69.631306)
		(stroke
			(width 0.2)
			(type default)
		)
		(layer "In6.Cu")
	)
	(gr_arc
		(start 37.33927 -69.631306)
		(mid 36.727257 -69.018912)
		(end 36.11499 -69.631052)
		(stroke
			(width 0.2)
			(type default)
		)
		(layer "In6.Cu")
	)
	(gr_line
		(start 37.33927 -57.94883)
		(end 37.33927 -56.831484)
		(stroke
			(width 0.2)
			(type default)
		)
		(layer "In6.Cu")
	)
	(gr_arc
		(start 37.33927 -56.831484)
		(mid 36.727257 -56.21909)
		(end 36.11499 -56.83123)
		(stroke
			(width 0.2)
			(type default)
		)
		(layer "In6.Cu")
	)
	(gr_arc
		(start 41.90746 -239.397286)
		(mid 42.418 -239.907826)
		(end 42.92854 -239.397286)
		(stroke
			(width 0.2)
			(type default)
		)
		(layer "In6.Cu")
	)
	(gr_line
		(start 41.90746 -238.584486)
		(end 41.90746 -239.397286)
		(stroke
			(width 0.2)
			(type default)
		)
		(layer "In6.Cu")
	)
	(gr_line
		(start 42.92854 -239.397286)
		(end 42.92854 -238.58474)
		(stroke
			(width 0.2)
			(type default)
		)
		(layer "In6.Cu")
	)
	(gr_arc
		(start 42.92854 -238.58474)
		(mid 42.418127 -238.073946)
		(end 41.90746 -238.584486)
		(stroke
			(width 0.2)
			(type default)
		)
		(layer "In6.Cu")
	)
	(gr_line
		(start 44.9072 -472.300808)
		(end 45.719746 -472.300808)
		(stroke
			(width 0.2)
			(type default)
		)
		(layer "In6.Cu")
	)
	(gr_arc
		(start 44.9072 -471.279728)
		(mid 44.39666 -471.790268)
		(end 44.9072 -472.300808)
		(stroke
			(width 0.2)
			(type default)
		)
		(layer "In6.Cu")
	)
	(gr_line
		(start 44.9072 -369.30076)
		(end 45.72 -369.30076)
		(stroke
			(width 0.2)
			(type default)
		)
		(layer "In6.Cu")
	)
	(gr_line
		(start 44.9072 -266.300712)
		(end 45.72 -266.300712)
		(stroke
			(width 0.2)
			(type default)
		)
		(layer "In6.Cu")
	)
	(gr_line
		(start 44.9072 -163.300664)
		(end 45.72 -163.300664)
		(stroke
			(width 0.2)
			(type default)
		)
		(layer "In6.Cu")
	)
	(gr_line
		(start 44.9072 -60.300616)
		(end 45.72 -60.300616)
		(stroke
			(width 0.2)
			(type default)
		)
		(layer "In6.Cu")
	)
	(gr_arc
		(start 44.907454 -368.27968)
		(mid 44.39666 -368.790093)
		(end 44.9072 -369.30076)
		(stroke
			(width 0.2)
			(type default)
		)
		(layer "In6.Cu")
	)
	(gr_arc
		(start 44.907454 -265.279632)
		(mid 44.39666 -265.790045)
		(end 44.9072 -266.300712)
		(stroke
			(width 0.2)
			(type default)
		)
		(layer "In6.Cu")
	)
	(gr_arc
		(start 44.907454 -162.279584)
		(mid 44.39666 -162.789997)
		(end 44.9072 -163.300664)
		(stroke
			(width 0.2)
			(type default)
		)
		(layer "In6.Cu")
	)
	(gr_arc
		(start 44.907454 -59.279536)
		(mid 44.39666 -59.789949)
		(end 44.9072 -60.300616)
		(stroke
			(width 0.2)
			(type default)
		)
		(layer "In6.Cu")
	)
	(gr_arc
		(start 45.719746 -472.300808)
		(mid 46.23054 -471.790395)
		(end 45.72 -471.279728)
		(stroke
			(width 0.2)
			(type default)
		)
		(layer "In6.Cu")
	)
	(gr_line
		(start 45.72 -471.279728)
		(end 44.9072 -471.279728)
		(stroke
			(width 0.2)
			(type default)
		)
		(layer "In6.Cu")
	)
	(gr_arc
		(start 45.72 -369.30076)
		(mid 46.23054 -368.79022)
		(end 45.72 -368.27968)
		(stroke
			(width 0.2)
			(type default)
		)
		(layer "In6.Cu")
	)
	(gr_line
		(start 45.72 -368.27968)
		(end 44.907454 -368.27968)
		(stroke
			(width 0.2)
			(type default)
		)
		(layer "In6.Cu")
	)
	(gr_arc
		(start 45.72 -266.300712)
		(mid 46.23054 -265.790172)
		(end 45.72 -265.279632)
		(stroke
			(width 0.2)
			(type default)
		)
		(layer "In6.Cu")
	)
	(gr_line
		(start 45.72 -265.279632)
		(end 44.907454 -265.279632)
		(stroke
			(width 0.2)
			(type default)
		)
		(layer "In6.Cu")
	)
	(gr_arc
		(start 45.72 -163.300664)
		(mid 46.23054 -162.790124)
		(end 45.72 -162.279584)
		(stroke
			(width 0.2)
			(type default)
		)
		(layer "In6.Cu")
	)
	(gr_line
		(start 45.72 -162.279584)
		(end 44.907454 -162.279584)
		(stroke
			(width 0.2)
			(type default)
		)
		(layer "In6.Cu")
	)
	(gr_arc
		(start 45.72 -60.300616)
		(mid 46.23054 -59.790076)
		(end 45.72 -59.279536)
		(stroke
			(width 0.2)
			(type default)
		)
		(layer "In6.Cu")
	)
	(gr_line
		(start 45.72 -59.279536)
		(end 44.907454 -59.279536)
		(stroke
			(width 0.2)
			(type default)
		)
		(layer "In6.Cu")
	)
	(gr_arc
		(start 47.87646 -473.392246)
		(mid 48.387 -473.902786)
		(end 48.89754 -473.392246)
		(stroke
			(width 0.2)
			(type default)
		)
		(layer "In6.Cu")
	)
	(gr_line
		(start 47.87646 -472.579446)
		(end 47.87646 -473.392246)
		(stroke
			(width 0.2)
			(type default)
		)
		(layer "In6.Cu")
	)
	(gr_arc
		(start 47.87646 -370.392198)
		(mid 48.387 -370.902738)
		(end 48.89754 -370.392198)
		(stroke
			(width 0.2)
			(type default)
		)
		(layer "In6.Cu")
	)
	(gr_line
		(start 47.87646 -369.579398)
		(end 47.87646 -370.392198)
		(stroke
			(width 0.2)
			(type default)
		)
		(layer "In6.Cu")
	)
	(gr_arc
		(start 47.87646 -267.39215)
		(mid 48.387 -267.90269)
		(end 48.89754 -267.39215)
		(stroke
			(width 0.2)
			(type default)
		)
		(layer "In6.Cu")
	)
	(gr_line
		(start 47.87646 -266.57935)
		(end 47.87646 -267.39215)
		(stroke
			(width 0.2)
			(type default)
		)
		(layer "In6.Cu")
	)
	(gr_arc
		(start 47.87646 -164.392102)
		(mid 48.387 -164.902642)
		(end 48.89754 -164.392102)
		(stroke
			(width 0.2)
			(type default)
		)
		(layer "In6.Cu")
	)
	(gr_line
		(start 47.87646 -163.579302)
		(end 47.87646 -164.392102)
		(stroke
			(width 0.2)
			(type default)
		)
		(layer "In6.Cu")
	)
	(gr_arc
		(start 47.87646 -61.392054)
		(mid 48.387 -61.902594)
		(end 48.89754 -61.392054)
		(stroke
			(width 0.2)
			(type default)
		)
		(layer "In6.Cu")
	)
	(gr_line
		(start 47.87646 -60.579254)
		(end 47.87646 -61.392054)
		(stroke
			(width 0.2)
			(type default)
		)
		(layer "In6.Cu")
	)
	(gr_line
		(start 48.89754 -473.392246)
		(end 48.89754 -472.5797)
		(stroke
			(width 0.2)
			(type default)
		)
		(layer "In6.Cu")
	)
	(gr_arc
		(start 48.89754 -472.5797)
		(mid 48.387127 -472.068906)
		(end 47.87646 -472.579446)
		(stroke
			(width 0.2)
			(type default)
		)
		(layer "In6.Cu")
	)
	(gr_line
		(start 48.89754 -370.392198)
		(end 48.89754 -369.579652)
		(stroke
			(width 0.2)
			(type default)
		)
		(layer "In6.Cu")
	)
	(gr_arc
		(start 48.89754 -369.579652)
		(mid 48.387127 -369.068858)
		(end 47.87646 -369.579398)
		(stroke
			(width 0.2)
			(type default)
		)
		(layer "In6.Cu")
	)
	(gr_line
		(start 48.89754 -267.39215)
		(end 48.89754 -266.579604)
		(stroke
			(width 0.2)
			(type default)
		)
		(layer "In6.Cu")
	)
	(gr_arc
		(start 48.89754 -266.579604)
		(mid 48.387127 -266.06881)
		(end 47.87646 -266.57935)
		(stroke
			(width 0.2)
			(type default)
		)
		(layer "In6.Cu")
	)
	(gr_line
		(start 48.89754 -164.392102)
		(end 48.89754 -163.579556)
		(stroke
			(width 0.2)
			(type default)
		)
		(layer "In6.Cu")
	)
	(gr_arc
		(start 48.89754 -163.579556)
		(mid 48.387127 -163.068762)
		(end 47.87646 -163.579302)
		(stroke
			(width 0.2)
			(type default)
		)
		(layer "In6.Cu")
	)
	(gr_line
		(start 48.89754 -61.392054)
		(end 48.89754 -60.579508)
		(stroke
			(width 0.2)
			(type default)
		)
		(layer "In6.Cu")
	)
	(gr_arc
		(start 48.89754 -60.579508)
		(mid 48.387127 -60.068714)
		(end 47.87646 -60.579254)
		(stroke
			(width 0.2)
			(type default)
		)
		(layer "In6.Cu")
	)
	(gr_arc
		(start 71.87946 -431.9524)
		(mid 72.39 -432.46294)
		(end 72.90054 -431.9524)
		(stroke
			(width 0.2)
			(type default)
		)
		(layer "In6.Cu")
	)
	(gr_line
		(start 71.87946 -431.1396)
		(end 71.87946 -431.9524)
		(stroke
			(width 0.2)
			(type default)
		)
		(layer "In6.Cu")
	)
	(gr_line
		(start 72.90054 -431.9524)
		(end 72.90054 -431.139854)
		(stroke
			(width 0.2)
			(type default)
		)
		(layer "In6.Cu")
	)
	(gr_arc
		(start 72.90054 -431.139854)
		(mid 72.390127 -430.62906)
		(end 71.87946 -431.1396)
		(stroke
			(width 0.2)
			(type default)
		)
		(layer "In6.Cu")
	)
	(gr_line
		(start 74.2696 -430.63414)
		(end 75.0824 -430.63414)
		(stroke
			(width 0.2)
			(type default)
		)
		(layer "In6.Cu")
	)
	(gr_arc
		(start 74.269854 -429.61306)
		(mid 73.75906 -430.123473)
		(end 74.2696 -430.63414)
		(stroke
			(width 0.2)
			(type default)
		)
		(layer "In6.Cu")
	)
	(gr_arc
		(start 75.0824 -430.63414)
		(mid 75.59294 -430.1236)
		(end 75.0824 -429.61306)
		(stroke
			(width 0.2)
			(type default)
		)
		(layer "In6.Cu")
	)
	(gr_line
		(start 75.0824 -429.61306)
		(end 74.269854 -429.61306)
		(stroke
			(width 0.2)
			(type default)
		)
		(layer "In6.Cu")
	)
	(gr_arc
		(start 219.819474 -489.796582)
		(mid 220.330014 -490.307122)
		(end 220.840554 -489.796582)
		(stroke
			(width 0.2)
			(type default)
		)
		(layer "In6.Cu")
	)
	(gr_line
		(start 219.819474 -488.983782)
		(end 219.819474 -489.796582)
		(stroke
			(width 0.2)
			(type default)
		)
		(layer "In6.Cu")
	)
	(gr_arc
		(start 219.819474 -484.99649)
		(mid 220.330014 -485.50703)
		(end 220.840554 -484.99649)
		(stroke
			(width 0.2)
			(type default)
		)
		(layer "In6.Cu")
	)
	(gr_line
		(start 219.819474 -484.18369)
		(end 219.819474 -484.99649)
		(stroke
			(width 0.2)
			(type default)
		)
		(layer "In6.Cu")
	)
	(gr_arc
		(start 219.819474 -480.196652)
		(mid 220.330014 -480.707192)
		(end 220.840554 -480.196652)
		(stroke
			(width 0.2)
			(type default)
		)
		(layer "In6.Cu")
	)
	(gr_line
		(start 219.819474 -479.383852)
		(end 219.819474 -480.196652)
		(stroke
			(width 0.2)
			(type default)
		)
		(layer "In6.Cu")
	)
	(gr_arc
		(start 219.819474 -467.396576)
		(mid 220.330014 -467.907116)
		(end 220.840554 -467.396576)
		(stroke
			(width 0.2)
			(type default)
		)
		(layer "In6.Cu")
	)
	(gr_line
		(start 219.819474 -466.583776)
		(end 219.819474 -467.396576)
		(stroke
			(width 0.2)
			(type default)
		)
		(layer "In6.Cu")
	)
	(gr_arc
		(start 219.819474 -386.796534)
		(mid 220.330014 -387.307074)
		(end 220.840554 -386.796534)
		(stroke
			(width 0.2)
			(type default)
		)
		(layer "In6.Cu")
	)
	(gr_line
		(start 219.819474 -385.983734)
		(end 219.819474 -386.796534)
		(stroke
			(width 0.2)
			(type default)
		)
		(layer "In6.Cu")
	)
	(gr_arc
		(start 219.819474 -381.996442)
		(mid 220.330014 -382.506982)
		(end 220.840554 -381.996442)
		(stroke
			(width 0.2)
			(type default)
		)
		(layer "In6.Cu")
	)
	(gr_line
		(start 219.819474 -381.183642)
		(end 219.819474 -381.996442)
		(stroke
			(width 0.2)
			(type default)
		)
		(layer "In6.Cu")
	)
	(gr_arc
		(start 219.819474 -377.196604)
		(mid 220.330014 -377.707144)
		(end 220.840554 -377.196604)
		(stroke
			(width 0.2)
			(type default)
		)
		(layer "In6.Cu")
	)
	(gr_line
		(start 219.819474 -376.383804)
		(end 219.819474 -377.196604)
		(stroke
			(width 0.2)
			(type default)
		)
		(layer "In6.Cu")
	)
	(gr_arc
		(start 219.819474 -364.396528)
		(mid 220.330014 -364.907068)
		(end 220.840554 -364.396528)
		(stroke
			(width 0.2)
			(type default)
		)
		(layer "In6.Cu")
	)
	(gr_line
		(start 219.819474 -363.583728)
		(end 219.819474 -364.396528)
		(stroke
			(width 0.2)
			(type default)
		)
		(layer "In6.Cu")
	)
	(gr_arc
		(start 219.819474 -283.796486)
		(mid 220.330014 -284.307026)
		(end 220.840554 -283.796486)
		(stroke
			(width 0.2)
			(type default)
		)
		(layer "In6.Cu")
	)
	(gr_line
		(start 219.819474 -282.983686)
		(end 219.819474 -283.796486)
		(stroke
			(width 0.2)
			(type default)
		)
		(layer "In6.Cu")
	)
	(gr_arc
		(start 219.819474 -278.996394)
		(mid 220.330014 -279.506934)
		(end 220.840554 -278.996394)
		(stroke
			(width 0.2)
			(type default)
		)
		(layer "In6.Cu")
	)
	(gr_line
		(start 219.819474 -278.183594)
		(end 219.819474 -278.996394)
		(stroke
			(width 0.2)
			(type default)
		)
		(layer "In6.Cu")
	)
	(gr_arc
		(start 219.819474 -274.196556)
		(mid 220.330014 -274.707096)
		(end 220.840554 -274.196556)
		(stroke
			(width 0.2)
			(type default)
		)
		(layer "In6.Cu")
	)
	(gr_line
		(start 219.819474 -273.383756)
		(end 219.819474 -274.196556)
		(stroke
			(width 0.2)
			(type default)
		)
		(layer "In6.Cu")
	)
	(gr_arc
		(start 219.819474 -261.39648)
		(mid 220.330014 -261.90702)
		(end 220.840554 -261.39648)
		(stroke
			(width 0.2)
			(type default)
		)
		(layer "In6.Cu")
	)
	(gr_line
		(start 219.819474 -260.58368)
		(end 219.819474 -261.39648)
		(stroke
			(width 0.2)
			(type default)
		)
		(layer "In6.Cu")
	)
	(gr_arc
		(start 219.819474 -180.796438)
		(mid 220.330014 -181.306978)
		(end 220.840554 -180.796438)
		(stroke
			(width 0.2)
			(type default)
		)
		(layer "In6.Cu")
	)
	(gr_line
		(start 219.819474 -179.983638)
		(end 219.819474 -180.796438)
		(stroke
			(width 0.2)
			(type default)
		)
		(layer "In6.Cu")
	)
	(gr_arc
		(start 219.819474 -175.996346)
		(mid 220.330014 -176.506886)
		(end 220.840554 -175.996346)
		(stroke
			(width 0.2)
			(type default)
		)
		(layer "In6.Cu")
	)
	(gr_line
		(start 219.819474 -175.183546)
		(end 219.819474 -175.996346)
		(stroke
			(width 0.2)
			(type default)
		)
		(layer "In6.Cu")
	)
	(gr_arc
		(start 219.819474 -171.196508)
		(mid 220.330014 -171.707048)
		(end 220.840554 -171.196508)
		(stroke
			(width 0.2)
			(type default)
		)
		(layer "In6.Cu")
	)
	(gr_line
		(start 219.819474 -170.383708)
		(end 219.819474 -171.196508)
		(stroke
			(width 0.2)
			(type default)
		)
		(layer "In6.Cu")
	)
	(gr_arc
		(start 219.819474 -158.396432)
		(mid 220.330014 -158.906972)
		(end 220.840554 -158.396432)
		(stroke
			(width 0.2)
			(type default)
		)
		(layer "In6.Cu")
	)
	(gr_line
		(start 219.819474 -157.583632)
		(end 219.819474 -158.396432)
		(stroke
			(width 0.2)
			(type default)
		)
		(layer "In6.Cu")
	)
	(gr_arc
		(start 219.819474 -77.79639)
		(mid 220.330014 -78.30693)
		(end 220.840554 -77.79639)
		(stroke
			(width 0.2)
			(type default)
		)
		(layer "In6.Cu")
	)
	(gr_line
		(start 219.819474 -76.98359)
		(end 219.819474 -77.79639)
		(stroke
			(width 0.2)
			(type default)
		)
		(layer "In6.Cu")
	)
	(gr_arc
		(start 219.819474 -72.996298)
		(mid 220.330014 -73.506838)
		(end 220.840554 -72.996298)
		(stroke
			(width 0.2)
			(type default)
		)
		(layer "In6.Cu")
	)
	(gr_line
		(start 219.819474 -72.183498)
		(end 219.819474 -72.996298)
		(stroke
			(width 0.2)
			(type default)
		)
		(layer "In6.Cu")
	)
	(gr_arc
		(start 219.819474 -68.19646)
		(mid 220.330014 -68.707)
		(end 220.840554 -68.19646)
		(stroke
			(width 0.2)
			(type default)
		)
		(layer "In6.Cu")
	)
	(gr_line
		(start 219.819474 -67.38366)
		(end 219.819474 -68.19646)
		(stroke
			(width 0.2)
			(type default)
		)
		(layer "In6.Cu")
	)
	(gr_arc
		(start 219.819474 -55.396384)
		(mid 220.330014 -55.906924)
		(end 220.840554 -55.396384)
		(stroke
			(width 0.2)
			(type default)
		)
		(layer "In6.Cu")
	)
	(gr_line
		(start 219.819474 -54.583584)
		(end 219.819474 -55.396384)
		(stroke
			(width 0.2)
			(type default)
		)
		(layer "In6.Cu")
	)
	(gr_line
		(start 220.840554 -489.796582)
		(end 220.840554 -488.984036)
		(stroke
			(width 0.2)
			(type default)
		)
		(layer "In6.Cu")
	)
	(gr_arc
		(start 220.840554 -488.984036)
		(mid 220.330141 -488.473242)
		(end 219.819474 -488.983782)
		(stroke
			(width 0.2)
			(type default)
		)
		(layer "In6.Cu")
	)
	(gr_line
		(start 220.840554 -484.99649)
		(end 220.840554 -484.183944)
		(stroke
			(width 0.2)
			(type default)
		)
		(layer "In6.Cu")
	)
	(gr_arc
		(start 220.840554 -484.183944)
		(mid 220.330141 -483.67315)
		(end 219.819474 -484.18369)
		(stroke
			(width 0.2)
			(type default)
		)
		(layer "In6.Cu")
	)
	(gr_line
		(start 220.840554 -480.196652)
		(end 220.840554 -479.384106)
		(stroke
			(width 0.2)
			(type default)
		)
		(layer "In6.Cu")
	)
	(gr_arc
		(start 220.840554 -479.384106)
		(mid 220.330141 -478.873312)
		(end 219.819474 -479.383852)
		(stroke
			(width 0.2)
			(type default)
		)
		(layer "In6.Cu")
	)
	(gr_line
		(start 220.840554 -467.396576)
		(end 220.840554 -466.58403)
		(stroke
			(width 0.2)
			(type default)
		)
		(layer "In6.Cu")
	)
	(gr_arc
		(start 220.840554 -466.58403)
		(mid 220.330141 -466.073236)
		(end 219.819474 -466.583776)
		(stroke
			(width 0.2)
			(type default)
		)
		(layer "In6.Cu")
	)
	(gr_line
		(start 220.840554 -386.796534)
		(end 220.840554 -385.983988)
		(stroke
			(width 0.2)
			(type default)
		)
		(layer "In6.Cu")
	)
	(gr_arc
		(start 220.840554 -385.983988)
		(mid 220.330141 -385.473194)
		(end 219.819474 -385.983734)
		(stroke
			(width 0.2)
			(type default)
		)
		(layer "In6.Cu")
	)
	(gr_line
		(start 220.840554 -381.996442)
		(end 220.840554 -381.183896)
		(stroke
			(width 0.2)
			(type default)
		)
		(layer "In6.Cu")
	)
	(gr_arc
		(start 220.840554 -381.183896)
		(mid 220.330141 -380.673102)
		(end 219.819474 -381.183642)
		(stroke
			(width 0.2)
			(type default)
		)
		(layer "In6.Cu")
	)
	(gr_line
		(start 220.840554 -377.196604)
		(end 220.840554 -376.384058)
		(stroke
			(width 0.2)
			(type default)
		)
		(layer "In6.Cu")
	)
	(gr_arc
		(start 220.840554 -376.384058)
		(mid 220.330141 -375.873264)
		(end 219.819474 -376.383804)
		(stroke
			(width 0.2)
			(type default)
		)
		(layer "In6.Cu")
	)
	(gr_line
		(start 220.840554 -364.396528)
		(end 220.840554 -363.583982)
		(stroke
			(width 0.2)
			(type default)
		)
		(layer "In6.Cu")
	)
	(gr_arc
		(start 220.840554 -363.583982)
		(mid 220.330141 -363.073188)
		(end 219.819474 -363.583728)
		(stroke
			(width 0.2)
			(type default)
		)
		(layer "In6.Cu")
	)
	(gr_line
		(start 220.840554 -283.796486)
		(end 220.840554 -282.98394)
		(stroke
			(width 0.2)
			(type default)
		)
		(layer "In6.Cu")
	)
	(gr_arc
		(start 220.840554 -282.98394)
		(mid 220.330141 -282.473146)
		(end 219.819474 -282.983686)
		(stroke
			(width 0.2)
			(type default)
		)
		(layer "In6.Cu")
	)
	(gr_line
		(start 220.840554 -278.996394)
		(end 220.840554 -278.183848)
		(stroke
			(width 0.2)
			(type default)
		)
		(layer "In6.Cu")
	)
	(gr_arc
		(start 220.840554 -278.183848)
		(mid 220.330141 -277.673054)
		(end 219.819474 -278.183594)
		(stroke
			(width 0.2)
			(type default)
		)
		(layer "In6.Cu")
	)
	(gr_line
		(start 220.840554 -274.196556)
		(end 220.840554 -273.38401)
		(stroke
			(width 0.2)
			(type default)
		)
		(layer "In6.Cu")
	)
	(gr_arc
		(start 220.840554 -273.38401)
		(mid 220.330141 -272.873216)
		(end 219.819474 -273.383756)
		(stroke
			(width 0.2)
			(type default)
		)
		(layer "In6.Cu")
	)
	(gr_line
		(start 220.840554 -261.39648)
		(end 220.840554 -260.583934)
		(stroke
			(width 0.2)
			(type default)
		)
		(layer "In6.Cu")
	)
	(gr_arc
		(start 220.840554 -260.583934)
		(mid 220.330141 -260.07314)
		(end 219.819474 -260.58368)
		(stroke
			(width 0.2)
			(type default)
		)
		(layer "In6.Cu")
	)
	(gr_line
		(start 220.840554 -180.796438)
		(end 220.840554 -179.983892)
		(stroke
			(width 0.2)
			(type default)
		)
		(layer "In6.Cu")
	)
	(gr_arc
		(start 220.840554 -179.983892)
		(mid 220.330141 -179.473098)
		(end 219.819474 -179.983638)
		(stroke
			(width 0.2)
			(type default)
		)
		(layer "In6.Cu")
	)
	(gr_line
		(start 220.840554 -175.996346)
		(end 220.840554 -175.1838)
		(stroke
			(width 0.2)
			(type default)
		)
		(layer "In6.Cu")
	)
	(gr_arc
		(start 220.840554 -175.1838)
		(mid 220.330141 -174.673006)
		(end 219.819474 -175.183546)
		(stroke
			(width 0.2)
			(type default)
		)
		(layer "In6.Cu")
	)
	(gr_line
		(start 220.840554 -171.196508)
		(end 220.840554 -170.383962)
		(stroke
			(width 0.2)
			(type default)
		)
		(layer "In6.Cu")
	)
	(gr_arc
		(start 220.840554 -170.383962)
		(mid 220.330141 -169.873168)
		(end 219.819474 -170.383708)
		(stroke
			(width 0.2)
			(type default)
		)
		(layer "In6.Cu")
	)
	(gr_line
		(start 220.840554 -158.396432)
		(end 220.840554 -157.583886)
		(stroke
			(width 0.2)
			(type default)
		)
		(layer "In6.Cu")
	)
	(gr_arc
		(start 220.840554 -157.583886)
		(mid 220.330141 -157.073092)
		(end 219.819474 -157.583632)
		(stroke
			(width 0.2)
			(type default)
		)
		(layer "In6.Cu")
	)
	(gr_line
		(start 220.840554 -77.79639)
		(end 220.840554 -76.983844)
		(stroke
			(width 0.2)
			(type default)
		)
		(layer "In6.Cu")
	)
	(gr_arc
		(start 220.840554 -76.983844)
		(mid 220.330141 -76.47305)
		(end 219.819474 -76.98359)
		(stroke
			(width 0.2)
			(type default)
		)
		(layer "In6.Cu")
	)
	(gr_line
		(start 220.840554 -72.996298)
		(end 220.840554 -72.183752)
		(stroke
			(width 0.2)
			(type default)
		)
		(layer "In6.Cu")
	)
	(gr_arc
		(start 220.840554 -72.183752)
		(mid 220.330141 -71.672958)
		(end 219.819474 -72.183498)
		(stroke
			(width 0.2)
			(type default)
		)
		(layer "In6.Cu")
	)
	(gr_line
		(start 220.840554 -68.19646)
		(end 220.840554 -67.383914)
		(stroke
			(width 0.2)
			(type default)
		)
		(layer "In6.Cu")
	)
	(gr_arc
		(start 220.840554 -67.383914)
		(mid 220.330141 -66.87312)
		(end 219.819474 -67.38366)
		(stroke
			(width 0.2)
			(type default)
		)
		(layer "In6.Cu")
	)
	(gr_line
		(start 220.840554 -55.396384)
		(end 220.840554 -54.583838)
		(stroke
			(width 0.2)
			(type default)
		)
		(layer "In6.Cu")
	)
	(gr_arc
		(start 220.840554 -54.583838)
		(mid 220.330141 -54.073044)
		(end 219.819474 -54.583584)
		(stroke
			(width 0.2)
			(type default)
		)
		(layer "In6.Cu")
	)
	(gr_arc
		(start 221.114874 -492.349028)
		(mid 221.727014 -492.961168)
		(end 222.339154 -492.349028)
		(stroke
			(width 0.2)
			(type default)
		)
		(layer "In6.Cu")
	)
	(gr_line
		(start 221.114874 -491.231428)
		(end 221.114874 -492.349028)
		(stroke
			(width 0.2)
			(type default)
		)
		(layer "In6.Cu")
	)
	(gr_arc
		(start 221.114874 -487.548936)
		(mid 221.727014 -488.161076)
		(end 222.339154 -487.548936)
		(stroke
			(width 0.2)
			(type default)
		)
		(layer "In6.Cu")
	)
	(gr_line
		(start 221.114874 -486.431336)
		(end 221.114874 -487.548936)
		(stroke
			(width 0.2)
			(type default)
		)
		(layer "In6.Cu")
	)
	(gr_arc
		(start 221.114874 -482.748844)
		(mid 221.727014 -483.360984)
		(end 222.339154 -482.748844)
		(stroke
			(width 0.2)
			(type default)
		)
		(layer "In6.Cu")
	)
	(gr_line
		(start 221.114874 -481.631244)
		(end 221.114874 -482.748844)
		(stroke
			(width 0.2)
			(type default)
		)
		(layer "In6.Cu")
	)
	(gr_arc
		(start 221.114874 -469.949022)
		(mid 221.727014 -470.561162)
		(end 222.339154 -469.949022)
		(stroke
			(width 0.2)
			(type default)
		)
		(layer "In6.Cu")
	)
	(gr_line
		(start 221.114874 -468.831422)
		(end 221.114874 -469.949022)
		(stroke
			(width 0.2)
			(type default)
		)
		(layer "In6.Cu")
	)
	(gr_arc
		(start 221.114874 -389.34898)
		(mid 221.727014 -389.96112)
		(end 222.339154 -389.34898)
		(stroke
			(width 0.2)
			(type default)
		)
		(layer "In6.Cu")
	)
	(gr_line
		(start 221.114874 -388.23138)
		(end 221.114874 -389.34898)
		(stroke
			(width 0.2)
			(type default)
		)
		(layer "In6.Cu")
	)
	(gr_arc
		(start 221.114874 -384.548888)
		(mid 221.727014 -385.161028)
		(end 222.339154 -384.548888)
		(stroke
			(width 0.2)
			(type default)
		)
		(layer "In6.Cu")
	)
	(gr_line
		(start 221.114874 -383.431288)
		(end 221.114874 -384.548888)
		(stroke
			(width 0.2)
			(type default)
		)
		(layer "In6.Cu")
	)
	(gr_arc
		(start 221.114874 -379.748796)
		(mid 221.727014 -380.360936)
		(end 222.339154 -379.748796)
		(stroke
			(width 0.2)
			(type default)
		)
		(layer "In6.Cu")
	)
	(gr_line
		(start 221.114874 -378.631196)
		(end 221.114874 -379.748796)
		(stroke
			(width 0.2)
			(type default)
		)
		(layer "In6.Cu")
	)
	(gr_arc
		(start 221.114874 -366.948974)
		(mid 221.727014 -367.561114)
		(end 222.339154 -366.948974)
		(stroke
			(width 0.2)
			(type default)
		)
		(layer "In6.Cu")
	)
	(gr_line
		(start 221.114874 -365.831374)
		(end 221.114874 -366.948974)
		(stroke
			(width 0.2)
			(type default)
		)
		(layer "In6.Cu")
	)
	(gr_arc
		(start 221.114874 -286.348932)
		(mid 221.727014 -286.961072)
		(end 222.339154 -286.348932)
		(stroke
			(width 0.2)
			(type default)
		)
		(layer "In6.Cu")
	)
	(gr_line
		(start 221.114874 -285.231332)
		(end 221.114874 -286.348932)
		(stroke
			(width 0.2)
			(type default)
		)
		(layer "In6.Cu")
	)
	(gr_arc
		(start 221.114874 -281.54884)
		(mid 221.727014 -282.16098)
		(end 222.339154 -281.54884)
		(stroke
			(width 0.2)
			(type default)
		)
		(layer "In6.Cu")
	)
	(gr_line
		(start 221.114874 -280.43124)
		(end 221.114874 -281.54884)
		(stroke
			(width 0.2)
			(type default)
		)
		(layer "In6.Cu")
	)
	(gr_arc
		(start 221.114874 -276.748748)
		(mid 221.727014 -277.360888)
		(end 222.339154 -276.748748)
		(stroke
			(width 0.2)
			(type default)
		)
		(layer "In6.Cu")
	)
	(gr_line
		(start 221.114874 -275.631148)
		(end 221.114874 -276.748748)
		(stroke
			(width 0.2)
			(type default)
		)
		(layer "In6.Cu")
	)
	(gr_arc
		(start 221.114874 -263.948926)
		(mid 221.727014 -264.561066)
		(end 222.339154 -263.948926)
		(stroke
			(width 0.2)
			(type default)
		)
		(layer "In6.Cu")
	)
	(gr_line
		(start 221.114874 -262.831326)
		(end 221.114874 -263.948926)
		(stroke
			(width 0.2)
			(type default)
		)
		(layer "In6.Cu")
	)
	(gr_arc
		(start 221.114874 -183.348884)
		(mid 221.727014 -183.961024)
		(end 222.339154 -183.348884)
		(stroke
			(width 0.2)
			(type default)
		)
		(layer "In6.Cu")
	)
	(gr_line
		(start 221.114874 -182.231284)
		(end 221.114874 -183.348884)
		(stroke
			(width 0.2)
			(type default)
		)
		(layer "In6.Cu")
	)
	(gr_arc
		(start 221.114874 -178.548792)
		(mid 221.727014 -179.160932)
		(end 222.339154 -178.548792)
		(stroke
			(width 0.2)
			(type default)
		)
		(layer "In6.Cu")
	)
	(gr_line
		(start 221.114874 -177.431192)
		(end 221.114874 -178.548792)
		(stroke
			(width 0.2)
			(type default)
		)
		(layer "In6.Cu")
	)
	(gr_arc
		(start 221.114874 -173.7487)
		(mid 221.727014 -174.36084)
		(end 222.339154 -173.7487)
		(stroke
			(width 0.2)
			(type default)
		)
		(layer "In6.Cu")
	)
	(gr_line
		(start 221.114874 -172.6311)
		(end 221.114874 -173.7487)
		(stroke
			(width 0.2)
			(type default)
		)
		(layer "In6.Cu")
	)
	(gr_arc
		(start 221.114874 -160.948878)
		(mid 221.727014 -161.561018)
		(end 222.339154 -160.948878)
		(stroke
			(width 0.2)
			(type default)
		)
		(layer "In6.Cu")
	)
	(gr_line
		(start 221.114874 -159.831278)
		(end 221.114874 -160.948878)
		(stroke
			(width 0.2)
			(type default)
		)
		(layer "In6.Cu")
	)
	(gr_arc
		(start 221.114874 -80.348836)
		(mid 221.727014 -80.960976)
		(end 222.339154 -80.348836)
		(stroke
			(width 0.2)
			(type default)
		)
		(layer "In6.Cu")
	)
	(gr_line
		(start 221.114874 -79.231236)
		(end 221.114874 -80.348836)
		(stroke
			(width 0.2)
			(type default)
		)
		(layer "In6.Cu")
	)
	(gr_arc
		(start 221.114874 -75.548744)
		(mid 221.727014 -76.160884)
		(end 222.339154 -75.548744)
		(stroke
			(width 0.2)
			(type default)
		)
		(layer "In6.Cu")
	)
	(gr_line
		(start 221.114874 -74.431144)
		(end 221.114874 -75.548744)
		(stroke
			(width 0.2)
			(type default)
		)
		(layer "In6.Cu")
	)
	(gr_arc
		(start 221.114874 -70.748652)
		(mid 221.727014 -71.360792)
		(end 222.339154 -70.748652)
		(stroke
			(width 0.2)
			(type default)
		)
		(layer "In6.Cu")
	)
	(gr_line
		(start 221.114874 -69.631052)
		(end 221.114874 -70.748652)
		(stroke
			(width 0.2)
			(type default)
		)
		(layer "In6.Cu")
	)
	(gr_arc
		(start 221.114874 -57.94883)
		(mid 221.727014 -58.56097)
		(end 222.339154 -57.94883)
		(stroke
			(width 0.2)
			(type default)
		)
		(layer "In6.Cu")
	)
	(gr_line
		(start 221.114874 -56.83123)
		(end 221.114874 -57.94883)
		(stroke
			(width 0.2)
			(type default)
		)
		(layer "In6.Cu")
	)
	(gr_line
		(start 222.339154 -492.349028)
		(end 222.339154 -491.231682)
		(stroke
			(width 0.2)
			(type default)
		)
		(layer "In6.Cu")
	)
	(gr_arc
		(start 222.339154 -491.231682)
		(mid 221.727141 -490.619288)
		(end 221.114874 -491.231428)
		(stroke
			(width 0.2)
			(type default)
		)
		(layer "In6.Cu")
	)
	(gr_line
		(start 222.339154 -487.548936)
		(end 222.339154 -486.43159)
		(stroke
			(width 0.2)
			(type default)
		)
		(layer "In6.Cu")
	)
	(gr_arc
		(start 222.339154 -486.43159)
		(mid 221.727141 -485.819196)
		(end 221.114874 -486.431336)
		(stroke
			(width 0.2)
			(type default)
		)
		(layer "In6.Cu")
	)
	(gr_line
		(start 222.339154 -482.748844)
		(end 222.339154 -481.631498)
		(stroke
			(width 0.2)
			(type default)
		)
		(layer "In6.Cu")
	)
	(gr_arc
		(start 222.339154 -481.631498)
		(mid 221.727141 -481.019104)
		(end 221.114874 -481.631244)
		(stroke
			(width 0.2)
			(type default)
		)
		(layer "In6.Cu")
	)
	(gr_line
		(start 222.339154 -469.949022)
		(end 222.339154 -468.831676)
		(stroke
			(width 0.2)
			(type default)
		)
		(layer "In6.Cu")
	)
	(gr_arc
		(start 222.339154 -468.831676)
		(mid 221.727141 -468.219282)
		(end 221.114874 -468.831422)
		(stroke
			(width 0.2)
			(type default)
		)
		(layer "In6.Cu")
	)
	(gr_line
		(start 222.339154 -389.34898)
		(end 222.339154 -388.231634)
		(stroke
			(width 0.2)
			(type default)
		)
		(layer "In6.Cu")
	)
	(gr_arc
		(start 222.339154 -388.231634)
		(mid 221.727141 -387.61924)
		(end 221.114874 -388.23138)
		(stroke
			(width 0.2)
			(type default)
		)
		(layer "In6.Cu")
	)
	(gr_line
		(start 222.339154 -384.548888)
		(end 222.339154 -383.431542)
		(stroke
			(width 0.2)
			(type default)
		)
		(layer "In6.Cu")
	)
	(gr_arc
		(start 222.339154 -383.431542)
		(mid 221.727141 -382.819148)
		(end 221.114874 -383.431288)
		(stroke
			(width 0.2)
			(type default)
		)
		(layer "In6.Cu")
	)
	(gr_line
		(start 222.339154 -379.748796)
		(end 222.339154 -378.63145)
		(stroke
			(width 0.2)
			(type default)
		)
		(layer "In6.Cu")
	)
	(gr_arc
		(start 222.339154 -378.63145)
		(mid 221.727141 -378.019056)
		(end 221.114874 -378.631196)
		(stroke
			(width 0.2)
			(type default)
		)
		(layer "In6.Cu")
	)
	(gr_line
		(start 222.339154 -366.948974)
		(end 222.339154 -365.831628)
		(stroke
			(width 0.2)
			(type default)
		)
		(layer "In6.Cu")
	)
	(gr_arc
		(start 222.339154 -365.831628)
		(mid 221.727141 -365.219234)
		(end 221.114874 -365.831374)
		(stroke
			(width 0.2)
			(type default)
		)
		(layer "In6.Cu")
	)
	(gr_line
		(start 222.339154 -286.348932)
		(end 222.339154 -285.231586)
		(stroke
			(width 0.2)
			(type default)
		)
		(layer "In6.Cu")
	)
	(gr_arc
		(start 222.339154 -285.231586)
		(mid 221.727141 -284.619192)
		(end 221.114874 -285.231332)
		(stroke
			(width 0.2)
			(type default)
		)
		(layer "In6.Cu")
	)
	(gr_line
		(start 222.339154 -281.54884)
		(end 222.339154 -280.431494)
		(stroke
			(width 0.2)
			(type default)
		)
		(layer "In6.Cu")
	)
	(gr_arc
		(start 222.339154 -280.431494)
		(mid 221.727141 -279.8191)
		(end 221.114874 -280.43124)
		(stroke
			(width 0.2)
			(type default)
		)
		(layer "In6.Cu")
	)
	(gr_line
		(start 222.339154 -276.748748)
		(end 222.339154 -275.631402)
		(stroke
			(width 0.2)
			(type default)
		)
		(layer "In6.Cu")
	)
	(gr_arc
		(start 222.339154 -275.631402)
		(mid 221.727141 -275.019008)
		(end 221.114874 -275.631148)
		(stroke
			(width 0.2)
			(type default)
		)
		(layer "In6.Cu")
	)
	(gr_line
		(start 222.339154 -263.948926)
		(end 222.339154 -262.83158)
		(stroke
			(width 0.2)
			(type default)
		)
		(layer "In6.Cu")
	)
	(gr_arc
		(start 222.339154 -262.83158)
		(mid 221.727141 -262.219186)
		(end 221.114874 -262.831326)
		(stroke
			(width 0.2)
			(type default)
		)
		(layer "In6.Cu")
	)
	(gr_line
		(start 222.339154 -183.348884)
		(end 222.339154 -182.231538)
		(stroke
			(width 0.2)
			(type default)
		)
		(layer "In6.Cu")
	)
	(gr_arc
		(start 222.339154 -182.231538)
		(mid 221.727141 -181.619144)
		(end 221.114874 -182.231284)
		(stroke
			(width 0.2)
			(type default)
		)
		(layer "In6.Cu")
	)
	(gr_line
		(start 222.339154 -178.548792)
		(end 222.339154 -177.431446)
		(stroke
			(width 0.2)
			(type default)
		)
		(layer "In6.Cu")
	)
	(gr_arc
		(start 222.339154 -177.431446)
		(mid 221.727141 -176.819052)
		(end 221.114874 -177.431192)
		(stroke
			(width 0.2)
			(type default)
		)
		(layer "In6.Cu")
	)
	(gr_line
		(start 222.339154 -173.7487)
		(end 222.339154 -172.631354)
		(stroke
			(width 0.2)
			(type default)
		)
		(layer "In6.Cu")
	)
	(gr_arc
		(start 222.339154 -172.631354)
		(mid 221.727141 -172.01896)
		(end 221.114874 -172.6311)
		(stroke
			(width 0.2)
			(type default)
		)
		(layer "In6.Cu")
	)
	(gr_line
		(start 222.339154 -160.948878)
		(end 222.339154 -159.831532)
		(stroke
			(width 0.2)
			(type default)
		)
		(layer "In6.Cu")
	)
	(gr_arc
		(start 222.339154 -159.831532)
		(mid 221.727141 -159.219138)
		(end 221.114874 -159.831278)
		(stroke
			(width 0.2)
			(type default)
		)
		(layer "In6.Cu")
	)
	(gr_line
		(start 222.339154 -80.348836)
		(end 222.339154 -79.23149)
		(stroke
			(width 0.2)
			(type default)
		)
		(layer "In6.Cu")
	)
	(gr_arc
		(start 222.339154 -79.23149)
		(mid 221.727141 -78.619096)
		(end 221.114874 -79.231236)
		(stroke
			(width 0.2)
			(type default)
		)
		(layer "In6.Cu")
	)
	(gr_line
		(start 222.339154 -75.548744)
		(end 222.339154 -74.431398)
		(stroke
			(width 0.2)
			(type default)
		)
		(layer "In6.Cu")
	)
	(gr_arc
		(start 222.339154 -74.431398)
		(mid 221.727141 -73.819004)
		(end 221.114874 -74.431144)
		(stroke
			(width 0.2)
			(type default)
		)
		(layer "In6.Cu")
	)
	(gr_line
		(start 222.339154 -70.748652)
		(end 222.339154 -69.631306)
		(stroke
			(width 0.2)
			(type default)
		)
		(layer "In6.Cu")
	)
	(gr_arc
		(start 222.339154 -69.631306)
		(mid 221.727141 -69.018912)
		(end 221.114874 -69.631052)
		(stroke
			(width 0.2)
			(type default)
		)
		(layer "In6.Cu")
	)
	(gr_line
		(start 222.339154 -57.94883)
		(end 222.339154 -56.831484)
		(stroke
			(width 0.2)
			(type default)
		)
		(layer "In6.Cu")
	)
	(gr_arc
		(start 222.339154 -56.831484)
		(mid 221.727141 -56.21909)
		(end 221.114874 -56.83123)
		(stroke
			(width 0.2)
			(type default)
		)
		(layer "In6.Cu")
	)
	(gr_line
		(start 229.907084 -472.300808)
		(end 230.71963 -472.300808)
		(stroke
			(width 0.2)
			(type default)
		)
		(layer "In6.Cu")
	)
	(gr_arc
		(start 229.907084 -471.279728)
		(mid 229.396544 -471.790268)
		(end 229.907084 -472.300808)
		(stroke
			(width 0.2)
			(type default)
		)
		(layer "In6.Cu")
	)
	(gr_line
		(start 229.907084 -369.30076)
		(end 230.71963 -369.30076)
		(stroke
			(width 0.2)
			(type default)
		)
		(layer "In6.Cu")
	)
	(gr_arc
		(start 229.907084 -368.27968)
		(mid 229.396544 -368.79022)
		(end 229.907084 -369.30076)
		(stroke
			(width 0.2)
			(type default)
		)
		(layer "In6.Cu")
	)
	(gr_line
		(start 229.907084 -266.300712)
		(end 230.71963 -266.300712)
		(stroke
			(width 0.2)
			(type default)
		)
		(layer "In6.Cu")
	)
	(gr_arc
		(start 229.907084 -265.279632)
		(mid 229.396544 -265.790172)
		(end 229.907084 -266.300712)
		(stroke
			(width 0.2)
			(type default)
		)
		(layer "In6.Cu")
	)
	(gr_line
		(start 229.907084 -163.300664)
		(end 230.71963 -163.300664)
		(stroke
			(width 0.2)
			(type default)
		)
		(layer "In6.Cu")
	)
	(gr_arc
		(start 229.907084 -162.279584)
		(mid 229.396544 -162.790124)
		(end 229.907084 -163.300664)
		(stroke
			(width 0.2)
			(type default)
		)
		(layer "In6.Cu")
	)
	(gr_line
		(start 229.907084 -60.300616)
		(end 230.71963 -60.300616)
		(stroke
			(width 0.2)
			(type default)
		)
		(layer "In6.Cu")
	)
	(gr_arc
		(start 229.907084 -59.279536)
		(mid 229.396544 -59.790076)
		(end 229.907084 -60.300616)
		(stroke
			(width 0.2)
			(type default)
		)
		(layer "In6.Cu")
	)
	(gr_arc
		(start 230.71963 -472.300808)
		(mid 231.230424 -471.790395)
		(end 230.719884 -471.279728)
		(stroke
			(width 0.2)
			(type default)
		)
		(layer "In6.Cu")
	)
	(gr_arc
		(start 230.71963 -369.30076)
		(mid 231.230424 -368.790347)
		(end 230.719884 -368.27968)
		(stroke
			(width 0.2)
			(type default)
		)
		(layer "In6.Cu")
	)
	(gr_arc
		(start 230.71963 -266.300712)
		(mid 231.230424 -265.790299)
		(end 230.719884 -265.279632)
		(stroke
			(width 0.2)
			(type default)
		)
		(layer "In6.Cu")
	)
	(gr_arc
		(start 230.71963 -163.300664)
		(mid 231.230424 -162.790251)
		(end 230.719884 -162.279584)
		(stroke
			(width 0.2)
			(type default)
		)
		(layer "In6.Cu")
	)
	(gr_arc
		(start 230.71963 -60.300616)
		(mid 231.230424 -59.790203)
		(end 230.719884 -59.279536)
		(stroke
			(width 0.2)
			(type default)
		)
		(layer "In6.Cu")
	)
	(gr_line
		(start 230.719884 -471.279728)
		(end 229.907084 -471.279728)
		(stroke
			(width 0.2)
			(type default)
		)
		(layer "In6.Cu")
	)
	(gr_line
		(start 230.719884 -368.27968)
		(end 229.907084 -368.27968)
		(stroke
			(width 0.2)
			(type default)
		)
		(layer "In6.Cu")
	)
	(gr_line
		(start 230.719884 -265.279632)
		(end 229.907084 -265.279632)
		(stroke
			(width 0.2)
			(type default)
		)
		(layer "In6.Cu")
	)
	(gr_line
		(start 230.719884 -162.279584)
		(end 229.907084 -162.279584)
		(stroke
			(width 0.2)
			(type default)
		)
		(layer "In6.Cu")
	)
	(gr_line
		(start 230.719884 -59.279536)
		(end 229.907084 -59.279536)
		(stroke
			(width 0.2)
			(type default)
		)
		(layer "In6.Cu")
	)
	(gr_arc
		(start 232.876344 -473.391992)
		(mid 233.386757 -473.902786)
		(end 233.897424 -473.392246)
		(stroke
			(width 0.2)
			(type default)
		)
		(layer "In6.Cu")
	)
	(gr_line
		(start 232.876344 -472.579446)
		(end 232.876344 -473.391992)
		(stroke
			(width 0.2)
			(type default)
		)
		(layer "In6.Cu")
	)
	(gr_arc
		(start 232.876344 -370.391944)
		(mid 233.386757 -370.902738)
		(end 233.897424 -370.392198)
		(stroke
			(width 0.2)
			(type default)
		)
		(layer "In6.Cu")
	)
	(gr_line
		(start 232.876344 -369.579398)
		(end 232.876344 -370.391944)
		(stroke
			(width 0.2)
			(type default)
		)
		(layer "In6.Cu")
	)
	(gr_arc
		(start 232.876344 -267.391896)
		(mid 233.386757 -267.90269)
		(end 233.897424 -267.39215)
		(stroke
			(width 0.2)
			(type default)
		)
		(layer "In6.Cu")
	)
	(gr_line
		(start 232.876344 -266.57935)
		(end 232.876344 -267.391896)
		(stroke
			(width 0.2)
			(type default)
		)
		(layer "In6.Cu")
	)
	(gr_arc
		(start 232.876344 -164.391848)
		(mid 233.386757 -164.902642)
		(end 233.897424 -164.392102)
		(stroke
			(width 0.2)
			(type default)
		)
		(layer "In6.Cu")
	)
	(gr_line
		(start 232.876344 -163.579302)
		(end 232.876344 -164.391848)
		(stroke
			(width 0.2)
			(type default)
		)
		(layer "In6.Cu")
	)
	(gr_arc
		(start 232.876344 -61.3918)
		(mid 233.386757 -61.902594)
		(end 233.897424 -61.392054)
		(stroke
			(width 0.2)
			(type default)
		)
		(layer "In6.Cu")
	)
	(gr_line
		(start 232.876344 -60.579254)
		(end 232.876344 -61.3918)
		(stroke
			(width 0.2)
			(type default)
		)
		(layer "In6.Cu")
	)
	(gr_line
		(start 233.897424 -473.392246)
		(end 233.897424 -472.579446)
		(stroke
			(width 0.2)
			(type default)
		)
		(layer "In6.Cu")
	)
	(gr_arc
		(start 233.897424 -472.579446)
		(mid 233.386884 -472.068906)
		(end 232.876344 -472.579446)
		(stroke
			(width 0.2)
			(type default)
		)
		(layer "In6.Cu")
	)
	(gr_line
		(start 233.897424 -370.392198)
		(end 233.897424 -369.579398)
		(stroke
			(width 0.2)
			(type default)
		)
		(layer "In6.Cu")
	)
	(gr_arc
		(start 233.897424 -369.579398)
		(mid 233.386884 -369.068858)
		(end 232.876344 -369.579398)
		(stroke
			(width 0.2)
			(type default)
		)
		(layer "In6.Cu")
	)
	(gr_line
		(start 233.897424 -267.39215)
		(end 233.897424 -266.57935)
		(stroke
			(width 0.2)
			(type default)
		)
		(layer "In6.Cu")
	)
	(gr_arc
		(start 233.897424 -266.57935)
		(mid 233.386884 -266.06881)
		(end 232.876344 -266.57935)
		(stroke
			(width 0.2)
			(type default)
		)
		(layer "In6.Cu")
	)
	(gr_line
		(start 233.897424 -164.392102)
		(end 233.897424 -163.579302)
		(stroke
			(width 0.2)
			(type default)
		)
		(layer "In6.Cu")
	)
	(gr_arc
		(start 233.897424 -163.579302)
		(mid 233.386884 -163.068762)
		(end 232.876344 -163.579302)
		(stroke
			(width 0.2)
			(type default)
		)
		(layer "In6.Cu")
	)
	(gr_line
		(start 233.897424 -61.392054)
		(end 233.897424 -60.579254)
		(stroke
			(width 0.2)
			(type default)
		)
		(layer "In6.Cu")
	)
	(gr_arc
		(start 233.897424 -60.579254)
		(mid 233.386884 -60.068714)
		(end 232.876344 -60.579254)
		(stroke
			(width 0.2)
			(type default)
		)
		(layer "In6.Cu")
	)
	(gr_line
		(start 252.394974 -410.485082)
		(end 258.899914 -410.485082)
		(stroke
			(width 1.524)
			(type default)
		)
		(layer "In6.Cu")
	)
	(gr_arc
		(start 252.394974 -409.41498)
		(mid 251.859796 -409.950158)
		(end 252.394974 -410.485082)
		(stroke
			(width 1.524)
			(type default)
		)
		(layer "In6.Cu")
	)
	(gr_line
		(start 258.899914 -410.485082)
		(end 259.899912 -411.48508)
		(stroke
			(width 1.524)
			(type default)
		)
		(layer "In6.Cu")
	)
	(gr_line
		(start 258.899914 -409.41498)
		(end 252.394974 -409.41498)
		(stroke
			(width 1.524)
			(type default)
		)
		(layer "In6.Cu")
	)
	(gr_arc
		(start 259.899912 -425.69003)
		(mid 260.307091 -426.672919)
		(end 261.290054 -427.079918)
		(stroke
			(width 1.524)
			(type default)
		)
		(layer "In6.Cu")
	)
	(gr_line
		(start 259.899912 -411.48508)
		(end 259.899912 -425.69003)
		(stroke
			(width 1.524)
			(type default)
		)
		(layer "In6.Cu")
	)
	(gr_line
		(start 259.899912 -408.414982)
		(end 258.899914 -409.41498)
		(stroke
			(width 1.524)
			(type default)
		)
		(layer "In6.Cu")
	)
	(gr_line
		(start 259.899912 -364.309914)
		(end 259.899912 -408.414982)
		(stroke
			(width 1.524)
			(type default)
		)
		(layer "In6.Cu")
	)
	(gr_line
		(start 261.290054 -427.079918)
		(end 262.50011 -427.079918)
		(stroke
			(width 1.524)
			(type default)
		)
		(layer "In6.Cu")
	)
	(gr_arc
		(start 261.290054 -362.920026)
		(mid 260.307165 -363.327099)
		(end 259.899912 -364.309914)
		(stroke
			(width 1.524)
			(type default)
		)
		(layer "In6.Cu")
	)
	(gr_line
		(start 262.50011 -506.000004)
		(end 0.999998 -506.000004)
		(stroke
			(width 1.524)
			(type default)
		)
		(layer "In6.Cu")
	)
	(gr_arc
		(start 262.50011 -506.000004)
		(mid 263.207211 -505.707108)
		(end 263.500108 -505.000006)
		(stroke
			(width 1.524)
			(type default)
		)
		(layer "In6.Cu")
	)
	(gr_line
		(start 262.50011 -427.079918)
		(end 263.500108 -428.079916)
		(stroke
			(width 1.524)
			(type default)
		)
		(layer "In6.Cu")
	)
	(gr_line
		(start 262.50011 -362.920026)
		(end 261.290054 -362.920026)
		(stroke
			(width 1.524)
			(type default)
		)
		(layer "In6.Cu")
	)
	(gr_line
		(start 263.500108 -428.079916)
		(end 263.500108 -505.000006)
		(stroke
			(width 1.524)
			(type default)
		)
		(layer "In6.Cu")
	)
	(gr_line
		(start 263.500108 -361.920028)
		(end 262.50011 -362.920026)
		(stroke
			(width 1.524)
			(type default)
		)
		(layer "In6.Cu")
	)
	(gr_arc
		(start 263.500108 -0.999998)
		(mid 263.207215 -0.29289)
		(end 262.50011 0)
		(stroke
			(width 1.524)
			(type default)
		)
		(layer "In6.Cu")
	)
	(gr_line
		(start 263.500108 -0.999998)
		(end 263.500108 -361.920028)
		(stroke
			(width 1.524)
			(type default)
		)
		(layer "In6.Cu")
	)
	(gr_line
		(start 0 -505.000006)
		(end 0 -421.942006)
		(stroke
			(width 0.05)
			(type default)
		)
		(layer "Edge.Cuts")
	)
	(gr_arc
		(start 0 -505.000006)
		(mid 0.292895 -505.707108)
		(end 0.999998 -506.000004)
		(stroke
			(width 0.05)
			(type default)
		)
		(layer "Edge.Cuts")
	)
	(gr_line
		(start 0 -421.942006)
		(end 0.500126 -421.44188)
		(stroke
			(width 0.05)
			(type default)
		)
		(layer "Edge.Cuts")
	)
	(gr_line
		(start 0 -418.742114)
		(end 0 -315.941964)
		(stroke
			(width 0.05)
			(type default)
		)
		(layer "Edge.Cuts")
	)
	(gr_line
		(start 0 -315.941964)
		(end 0.500126 -315.442092)
		(stroke
			(width 0.05)
			(type default)
		)
		(layer "Edge.Cuts")
	)
	(gr_line
		(start 0 -312.742072)
		(end 0 -189.941962)
		(stroke
			(width 0.05)
			(type default)
		)
		(layer "Edge.Cuts")
	)
	(gr_line
		(start 0 -189.941962)
		(end 0.500126 -189.44209)
		(stroke
			(width 0.05)
			(type default)
		)
		(layer "Edge.Cuts")
	)
	(gr_line
		(start 0 -186.74207)
		(end 0 -0.999998)
		(stroke
			(width 0.05)
			(type default)
		)
		(layer "Edge.Cuts")
	)
	(gr_line
		(start 0.500126 -421.44188)
		(end 4.400042 -421.44188)
		(stroke
			(width 0.05)
			(type default)
		)
		(layer "Edge.Cuts")
	)
	(gr_line
		(start 0.500126 -419.241986)
		(end 0 -418.742114)
		(stroke
			(width 0.05)
			(type default)
		)
		(layer "Edge.Cuts")
	)
	(gr_line
		(start 0.500126 -315.442092)
		(end 4.400042 -315.442092)
		(stroke
			(width 0.05)
			(type default)
		)
		(layer "Edge.Cuts")
	)
	(gr_line
		(start 0.500126 -313.241944)
		(end 0 -312.742072)
		(stroke
			(width 0.05)
			(type default)
		)
		(layer "Edge.Cuts")
	)
	(gr_line
		(start 0.500126 -189.44209)
		(end 4.400042 -189.44209)
		(stroke
			(width 0.05)
			(type default)
		)
		(layer "Edge.Cuts")
	)
	(gr_line
		(start 0.500126 -187.241942)
		(end 0 -186.74207)
		(stroke
			(width 0.05)
			(type default)
		)
		(layer "Edge.Cuts")
	)
	(gr_arc
		(start 0.999998 0)
		(mid 0.292893 -0.292893)
		(end 0 -0.999998)
		(stroke
			(width 0.05)
			(type default)
		)
		(layer "Edge.Cuts")
	)
	(gr_line
		(start 0.999998 0)
		(end 30.80004 0)
		(stroke
			(width 0.05)
			(type default)
		)
		(layer "Edge.Cuts")
	)
	(gr_arc
		(start 2.999994 -474.241876)
		(mid 4.099814 -473.142056)
		(end 2.999994 -472.041982)
		(stroke
			(width 0.05)
			(type default)
		)
		(layer "Edge.Cuts")
	)
	(gr_arc
		(start 2.999994 -472.041982)
		(mid 1.89992 -473.142056)
		(end 2.999994 -474.241876)
		(stroke
			(width 0.05)
			(type default)
		)
		(layer "Edge.Cuts")
	)
	(gr_arc
		(start 2.999994 -378.242068)
		(mid 4.100068 -377.141994)
		(end 2.999994 -376.04192)
		(stroke
			(width 0.05)
			(type default)
		)
		(layer "Edge.Cuts")
	)
	(gr_arc
		(start 2.999994 -376.04192)
		(mid 1.89992 -377.141994)
		(end 2.999994 -378.242068)
		(stroke
			(width 0.05)
			(type default)
		)
		(layer "Edge.Cuts")
	)
	(gr_arc
		(start 2.999994 -368.242088)
		(mid 4.100068 -367.142014)
		(end 2.999994 -366.04194)
		(stroke
			(width 0.05)
			(type default)
		)
		(layer "Edge.Cuts")
	)
	(gr_arc
		(start 2.999994 -366.04194)
		(mid 1.89992 -367.142014)
		(end 2.999994 -368.242088)
		(stroke
			(width 0.05)
			(type default)
		)
		(layer "Edge.Cuts")
	)
	(gr_arc
		(start 2.999994 -272.242026)
		(mid 4.100068 -271.141952)
		(end 2.999994 -270.041878)
		(stroke
			(width 0.05)
			(type default)
		)
		(layer "Edge.Cuts")
	)
	(gr_arc
		(start 2.999994 -270.041878)
		(mid 1.89992 -271.141952)
		(end 2.999994 -272.242026)
		(stroke
			(width 0.05)
			(type default)
		)
		(layer "Edge.Cuts")
	)
	(gr_arc
		(start 2.999994 -242.242086)
		(mid 4.100068 -241.142012)
		(end 2.999994 -240.041938)
		(stroke
			(width 0.05)
			(type default)
		)
		(layer "Edge.Cuts")
	)
	(gr_arc
		(start 2.999994 -240.041938)
		(mid 1.89992 -241.142012)
		(end 2.999994 -242.242086)
		(stroke
			(width 0.05)
			(type default)
		)
		(layer "Edge.Cuts")
	)
	(gr_arc
		(start 2.999994 -146.242024)
		(mid 4.100068 -145.14195)
		(end 2.999994 -144.041876)
		(stroke
			(width 0.05)
			(type default)
		)
		(layer "Edge.Cuts")
	)
	(gr_arc
		(start 2.999994 -144.041876)
		(mid 1.89992 -145.14195)
		(end 2.999994 -146.242024)
		(stroke
			(width 0.05)
			(type default)
		)
		(layer "Edge.Cuts")
	)
	(gr_arc
		(start 3.999992 -488.40009)
		(mid 5.500116 -489.900214)
		(end 6.999986 -488.40009)
		(stroke
			(width 0.05)
			(type default)
		)
		(layer "Edge.Cuts")
	)
	(gr_arc
		(start 3.999992 -487.349546)
		(mid 3.925796 -486.971498)
		(end 3.714242 -486.649522)
		(stroke
			(width 0.05)
			(type default)
		)
		(layer "Edge.Cuts")
	)
	(gr_line
		(start 3.999992 -487.349546)
		(end 3.999992 -488.40009)
		(stroke
			(width 0.05)
			(type default)
		)
		(layer "Edge.Cuts")
	)
	(gr_arc
		(start 4.400042 -421.44188)
		(mid 5.499862 -420.34206)
		(end 4.400042 -419.241986)
		(stroke
			(width 0.05)
			(type default)
		)
		(layer "Edge.Cuts")
	)
	(gr_line
		(start 4.400042 -419.241986)
		(end 0.500126 -419.241986)
		(stroke
			(width 0.05)
			(type default)
		)
		(layer "Edge.Cuts")
	)
	(gr_arc
		(start 4.400042 -315.442092)
		(mid 5.500116 -314.342018)
		(end 4.400042 -313.241944)
		(stroke
			(width 0.05)
			(type default)
		)
		(layer "Edge.Cuts")
	)
	(gr_line
		(start 4.400042 -313.241944)
		(end 0.500126 -313.241944)
		(stroke
			(width 0.05)
			(type default)
		)
		(layer "Edge.Cuts")
	)
	(gr_arc
		(start 4.400042 -189.44209)
		(mid 5.500116 -188.342016)
		(end 4.400042 -187.241942)
		(stroke
			(width 0.05)
			(type default)
		)
		(layer "Edge.Cuts")
	)
	(gr_line
		(start 4.400042 -187.241942)
		(end 0.500126 -187.241942)
		(stroke
			(width 0.05)
			(type default)
		)
		(layer "Edge.Cuts")
	)
	(gr_arc
		(start 6.480048 -496.519962)
		(mid 7.569962 -495.430048)
		(end 6.480048 -494.33988)
		(stroke
			(width 0.05)
			(type default)
		)
		(layer "Edge.Cuts")
	)
	(gr_arc
		(start 6.480048 -494.33988)
		(mid 5.38988 -495.430048)
		(end 6.480048 -496.519962)
		(stroke
			(width 0.05)
			(type default)
		)
		(layer "Edge.Cuts")
	)
	(gr_line
		(start 6.999986 -488.40009)
		(end 6.999986 -487.349546)
		(stroke
			(width 0.05)
			(type default)
		)
		(layer "Edge.Cuts")
	)
	(gr_arc
		(start 7.000494 -71.499984)
		(mid 8.50011 -72.9996)
		(end 9.999472 -71.499984)
		(stroke
			(width 0.05)
			(type default)
		)
		(layer "Edge.Cuts")
	)
	(gr_arc
		(start 7.000494 -70.449948)
		(mid 6.92637 -70.071871)
		(end 6.714744 -69.749924)
		(stroke
			(width 0.05)
			(type default)
		)
		(layer "Edge.Cuts")
	)
	(gr_line
		(start 7.000494 -70.449948)
		(end 7.000494 -71.499984)
		(stroke
			(width 0.05)
			(type default)
		)
		(layer "Edge.Cuts")
	)
	(gr_arc
		(start 7.285736 -486.649522)
		(mid 5.500205 -482.400096)
		(end 3.714242 -486.649522)
		(stroke
			(width 0.05)
			(type default)
		)
		(layer "Edge.Cuts")
	)
	(gr_arc
		(start 7.285736 -486.649522)
		(mid 7.074198 -486.971506)
		(end 6.999986 -487.349546)
		(stroke
			(width 0.05)
			(type default)
		)
		(layer "Edge.Cuts")
	)
	(gr_arc
		(start 8.50011 -263.275064)
		(mid 10.275062 -261.500112)
		(end 8.50011 -259.724906)
		(stroke
			(width 0.05)
			(type default)
		)
		(layer "Edge.Cuts")
	)
	(gr_arc
		(start 8.50011 -259.724906)
		(mid 6.724904 -261.500112)
		(end 8.50011 -263.275064)
		(stroke
			(width 0.05)
			(type default)
		)
		(layer "Edge.Cuts")
	)
	(gr_line
		(start 9.999472 -71.499984)
		(end 9.999472 -70.449948)
		(stroke
			(width 0.05)
			(type default)
		)
		(layer "Edge.Cuts")
	)
	(gr_arc
		(start 10.285222 -69.749924)
		(mid 8.500199 -65.499997)
		(end 6.714744 -69.749924)
		(stroke
			(width 0.05)
			(type default)
		)
		(layer "Edge.Cuts")
	)
	(gr_arc
		(start 10.285222 -69.749924)
		(mid 10.073674 -70.071906)
		(end 9.999472 -70.449948)
		(stroke
			(width 0.05)
			(type default)
		)
		(layer "Edge.Cuts")
	)
	(gr_line
		(start 17.949926 -460.730092)
		(end 19.05 -460.730092)
		(stroke
			(width 0.05)
			(type default)
		)
		(layer "Edge.Cuts")
	)
	(gr_arc
		(start 17.949926 -459.929992)
		(mid 17.549876 -460.330042)
		(end 17.949926 -460.730092)
		(stroke
			(width 0.05)
			(type default)
		)
		(layer "Edge.Cuts")
	)
	(gr_line
		(start 17.949926 -416.729926)
		(end 19.05 -416.729926)
		(stroke
			(width 0.05)
			(type default)
		)
		(layer "Edge.Cuts")
	)
	(gr_arc
		(start 17.949926 -415.93008)
		(mid 17.549876 -416.33013)
		(end 17.949926 -416.729926)
		(stroke
			(width 0.05)
			(type default)
		)
		(layer "Edge.Cuts")
	)
	(gr_line
		(start 17.949926 -357.730044)
		(end 19.05 -357.730044)
		(stroke
			(width 0.05)
			(type default)
		)
		(layer "Edge.Cuts")
	)
	(gr_arc
		(start 17.949926 -356.929944)
		(mid 17.549876 -357.329994)
		(end 17.949926 -357.730044)
		(stroke
			(width 0.05)
			(type default)
		)
		(layer "Edge.Cuts")
	)
	(gr_line
		(start 17.949926 -313.729878)
		(end 19.05 -313.729878)
		(stroke
			(width 0.05)
			(type default)
		)
		(layer "Edge.Cuts")
	)
	(gr_arc
		(start 17.949926 -312.930032)
		(mid 17.549876 -313.330082)
		(end 17.949926 -313.729878)
		(stroke
			(width 0.05)
			(type default)
		)
		(layer "Edge.Cuts")
	)
	(gr_line
		(start 17.949926 -254.729996)
		(end 19.05 -254.729996)
		(stroke
			(width 0.05)
			(type default)
		)
		(layer "Edge.Cuts")
	)
	(gr_arc
		(start 17.949926 -253.929896)
		(mid 17.549876 -254.329946)
		(end 17.949926 -254.729996)
		(stroke
			(width 0.05)
			(type default)
		)
		(layer "Edge.Cuts")
	)
	(gr_line
		(start 17.949926 -210.730084)
		(end 19.05 -210.730084)
		(stroke
			(width 0.05)
			(type default)
		)
		(layer "Edge.Cuts")
	)
	(gr_arc
		(start 17.949926 -209.929984)
		(mid 17.549876 -210.330034)
		(end 17.949926 -210.730084)
		(stroke
			(width 0.05)
			(type default)
		)
		(layer "Edge.Cuts")
	)
	(gr_line
		(start 17.949926 -151.729948)
		(end 19.05 -151.729948)
		(stroke
			(width 0.05)
			(type default)
		)
		(layer "Edge.Cuts")
	)
	(gr_arc
		(start 17.949926 -150.930102)
		(mid 17.549876 -151.330152)
		(end 17.949926 -151.729948)
		(stroke
			(width 0.05)
			(type default)
		)
		(layer "Edge.Cuts")
	)
	(gr_line
		(start 17.949926 -107.730036)
		(end 19.05 -107.730036)
		(stroke
			(width 0.05)
			(type default)
		)
		(layer "Edge.Cuts")
	)
	(gr_arc
		(start 17.949926 -106.929936)
		(mid 17.549876 -107.329986)
		(end 17.949926 -107.730036)
		(stroke
			(width 0.05)
			(type default)
		)
		(layer "Edge.Cuts")
	)
	(gr_line
		(start 17.949926 -48.7299)
		(end 19.05 -48.7299)
		(stroke
			(width 0.05)
			(type default)
		)
		(layer "Edge.Cuts")
	)
	(gr_arc
		(start 17.949926 -47.930054)
		(mid 17.549876 -48.330104)
		(end 17.949926 -48.7299)
		(stroke
			(width 0.05)
			(type default)
		)
		(layer "Edge.Cuts")
	)
	(gr_line
		(start 17.949926 -4.729988)
		(end 19.05 -4.729988)
		(stroke
			(width 0.05)
			(type default)
		)
		(layer "Edge.Cuts")
	)
	(gr_arc
		(start 17.949926 -3.929888)
		(mid 17.549876 -4.329938)
		(end 17.949926 -4.729988)
		(stroke
			(width 0.05)
			(type default)
		)
		(layer "Edge.Cuts")
	)
	(gr_arc
		(start 19.05 -460.730092)
		(mid 19.45005 -460.330042)
		(end 19.05 -459.929992)
		(stroke
			(width 0.05)
			(type default)
		)
		(layer "Edge.Cuts")
	)
	(gr_line
		(start 19.05 -459.929992)
		(end 17.949926 -459.929992)
		(stroke
			(width 0.05)
			(type default)
		)
		(layer "Edge.Cuts")
	)
	(gr_arc
		(start 19.05 -416.729926)
		(mid 19.449796 -416.33013)
		(end 19.05 -415.93008)
		(stroke
			(width 0.05)
			(type default)
		)
		(layer "Edge.Cuts")
	)
	(gr_line
		(start 19.05 -415.93008)
		(end 17.949926 -415.93008)
		(stroke
			(width 0.05)
			(type default)
		)
		(layer "Edge.Cuts")
	)
	(gr_arc
		(start 19.05 -357.730044)
		(mid 19.45005 -357.329994)
		(end 19.05 -356.929944)
		(stroke
			(width 0.05)
			(type default)
		)
		(layer "Edge.Cuts")
	)
	(gr_line
		(start 19.05 -356.929944)
		(end 17.949926 -356.929944)
		(stroke
			(width 0.05)
			(type default)
		)
		(layer "Edge.Cuts")
	)
	(gr_arc
		(start 19.05 -313.729878)
		(mid 19.449796 -313.330082)
		(end 19.05 -312.930032)
		(stroke
			(width 0.05)
			(type default)
		)
		(layer "Edge.Cuts")
	)
	(gr_line
		(start 19.05 -312.930032)
		(end 17.949926 -312.930032)
		(stroke
			(width 0.05)
			(type default)
		)
		(layer "Edge.Cuts")
	)
	(gr_arc
		(start 19.05 -254.729996)
		(mid 19.45005 -254.329946)
		(end 19.05 -253.929896)
		(stroke
			(width 0.05)
			(type default)
		)
		(layer "Edge.Cuts")
	)
	(gr_line
		(start 19.05 -253.929896)
		(end 17.949926 -253.929896)
		(stroke
			(width 0.05)
			(type default)
		)
		(layer "Edge.Cuts")
	)
	(gr_arc
		(start 19.05 -210.730084)
		(mid 19.45005 -210.330034)
		(end 19.05 -209.929984)
		(stroke
			(width 0.05)
			(type default)
		)
		(layer "Edge.Cuts")
	)
	(gr_line
		(start 19.05 -209.929984)
		(end 17.949926 -209.929984)
		(stroke
			(width 0.05)
			(type default)
		)
		(layer "Edge.Cuts")
	)
	(gr_arc
		(start 19.05 -151.729948)
		(mid 19.449796 -151.330152)
		(end 19.05 -150.930102)
		(stroke
			(width 0.05)
			(type default)
		)
		(layer "Edge.Cuts")
	)
	(gr_line
		(start 19.05 -150.930102)
		(end 17.949926 -150.930102)
		(stroke
			(width 0.05)
			(type default)
		)
		(layer "Edge.Cuts")
	)
	(gr_arc
		(start 19.05 -107.730036)
		(mid 19.45005 -107.329986)
		(end 19.05 -106.929936)
		(stroke
			(width 0.05)
			(type default)
		)
		(layer "Edge.Cuts")
	)
	(gr_line
		(start 19.05 -106.929936)
		(end 17.949926 -106.929936)
		(stroke
			(width 0.05)
			(type default)
		)
		(layer "Edge.Cuts")
	)
	(gr_arc
		(start 19.05 -48.7299)
		(mid 19.449796 -48.330104)
		(end 19.05 -47.930054)
		(stroke
			(width 0.05)
			(type default)
		)
		(layer "Edge.Cuts")
	)
	(gr_line
		(start 19.05 -47.930054)
		(end 17.949926 -47.930054)
		(stroke
			(width 0.05)
			(type default)
		)
		(layer "Edge.Cuts")
	)
	(gr_arc
		(start 19.05 -4.729988)
		(mid 19.45005 -4.329938)
		(end 19.05 -3.929888)
		(stroke
			(width 0.05)
			(type default)
		)
		(layer "Edge.Cuts")
	)
	(gr_line
		(start 19.05 -3.929888)
		(end 17.949926 -3.929888)
		(stroke
			(width 0.05)
			(type default)
		)
		(layer "Edge.Cuts")
	)
	(gr_arc
		(start 20.850098 -458.220064)
		(mid 21.740114 -457.330048)
		(end 20.850098 -456.440032)
		(stroke
			(width 0.05)
			(type default)
		)
		(layer "Edge.Cuts")
	)
	(gr_arc
		(start 20.850098 -456.440032)
		(mid 19.960082 -457.330048)
		(end 20.850098 -458.220064)
		(stroke
			(width 0.05)
			(type default)
		)
		(layer "Edge.Cuts")
	)
	(gr_arc
		(start 20.850098 -420.219886)
		(mid 21.73986 -419.330124)
		(end 20.850098 -418.440108)
		(stroke
			(width 0.05)
			(type default)
		)
		(layer "Edge.Cuts")
	)
	(gr_arc
		(start 20.850098 -418.440108)
		(mid 19.960082 -419.330124)
		(end 20.850098 -420.219886)
		(stroke
			(width 0.05)
			(type default)
		)
		(layer "Edge.Cuts")
	)
	(gr_arc
		(start 20.850098 -355.220016)
		(mid 21.740114 -354.33)
		(end 20.850098 -353.439984)
		(stroke
			(width 0.05)
			(type default)
		)
		(layer "Edge.Cuts")
	)
	(gr_arc
		(start 20.850098 -353.439984)
		(mid 19.960082 -354.33)
		(end 20.850098 -355.220016)
		(stroke
			(width 0.05)
			(type default)
		)
		(layer "Edge.Cuts")
	)
	(gr_arc
		(start 20.850098 -317.220092)
		(mid 21.740114 -316.330076)
		(end 20.850098 -315.44006)
		(stroke
			(width 0.05)
			(type default)
		)
		(layer "Edge.Cuts")
	)
	(gr_arc
		(start 20.850098 -315.44006)
		(mid 19.960082 -316.330076)
		(end 20.850098 -317.220092)
		(stroke
			(width 0.05)
			(type default)
		)
		(layer "Edge.Cuts")
	)
	(gr_arc
		(start 20.850098 -252.219968)
		(mid 21.740114 -251.329952)
		(end 20.850098 -250.439936)
		(stroke
			(width 0.05)
			(type default)
		)
		(layer "Edge.Cuts")
	)
	(gr_arc
		(start 20.850098 -250.439936)
		(mid 19.960082 -251.329952)
		(end 20.850098 -252.219968)
		(stroke
			(width 0.05)
			(type default)
		)
		(layer "Edge.Cuts")
	)
	(gr_arc
		(start 20.850098 -214.220044)
		(mid 21.740114 -213.330028)
		(end 20.850098 -212.440012)
		(stroke
			(width 0.05)
			(type default)
		)
		(layer "Edge.Cuts")
	)
	(gr_arc
		(start 20.850098 -212.440012)
		(mid 19.960082 -213.330028)
		(end 20.850098 -214.220044)
		(stroke
			(width 0.05)
			(type default)
		)
		(layer "Edge.Cuts")
	)
	(gr_arc
		(start 20.850098 -149.21992)
		(mid 21.740114 -148.329904)
		(end 20.850098 -147.439888)
		(stroke
			(width 0.05)
			(type default)
		)
		(layer "Edge.Cuts")
	)
	(gr_arc
		(start 20.850098 -147.439888)
		(mid 19.960082 -148.329904)
		(end 20.850098 -149.21992)
		(stroke
			(width 0.05)
			(type default)
		)
		(layer "Edge.Cuts")
	)
	(gr_arc
		(start 20.850098 -111.219996)
		(mid 21.740114 -110.32998)
		(end 20.850098 -109.439964)
		(stroke
			(width 0.05)
			(type default)
		)
		(layer "Edge.Cuts")
	)
	(gr_arc
		(start 20.850098 -109.439964)
		(mid 19.960082 -110.32998)
		(end 20.850098 -111.219996)
		(stroke
			(width 0.05)
			(type default)
		)
		(layer "Edge.Cuts")
	)
	(gr_arc
		(start 20.850098 -46.220126)
		(mid 21.740114 -45.33011)
		(end 20.850098 -44.440094)
		(stroke
			(width 0.05)
			(type default)
		)
		(layer "Edge.Cuts")
	)
	(gr_arc
		(start 20.850098 -44.440094)
		(mid 19.960082 -45.33011)
		(end 20.850098 -46.220126)
		(stroke
			(width 0.05)
			(type default)
		)
		(layer "Edge.Cuts")
	)
	(gr_arc
		(start 20.850098 -8.219948)
		(mid 21.740114 -7.329932)
		(end 20.850098 -6.439916)
		(stroke
			(width 0.05)
			(type default)
		)
		(layer "Edge.Cuts")
	)
	(gr_arc
		(start 20.850098 -6.439916)
		(mid 19.960082 -7.329932)
		(end 20.850098 -8.219948)
		(stroke
			(width 0.05)
			(type default)
		)
		(layer "Edge.Cuts")
	)
	(gr_line
		(start 30.80004 0)
		(end 32.33674 -3.019552)
		(stroke
			(width 0.05)
			(type default)
		)
		(layer "Edge.Cuts")
	)
	(gr_arc
		(start 32.500062 -4.500118)
		(mid 34.000186 -6.000242)
		(end 35.500056 -4.500118)
		(stroke
			(width 0.05)
			(type default)
		)
		(layer "Edge.Cuts")
	)
	(gr_arc
		(start 32.500062 -3.700018)
		(mid 32.458636 -3.350129)
		(end 32.33674 -3.019552)
		(stroke
			(width 0.05)
			(type default)
		)
		(layer "Edge.Cuts")
	)
	(gr_line
		(start 32.500062 -3.700018)
		(end 32.500062 -4.500118)
		(stroke
			(width 0.05)
			(type default)
		)
		(layer "Edge.Cuts")
	)
	(gr_line
		(start 35.500056 -4.500118)
		(end 35.500056 -3.700018)
		(stroke
			(width 0.05)
			(type default)
		)
		(layer "Edge.Cuts")
	)
	(gr_arc
		(start 35.663124 -3.019552)
		(mid 35.541364 -3.350145)
		(end 35.500056 -3.700018)
		(stroke
			(width 0.05)
			(type default)
		)
		(layer "Edge.Cuts")
	)
	(gr_line
		(start 35.663124 -3.019552)
		(end 37.200078 0)
		(stroke
			(width 0.05)
			(type default)
		)
		(layer "Edge.Cuts")
	)
	(gr_line
		(start 37.200078 0)
		(end 262.50011 0)
		(stroke
			(width 0.05)
			(type default)
		)
		(layer "Edge.Cuts")
	)
	(gr_arc
		(start 41.150032 -499.560088)
		(mid 42.040048 -498.670072)
		(end 41.150032 -497.780056)
		(stroke
			(width 0.05)
			(type default)
		)
		(layer "Edge.Cuts")
	)
	(gr_arc
		(start 41.150032 -497.780056)
		(mid 40.260016 -498.670072)
		(end 41.150032 -499.560088)
		(stroke
			(width 0.05)
			(type default)
		)
		(layer "Edge.Cuts")
	)
	(gr_arc
		(start 41.150032 -461.55991)
		(mid 42.040048 -460.669894)
		(end 41.150032 -459.779878)
		(stroke
			(width 0.05)
			(type default)
		)
		(layer "Edge.Cuts")
	)
	(gr_arc
		(start 41.150032 -459.779878)
		(mid 40.260016 -460.669894)
		(end 41.150032 -461.55991)
		(stroke
			(width 0.05)
			(type default)
		)
		(layer "Edge.Cuts")
	)
	(gr_arc
		(start 41.150032 -396.56004)
		(mid 42.040048 -395.670024)
		(end 41.150032 -394.780008)
		(stroke
			(width 0.05)
			(type default)
		)
		(layer "Edge.Cuts")
	)
	(gr_arc
		(start 41.150032 -394.780008)
		(mid 40.260016 -395.670024)
		(end 41.150032 -396.56004)
		(stroke
			(width 0.05)
			(type default)
		)
		(layer "Edge.Cuts")
	)
	(gr_arc
		(start 41.150032 -358.560116)
		(mid 42.040048 -357.6701)
		(end 41.150032 -356.780084)
		(stroke
			(width 0.05)
			(type default)
		)
		(layer "Edge.Cuts")
	)
	(gr_arc
		(start 41.150032 -356.780084)
		(mid 40.260016 -357.6701)
		(end 41.150032 -358.560116)
		(stroke
			(width 0.05)
			(type default)
		)
		(layer "Edge.Cuts")
	)
	(gr_arc
		(start 41.150032 -293.559992)
		(mid 42.040048 -292.669976)
		(end 41.150032 -291.77996)
		(stroke
			(width 0.05)
			(type default)
		)
		(layer "Edge.Cuts")
	)
	(gr_arc
		(start 41.150032 -291.77996)
		(mid 40.260016 -292.669976)
		(end 41.150032 -293.559992)
		(stroke
			(width 0.05)
			(type default)
		)
		(layer "Edge.Cuts")
	)
	(gr_arc
		(start 41.150032 -255.560068)
		(mid 42.040048 -254.670052)
		(end 41.150032 -253.780036)
		(stroke
			(width 0.05)
			(type default)
		)
		(layer "Edge.Cuts")
	)
	(gr_arc
		(start 41.150032 -253.780036)
		(mid 40.260016 -254.670052)
		(end 41.150032 -255.560068)
		(stroke
			(width 0.05)
			(type default)
		)
		(layer "Edge.Cuts")
	)
	(gr_arc
		(start 41.150032 -190.559944)
		(mid 42.040048 -189.669928)
		(end 41.150032 -188.779912)
		(stroke
			(width 0.05)
			(type default)
		)
		(layer "Edge.Cuts")
	)
	(gr_arc
		(start 41.150032 -188.779912)
		(mid 40.260016 -189.669928)
		(end 41.150032 -190.559944)
		(stroke
			(width 0.05)
			(type default)
		)
		(layer "Edge.Cuts")
	)
	(gr_arc
		(start 41.150032 -152.56002)
		(mid 42.040048 -151.670004)
		(end 41.150032 -150.779988)
		(stroke
			(width 0.05)
			(type default)
		)
		(layer "Edge.Cuts")
	)
	(gr_arc
		(start 41.150032 -150.779988)
		(mid 40.260016 -151.670004)
		(end 41.150032 -152.56002)
		(stroke
			(width 0.05)
			(type default)
		)
		(layer "Edge.Cuts")
	)
	(gr_arc
		(start 41.150032 -87.559896)
		(mid 42.039794 -86.670134)
		(end 41.150032 -85.780118)
		(stroke
			(width 0.05)
			(type default)
		)
		(layer "Edge.Cuts")
	)
	(gr_arc
		(start 41.150032 -85.780118)
		(mid 40.260016 -86.670134)
		(end 41.150032 -87.559896)
		(stroke
			(width 0.05)
			(type default)
		)
		(layer "Edge.Cuts")
	)
	(gr_arc
		(start 41.150032 -49.559972)
		(mid 42.040048 -48.669956)
		(end 41.150032 -47.77994)
		(stroke
			(width 0.05)
			(type default)
		)
		(layer "Edge.Cuts")
	)
	(gr_arc
		(start 41.150032 -47.77994)
		(mid 40.260016 -48.669956)
		(end 41.150032 -49.559972)
		(stroke
			(width 0.05)
			(type default)
		)
		(layer "Edge.Cuts")
	)
	(gr_line
		(start 42.949876 -502.070116)
		(end 44.04995 -502.070116)
		(stroke
			(width 0.05)
			(type default)
		)
		(layer "Edge.Cuts")
	)
	(gr_arc
		(start 42.949876 -501.270016)
		(mid 42.549826 -501.670066)
		(end 42.949876 -502.070116)
		(stroke
			(width 0.05)
			(type default)
		)
		(layer "Edge.Cuts")
	)
	(gr_line
		(start 42.949876 -458.06995)
		(end 44.04995 -458.06995)
		(stroke
			(width 0.05)
			(type default)
		)
		(layer "Edge.Cuts")
	)
	(gr_arc
		(start 42.949876 -457.270104)
		(mid 42.549826 -457.670154)
		(end 42.949876 -458.06995)
		(stroke
			(width 0.05)
			(type default)
		)
		(layer "Edge.Cuts")
	)
	(gr_line
		(start 42.949876 -399.070068)
		(end 44.04995 -399.070068)
		(stroke
			(width 0.05)
			(type default)
		)
		(layer "Edge.Cuts")
	)
	(gr_arc
		(start 42.949876 -398.269968)
		(mid 42.549826 -398.670018)
		(end 42.949876 -399.070068)
		(stroke
			(width 0.05)
			(type default)
		)
		(layer "Edge.Cuts")
	)
	(gr_line
		(start 42.949876 -355.069902)
		(end 44.04995 -355.069902)
		(stroke
			(width 0.05)
			(type default)
		)
		(layer "Edge.Cuts")
	)
	(gr_arc
		(start 42.949876 -354.270056)
		(mid 42.549826 -354.670106)
		(end 42.949876 -355.069902)
		(stroke
			(width 0.05)
			(type default)
		)
		(layer "Edge.Cuts")
	)
	(gr_line
		(start 42.949876 -296.07002)
		(end 44.04995 -296.07002)
		(stroke
			(width 0.05)
			(type default)
		)
		(layer "Edge.Cuts")
	)
	(gr_arc
		(start 42.949876 -295.26992)
		(mid 42.549826 -295.66997)
		(end 42.949876 -296.07002)
		(stroke
			(width 0.05)
			(type default)
		)
		(layer "Edge.Cuts")
	)
	(gr_line
		(start 42.949876 -252.070108)
		(end 44.04995 -252.070108)
		(stroke
			(width 0.05)
			(type default)
		)
		(layer "Edge.Cuts")
	)
	(gr_arc
		(start 42.949876 -251.270008)
		(mid 42.549826 -251.670058)
		(end 42.949876 -252.070108)
		(stroke
			(width 0.05)
			(type default)
		)
		(layer "Edge.Cuts")
	)
	(gr_line
		(start 42.949876 -193.069972)
		(end 44.04995 -193.069972)
		(stroke
			(width 0.05)
			(type default)
		)
		(layer "Edge.Cuts")
	)
	(gr_arc
		(start 42.949876 -192.270126)
		(mid 42.549826 -192.670176)
		(end 42.949876 -193.069972)
		(stroke
			(width 0.05)
			(type default)
		)
		(layer "Edge.Cuts")
	)
	(gr_line
		(start 42.949876 -149.07006)
		(end 44.04995 -149.07006)
		(stroke
			(width 0.05)
			(type default)
		)
		(layer "Edge.Cuts")
	)
	(gr_arc
		(start 42.949876 -148.26996)
		(mid 42.549826 -148.67001)
		(end 42.949876 -149.07006)
		(stroke
			(width 0.05)
			(type default)
		)
		(layer "Edge.Cuts")
	)
	(gr_line
		(start 42.949876 -90.069924)
		(end 44.04995 -90.069924)
		(stroke
			(width 0.05)
			(type default)
		)
		(layer "Edge.Cuts")
	)
	(gr_arc
		(start 42.949876 -89.270078)
		(mid 42.549826 -89.670128)
		(end 42.949876 -90.069924)
		(stroke
			(width 0.05)
			(type default)
		)
		(layer "Edge.Cuts")
	)
	(gr_line
		(start 42.949876 -46.070012)
		(end 44.04995 -46.070012)
		(stroke
			(width 0.05)
			(type default)
		)
		(layer "Edge.Cuts")
	)
	(gr_arc
		(start 42.949876 -45.269912)
		(mid 42.549826 -45.669962)
		(end 42.949876 -46.070012)
		(stroke
			(width 0.05)
			(type default)
		)
		(layer "Edge.Cuts")
	)
	(gr_arc
		(start 44.04995 -502.070116)
		(mid 44.45 -501.670066)
		(end 44.04995 -501.270016)
		(stroke
			(width 0.05)
			(type default)
		)
		(layer "Edge.Cuts")
	)
	(gr_line
		(start 44.04995 -501.270016)
		(end 42.949876 -501.270016)
		(stroke
			(width 0.05)
			(type default)
		)
		(layer "Edge.Cuts")
	)
	(gr_arc
		(start 44.04995 -458.06995)
		(mid 44.449746 -457.670154)
		(end 44.04995 -457.270104)
		(stroke
			(width 0.05)
			(type default)
		)
		(layer "Edge.Cuts")
	)
	(gr_line
		(start 44.04995 -457.270104)
		(end 42.949876 -457.270104)
		(stroke
			(width 0.05)
			(type default)
		)
		(layer "Edge.Cuts")
	)
	(gr_arc
		(start 44.04995 -399.070068)
		(mid 44.45 -398.670018)
		(end 44.04995 -398.269968)
		(stroke
			(width 0.05)
			(type default)
		)
		(layer "Edge.Cuts")
	)
	(gr_line
		(start 44.04995 -398.269968)
		(end 42.949876 -398.269968)
		(stroke
			(width 0.05)
			(type default)
		)
		(layer "Edge.Cuts")
	)
	(gr_arc
		(start 44.04995 -355.069902)
		(mid 44.449746 -354.670106)
		(end 44.04995 -354.270056)
		(stroke
			(width 0.05)
			(type default)
		)
		(layer "Edge.Cuts")
	)
	(gr_line
		(start 44.04995 -354.270056)
		(end 42.949876 -354.270056)
		(stroke
			(width 0.05)
			(type default)
		)
		(layer "Edge.Cuts")
	)
	(gr_arc
		(start 44.04995 -296.07002)
		(mid 44.45 -295.66997)
		(end 44.04995 -295.26992)
		(stroke
			(width 0.05)
			(type default)
		)
		(layer "Edge.Cuts")
	)
	(gr_line
		(start 44.04995 -295.26992)
		(end 42.949876 -295.26992)
		(stroke
			(width 0.05)
			(type default)
		)
		(layer "Edge.Cuts")
	)
	(gr_arc
		(start 44.04995 -252.070108)
		(mid 44.45 -251.670058)
		(end 44.04995 -251.270008)
		(stroke
			(width 0.05)
			(type default)
		)
		(layer "Edge.Cuts")
	)
	(gr_line
		(start 44.04995 -251.270008)
		(end 42.949876 -251.270008)
		(stroke
			(width 0.05)
			(type default)
		)
		(layer "Edge.Cuts")
	)
	(gr_arc
		(start 44.04995 -193.069972)
		(mid 44.449746 -192.670176)
		(end 44.04995 -192.270126)
		(stroke
			(width 0.05)
			(type default)
		)
		(layer "Edge.Cuts")
	)
	(gr_line
		(start 44.04995 -192.270126)
		(end 42.949876 -192.270126)
		(stroke
			(width 0.05)
			(type default)
		)
		(layer "Edge.Cuts")
	)
	(gr_arc
		(start 44.04995 -149.07006)
		(mid 44.45 -148.67001)
		(end 44.04995 -148.26996)
		(stroke
			(width 0.05)
			(type default)
		)
		(layer "Edge.Cuts")
	)
	(gr_line
		(start 44.04995 -148.26996)
		(end 42.949876 -148.26996)
		(stroke
			(width 0.05)
			(type default)
		)
		(layer "Edge.Cuts")
	)
	(gr_arc
		(start 44.04995 -90.069924)
		(mid 44.449746 -89.670128)
		(end 44.04995 -89.270078)
		(stroke
			(width 0.05)
			(type default)
		)
		(layer "Edge.Cuts")
	)
	(gr_line
		(start 44.04995 -89.270078)
		(end 42.949876 -89.270078)
		(stroke
			(width 0.05)
			(type default)
		)
		(layer "Edge.Cuts")
	)
	(gr_arc
		(start 44.04995 -46.070012)
		(mid 44.45 -45.669962)
		(end 44.04995 -45.269912)
		(stroke
			(width 0.05)
			(type default)
		)
		(layer "Edge.Cuts")
	)
	(gr_line
		(start 44.04995 -45.269912)
		(end 42.949876 -45.269912)
		(stroke
			(width 0.05)
			(type default)
		)
		(layer "Edge.Cuts")
	)
	(gr_arc
		(start 68.49999 -380.275084)
		(mid 70.274942 -378.500132)
		(end 68.49999 -376.724926)
		(stroke
			(width 0.05)
			(type default)
		)
		(layer "Edge.Cuts")
	)
	(gr_arc
		(start 68.49999 -376.724926)
		(mid 66.724784 -378.500132)
		(end 68.49999 -380.275084)
		(stroke
			(width 0.05)
			(type default)
		)
		(layer "Edge.Cuts")
	)
	(gr_arc
		(start 68.49999 -71.000112)
		(mid 70.000114 -72.500236)
		(end 71.499984 -71.000112)
		(stroke
			(width 0.05)
			(type default)
		)
		(layer "Edge.Cuts")
	)
	(gr_arc
		(start 68.49999 -69.949568)
		(mid 68.425801 -69.571516)
		(end 68.21424 -69.249544)
		(stroke
			(width 0.05)
			(type default)
		)
		(layer "Edge.Cuts")
	)
	(gr_line
		(start 68.49999 -69.949568)
		(end 68.49999 -71.000112)
		(stroke
			(width 0.05)
			(type default)
		)
		(layer "Edge.Cuts")
	)
	(gr_arc
		(start 68.500498 -483.497636)
		(mid 70.000114 -484.997252)
		(end 71.499476 -483.497636)
		(stroke
			(width 0.05)
			(type default)
		)
		(layer "Edge.Cuts")
	)
	(gr_arc
		(start 68.500498 -482.4476)
		(mid 68.426287 -482.069562)
		(end 68.214748 -481.747576)
		(stroke
			(width 0.05)
			(type default)
		)
		(layer "Edge.Cuts")
	)
	(gr_line
		(start 68.500498 -482.4476)
		(end 68.500498 -483.497636)
		(stroke
			(width 0.05)
			(type default)
		)
		(layer "Edge.Cuts")
	)
	(gr_arc
		(start 68.500498 -276.497542)
		(mid 70.000114 -277.997158)
		(end 71.499476 -276.497542)
		(stroke
			(width 0.05)
			(type default)
		)
		(layer "Edge.Cuts")
	)
	(gr_arc
		(start 68.500498 -275.447506)
		(mid 68.42636 -275.069438)
		(end 68.214748 -274.747482)
		(stroke
			(width 0.05)
			(type default)
		)
		(layer "Edge.Cuts")
	)
	(gr_line
		(start 68.500498 -275.447506)
		(end 68.500498 -276.497542)
		(stroke
			(width 0.05)
			(type default)
		)
		(layer "Edge.Cuts")
	)
	(gr_arc
		(start 68.500498 -173.99762)
		(mid 70.000114 -175.497236)
		(end 71.499476 -173.99762)
		(stroke
			(width 0.05)
			(type default)
		)
		(layer "Edge.Cuts")
	)
	(gr_arc
		(start 68.500498 -172.947584)
		(mid 68.426314 -172.569528)
		(end 68.214748 -172.24756)
		(stroke
			(width 0.05)
			(type default)
		)
		(layer "Edge.Cuts")
	)
	(gr_line
		(start 68.500498 -172.947584)
		(end 68.500498 -173.99762)
		(stroke
			(width 0.05)
			(type default)
		)
		(layer "Edge.Cuts")
	)
	(gr_line
		(start 71.499476 -483.497636)
		(end 71.499476 -482.4476)
		(stroke
			(width 0.05)
			(type default)
		)
		(layer "Edge.Cuts")
	)
	(gr_line
		(start 71.499476 -276.497542)
		(end 71.499476 -275.447506)
		(stroke
			(width 0.05)
			(type default)
		)
		(layer "Edge.Cuts")
	)
	(gr_line
		(start 71.499476 -173.99762)
		(end 71.499476 -172.947584)
		(stroke
			(width 0.05)
			(type default)
		)
		(layer "Edge.Cuts")
	)
	(gr_line
		(start 71.499984 -71.000112)
		(end 71.499984 -69.949568)
		(stroke
			(width 0.05)
			(type default)
		)
		(layer "Edge.Cuts")
	)
	(gr_arc
		(start 71.785226 -481.747576)
		(mid 70.000203 -477.497649)
		(end 68.214748 -481.747576)
		(stroke
			(width 0.05)
			(type default)
		)
		(layer "Edge.Cuts")
	)
	(gr_arc
		(start 71.785226 -481.747576)
		(mid 71.573694 -482.06956)
		(end 71.499476 -482.4476)
		(stroke
			(width 0.05)
			(type default)
		)
		(layer "Edge.Cuts")
	)
	(gr_arc
		(start 71.785226 -274.747482)
		(mid 70.000203 -270.497555)
		(end 68.214748 -274.747482)
		(stroke
			(width 0.05)
			(type default)
		)
		(layer "Edge.Cuts")
	)
	(gr_arc
		(start 71.785226 -274.747482)
		(mid 71.573695 -275.069467)
		(end 71.499476 -275.447506)
		(stroke
			(width 0.05)
			(type default)
		)
		(layer "Edge.Cuts")
	)
	(gr_arc
		(start 71.785226 -172.24756)
		(mid 70.000203 -167.997633)
		(end 68.214748 -172.24756)
		(stroke
			(width 0.05)
			(type default)
		)
		(layer "Edge.Cuts")
	)
	(gr_arc
		(start 71.785226 -172.24756)
		(mid 71.573688 -172.569543)
		(end 71.499476 -172.947584)
		(stroke
			(width 0.05)
			(type default)
		)
		(layer "Edge.Cuts")
	)
	(gr_arc
		(start 71.785734 -69.249544)
		(mid 70.000203 -65.000118)
		(end 68.21424 -69.249544)
		(stroke
			(width 0.05)
			(type default)
		)
		(layer "Edge.Cuts")
	)
	(gr_arc
		(start 71.785734 -69.249544)
		(mid 71.574104 -69.57149)
		(end 71.499984 -69.949568)
		(stroke
			(width 0.05)
			(type default)
		)
		(layer "Edge.Cuts")
	)
	(gr_arc
		(start 226.149916 -499.560088)
		(mid 227.039932 -498.670072)
		(end 226.149916 -497.780056)
		(stroke
			(width 0.05)
			(type default)
		)
		(layer "Edge.Cuts")
	)
	(gr_arc
		(start 226.149916 -497.780056)
		(mid 225.2599 -498.670072)
		(end 226.149916 -499.560088)
		(stroke
			(width 0.05)
			(type default)
		)
		(layer "Edge.Cuts")
	)
	(gr_arc
		(start 226.149916 -461.55991)
		(mid 227.039932 -460.669894)
		(end 226.149916 -459.779878)
		(stroke
			(width 0.05)
			(type default)
		)
		(layer "Edge.Cuts")
	)
	(gr_arc
		(start 226.149916 -459.779878)
		(mid 225.2599 -460.669894)
		(end 226.149916 -461.55991)
		(stroke
			(width 0.05)
			(type default)
		)
		(layer "Edge.Cuts")
	)
	(gr_arc
		(start 226.149916 -396.56004)
		(mid 227.039932 -395.670024)
		(end 226.149916 -394.780008)
		(stroke
			(width 0.05)
			(type default)
		)
		(layer "Edge.Cuts")
	)
	(gr_arc
		(start 226.149916 -394.780008)
		(mid 225.2599 -395.670024)
		(end 226.149916 -396.56004)
		(stroke
			(width 0.05)
			(type default)
		)
		(layer "Edge.Cuts")
	)
	(gr_arc
		(start 226.149916 -358.560116)
		(mid 227.039932 -357.6701)
		(end 226.149916 -356.780084)
		(stroke
			(width 0.05)
			(type default)
		)
		(layer "Edge.Cuts")
	)
	(gr_arc
		(start 226.149916 -356.780084)
		(mid 225.2599 -357.6701)
		(end 226.149916 -358.560116)
		(stroke
			(width 0.05)
			(type default)
		)
		(layer "Edge.Cuts")
	)
	(gr_arc
		(start 226.149916 -293.559992)
		(mid 227.039932 -292.669976)
		(end 226.149916 -291.77996)
		(stroke
			(width 0.05)
			(type default)
		)
		(layer "Edge.Cuts")
	)
	(gr_arc
		(start 226.149916 -291.77996)
		(mid 225.2599 -292.669976)
		(end 226.149916 -293.559992)
		(stroke
			(width 0.05)
			(type default)
		)
		(layer "Edge.Cuts")
	)
	(gr_arc
		(start 226.149916 -255.560068)
		(mid 227.039932 -254.670052)
		(end 226.149916 -253.780036)
		(stroke
			(width 0.05)
			(type default)
		)
		(layer "Edge.Cuts")
	)
	(gr_arc
		(start 226.149916 -253.780036)
		(mid 225.2599 -254.670052)
		(end 226.149916 -255.560068)
		(stroke
			(width 0.05)
			(type default)
		)
		(layer "Edge.Cuts")
	)
	(gr_arc
		(start 226.149916 -190.559944)
		(mid 227.039932 -189.669928)
		(end 226.149916 -188.779912)
		(stroke
			(width 0.05)
			(type default)
		)
		(layer "Edge.Cuts")
	)
	(gr_arc
		(start 226.149916 -188.779912)
		(mid 225.2599 -189.669928)
		(end 226.149916 -190.559944)
		(stroke
			(width 0.05)
			(type default)
		)
		(layer "Edge.Cuts")
	)
	(gr_arc
		(start 226.149916 -152.56002)
		(mid 227.039932 -151.670004)
		(end 226.149916 -150.779988)
		(stroke
			(width 0.05)
			(type default)
		)
		(layer "Edge.Cuts")
	)
	(gr_arc
		(start 226.149916 -150.779988)
		(mid 225.2599 -151.670004)
		(end 226.149916 -152.56002)
		(stroke
			(width 0.05)
			(type default)
		)
		(layer "Edge.Cuts")
	)
	(gr_arc
		(start 226.149916 -87.559896)
		(mid 227.039678 -86.670134)
		(end 226.149916 -85.780118)
		(stroke
			(width 0.05)
			(type default)
		)
		(layer "Edge.Cuts")
	)
	(gr_arc
		(start 226.149916 -85.780118)
		(mid 225.2599 -86.670134)
		(end 226.149916 -87.559896)
		(stroke
			(width 0.05)
			(type default)
		)
		(layer "Edge.Cuts")
	)
	(gr_arc
		(start 226.149916 -49.559972)
		(mid 227.039932 -48.669956)
		(end 226.149916 -47.77994)
		(stroke
			(width 0.05)
			(type default)
		)
		(layer "Edge.Cuts")
	)
	(gr_arc
		(start 226.149916 -47.77994)
		(mid 225.2599 -48.669956)
		(end 226.149916 -49.559972)
		(stroke
			(width 0.05)
			(type default)
		)
		(layer "Edge.Cuts")
	)
	(gr_line
		(start 227.950014 -502.070116)
		(end 229.050088 -502.070116)
		(stroke
			(width 0.05)
			(type default)
		)
		(layer "Edge.Cuts")
	)
	(gr_arc
		(start 227.950014 -501.270016)
		(mid 227.549964 -501.670066)
		(end 227.950014 -502.070116)
		(stroke
			(width 0.05)
			(type default)
		)
		(layer "Edge.Cuts")
	)
	(gr_line
		(start 227.950014 -458.06995)
		(end 229.050088 -458.06995)
		(stroke
			(width 0.05)
			(type default)
		)
		(layer "Edge.Cuts")
	)
	(gr_arc
		(start 227.950014 -457.270104)
		(mid 227.549964 -457.670154)
		(end 227.950014 -458.06995)
		(stroke
			(width 0.05)
			(type default)
		)
		(layer "Edge.Cuts")
	)
	(gr_line
		(start 227.950014 -399.070068)
		(end 229.050088 -399.070068)
		(stroke
			(width 0.05)
			(type default)
		)
		(layer "Edge.Cuts")
	)
	(gr_arc
		(start 227.950014 -398.269968)
		(mid 227.549964 -398.670018)
		(end 227.950014 -399.070068)
		(stroke
			(width 0.05)
			(type default)
		)
		(layer "Edge.Cuts")
	)
	(gr_line
		(start 227.950014 -355.069902)
		(end 229.050088 -355.069902)
		(stroke
			(width 0.05)
			(type default)
		)
		(layer "Edge.Cuts")
	)
	(gr_arc
		(start 227.950014 -354.270056)
		(mid 227.549964 -354.670106)
		(end 227.950014 -355.069902)
		(stroke
			(width 0.05)
			(type default)
		)
		(layer "Edge.Cuts")
	)
	(gr_line
		(start 227.950014 -296.07002)
		(end 229.050088 -296.07002)
		(stroke
			(width 0.05)
			(type default)
		)
		(layer "Edge.Cuts")
	)
	(gr_arc
		(start 227.950014 -295.26992)
		(mid 227.549964 -295.66997)
		(end 227.950014 -296.07002)
		(stroke
			(width 0.05)
			(type default)
		)
		(layer "Edge.Cuts")
	)
	(gr_line
		(start 227.950014 -252.070108)
		(end 229.050088 -252.070108)
		(stroke
			(width 0.05)
			(type default)
		)
		(layer "Edge.Cuts")
	)
	(gr_arc
		(start 227.950014 -251.270008)
		(mid 227.549964 -251.670058)
		(end 227.950014 -252.070108)
		(stroke
			(width 0.05)
			(type default)
		)
		(layer "Edge.Cuts")
	)
	(gr_line
		(start 227.950014 -193.069972)
		(end 229.050088 -193.069972)
		(stroke
			(width 0.05)
			(type default)
		)
		(layer "Edge.Cuts")
	)
	(gr_arc
		(start 227.950014 -192.270126)
		(mid 227.549964 -192.670176)
		(end 227.950014 -193.069972)
		(stroke
			(width 0.05)
			(type default)
		)
		(layer "Edge.Cuts")
	)
	(gr_line
		(start 227.950014 -149.07006)
		(end 229.050088 -149.07006)
		(stroke
			(width 0.05)
			(type default)
		)
		(layer "Edge.Cuts")
	)
	(gr_arc
		(start 227.950014 -148.26996)
		(mid 227.549964 -148.67001)
		(end 227.950014 -149.07006)
		(stroke
			(width 0.05)
			(type default)
		)
		(layer "Edge.Cuts")
	)
	(gr_line
		(start 227.950014 -90.069924)
		(end 229.050088 -90.069924)
		(stroke
			(width 0.05)
			(type default)
		)
		(layer "Edge.Cuts")
	)
	(gr_arc
		(start 227.950014 -89.270078)
		(mid 227.549964 -89.670128)
		(end 227.950014 -90.069924)
		(stroke
			(width 0.05)
			(type default)
		)
		(layer "Edge.Cuts")
	)
	(gr_line
		(start 227.950014 -46.070012)
		(end 229.050088 -46.070012)
		(stroke
			(width 0.05)
			(type default)
		)
		(layer "Edge.Cuts")
	)
	(gr_arc
		(start 227.950014 -45.269912)
		(mid 227.549964 -45.669962)
		(end 227.950014 -46.070012)
		(stroke
			(width 0.05)
			(type default)
		)
		(layer "Edge.Cuts")
	)
	(gr_arc
		(start 229.050088 -502.070116)
		(mid 229.450138 -501.670066)
		(end 229.050088 -501.270016)
		(stroke
			(width 0.05)
			(type default)
		)
		(layer "Edge.Cuts")
	)
	(gr_line
		(start 229.050088 -501.270016)
		(end 227.950014 -501.270016)
		(stroke
			(width 0.05)
			(type default)
		)
		(layer "Edge.Cuts")
	)
	(gr_arc
		(start 229.050088 -458.06995)
		(mid 229.449884 -457.670154)
		(end 229.050088 -457.270104)
		(stroke
			(width 0.05)
			(type default)
		)
		(layer "Edge.Cuts")
	)
	(gr_line
		(start 229.050088 -457.270104)
		(end 227.950014 -457.270104)
		(stroke
			(width 0.05)
			(type default)
		)
		(layer "Edge.Cuts")
	)
	(gr_arc
		(start 229.050088 -399.070068)
		(mid 229.450138 -398.670018)
		(end 229.050088 -398.269968)
		(stroke
			(width 0.05)
			(type default)
		)
		(layer "Edge.Cuts")
	)
	(gr_line
		(start 229.050088 -398.269968)
		(end 227.950014 -398.269968)
		(stroke
			(width 0.05)
			(type default)
		)
		(layer "Edge.Cuts")
	)
	(gr_arc
		(start 229.050088 -355.069902)
		(mid 229.449884 -354.670106)
		(end 229.050088 -354.270056)
		(stroke
			(width 0.05)
			(type default)
		)
		(layer "Edge.Cuts")
	)
	(gr_line
		(start 229.050088 -354.270056)
		(end 227.950014 -354.270056)
		(stroke
			(width 0.05)
			(type default)
		)
		(layer "Edge.Cuts")
	)
	(gr_arc
		(start 229.050088 -296.07002)
		(mid 229.450138 -295.66997)
		(end 229.050088 -295.26992)
		(stroke
			(width 0.05)
			(type default)
		)
		(layer "Edge.Cuts")
	)
	(gr_line
		(start 229.050088 -295.26992)
		(end 227.950014 -295.26992)
		(stroke
			(width 0.05)
			(type default)
		)
		(layer "Edge.Cuts")
	)
	(gr_arc
		(start 229.050088 -252.070108)
		(mid 229.450138 -251.670058)
		(end 229.050088 -251.270008)
		(stroke
			(width 0.05)
			(type default)
		)
		(layer "Edge.Cuts")
	)
	(gr_line
		(start 229.050088 -251.270008)
		(end 227.950014 -251.270008)
		(stroke
			(width 0.05)
			(type default)
		)
		(layer "Edge.Cuts")
	)
	(gr_arc
		(start 229.050088 -193.069972)
		(mid 229.449884 -192.670176)
		(end 229.050088 -192.270126)
		(stroke
			(width 0.05)
			(type default)
		)
		(layer "Edge.Cuts")
	)
	(gr_line
		(start 229.050088 -192.270126)
		(end 227.950014 -192.270126)
		(stroke
			(width 0.05)
			(type default)
		)
		(layer "Edge.Cuts")
	)
	(gr_arc
		(start 229.050088 -149.07006)
		(mid 229.450138 -148.67001)
		(end 229.050088 -148.26996)
		(stroke
			(width 0.05)
			(type default)
		)
		(layer "Edge.Cuts")
	)
	(gr_line
		(start 229.050088 -148.26996)
		(end 227.950014 -148.26996)
		(stroke
			(width 0.05)
			(type default)
		)
		(layer "Edge.Cuts")
	)
	(gr_arc
		(start 229.050088 -90.069924)
		(mid 229.449884 -89.670128)
		(end 229.050088 -89.270078)
		(stroke
			(width 0.05)
			(type default)
		)
		(layer "Edge.Cuts")
	)
	(gr_line
		(start 229.050088 -89.270078)
		(end 227.950014 -89.270078)
		(stroke
			(width 0.05)
			(type default)
		)
		(layer "Edge.Cuts")
	)
	(gr_arc
		(start 229.050088 -46.070012)
		(mid 229.450138 -45.669962)
		(end 229.050088 -45.269912)
		(stroke
			(width 0.05)
			(type default)
		)
		(layer "Edge.Cuts")
	)
	(gr_line
		(start 229.050088 -45.269912)
		(end 227.950014 -45.269912)
		(stroke
			(width 0.05)
			(type default)
		)
		(layer "Edge.Cuts")
	)
	(gr_arc
		(start 252.000512 -483.497636)
		(mid 253.500128 -484.997252)
		(end 254.99949 -483.497636)
		(stroke
			(width 0.05)
			(type default)
		)
		(layer "Edge.Cuts")
	)
	(gr_arc
		(start 252.000512 -482.4476)
		(mid 251.926302 -482.069561)
		(end 251.714762 -481.747576)
		(stroke
			(width 0.05)
			(type default)
		)
		(layer "Edge.Cuts")
	)
	(gr_line
		(start 252.000512 -482.4476)
		(end 252.000512 -483.497636)
		(stroke
			(width 0.05)
			(type default)
		)
		(layer "Edge.Cuts")
	)
	(gr_arc
		(start 252.000512 -274.997418)
		(mid 253.500128 -276.497034)
		(end 254.99949 -274.997418)
		(stroke
			(width 0.05)
			(type default)
		)
		(layer "Edge.Cuts")
	)
	(gr_arc
		(start 252.000512 -273.947636)
		(mid 251.926313 -273.569589)
		(end 251.714762 -273.247612)
		(stroke
			(width 0.05)
			(type default)
		)
		(layer "Edge.Cuts")
	)
	(gr_line
		(start 252.000512 -273.947636)
		(end 252.000512 -274.997418)
		(stroke
			(width 0.05)
			(type default)
		)
		(layer "Edge.Cuts")
	)
	(gr_arc
		(start 252.000512 -174.497492)
		(mid 253.500128 -175.997108)
		(end 254.99949 -174.497492)
		(stroke
			(width 0.05)
			(type default)
		)
		(layer "Edge.Cuts")
	)
	(gr_arc
		(start 252.000512 -173.44771)
		(mid 251.926305 -173.069669)
		(end 251.714762 -172.747686)
		(stroke
			(width 0.05)
			(type default)
		)
		(layer "Edge.Cuts")
	)
	(gr_line
		(start 252.000512 -173.44771)
		(end 252.000512 -174.497492)
		(stroke
			(width 0.05)
			(type default)
		)
		(layer "Edge.Cuts")
	)
	(gr_arc
		(start 252.000512 -41.497504)
		(mid 253.500128 -42.99712)
		(end 254.99949 -41.497504)
		(stroke
			(width 0.05)
			(type default)
		)
		(layer "Edge.Cuts")
	)
	(gr_arc
		(start 252.000512 -40.447468)
		(mid 251.92639 -40.069392)
		(end 251.714762 -39.747444)
		(stroke
			(width 0.05)
			(type default)
		)
		(layer "Edge.Cuts")
	)
	(gr_line
		(start 252.000512 -40.447468)
		(end 252.000512 -41.497504)
		(stroke
			(width 0.05)
			(type default)
		)
		(layer "Edge.Cuts")
	)
	(gr_line
		(start 252.394974 -410.485082)
		(end 259.40004 -410.485082)
		(stroke
			(width 0.05)
			(type default)
		)
		(layer "Edge.Cuts")
	)
	(gr_arc
		(start 252.394974 -409.41498)
		(mid 251.859796 -409.950158)
		(end 252.394974 -410.485082)
		(stroke
			(width 0.05)
			(type default)
		)
		(layer "Edge.Cuts")
	)
	(gr_line
		(start 254.99949 -483.497636)
		(end 254.99949 -482.4476)
		(stroke
			(width 0.05)
			(type default)
		)
		(layer "Edge.Cuts")
	)
	(gr_line
		(start 254.99949 -274.997418)
		(end 254.99949 -273.947636)
		(stroke
			(width 0.05)
			(type default)
		)
		(layer "Edge.Cuts")
	)
	(gr_line
		(start 254.99949 -174.497492)
		(end 254.99949 -173.44771)
		(stroke
			(width 0.05)
			(type default)
		)
		(layer "Edge.Cuts")
	)
	(gr_line
		(start 254.99949 -41.497504)
		(end 254.99949 -40.447468)
		(stroke
			(width 0.05)
			(type default)
		)
		(layer "Edge.Cuts")
	)
	(gr_arc
		(start 255.28524 -481.747576)
		(mid 253.500217 -477.497649)
		(end 251.714762 -481.747576)
		(stroke
			(width 0.05)
			(type default)
		)
		(layer "Edge.Cuts")
	)
	(gr_arc
		(start 255.28524 -481.747576)
		(mid 255.073619 -482.069524)
		(end 254.99949 -482.4476)
		(stroke
			(width 0.05)
			(type default)
		)
		(layer "Edge.Cuts")
	)
	(gr_arc
		(start 255.28524 -273.247612)
		(mid 253.500217 -268.997685)
		(end 251.714762 -273.247612)
		(stroke
			(width 0.05)
			(type default)
		)
		(layer "Edge.Cuts")
	)
	(gr_arc
		(start 255.28524 -273.247612)
		(mid 255.073598 -273.569556)
		(end 254.99949 -273.947636)
		(stroke
			(width 0.05)
			(type default)
		)
		(layer "Edge.Cuts")
	)
	(gr_arc
		(start 255.28524 -172.747686)
		(mid 253.500217 -168.497759)
		(end 251.714762 -172.747686)
		(stroke
			(width 0.05)
			(type default)
		)
		(layer "Edge.Cuts")
	)
	(gr_arc
		(start 255.28524 -172.747686)
		(mid 255.073622 -173.069634)
		(end 254.99949 -173.44771)
		(stroke
			(width 0.05)
			(type default)
		)
		(layer "Edge.Cuts")
	)
	(gr_arc
		(start 255.28524 -39.747444)
		(mid 253.500217 -35.497517)
		(end 251.714762 -39.747444)
		(stroke
			(width 0.05)
			(type default)
		)
		(layer "Edge.Cuts")
	)
	(gr_arc
		(start 255.28524 -39.747444)
		(mid 255.073694 -40.069426)
		(end 254.99949 -40.447468)
		(stroke
			(width 0.05)
			(type default)
		)
		(layer "Edge.Cuts")
	)
	(gr_arc
		(start 256.670048 -496.519962)
		(mid 257.759962 -495.430048)
		(end 256.670048 -494.33988)
		(stroke
			(width 0.05)
			(type default)
		)
		(layer "Edge.Cuts")
	)
	(gr_arc
		(start 256.670048 -494.33988)
		(mid 255.57988 -495.430048)
		(end 256.670048 -496.519962)
		(stroke
			(width 0.05)
			(type default)
		)
		(layer "Edge.Cuts")
	)
	(gr_arc
		(start 256.789936 -12.269978)
		(mid 257.87985 -11.180064)
		(end 256.789936 -10.089896)
		(stroke
			(width 0.05)
			(type default)
		)
		(layer "Edge.Cuts")
	)
	(gr_arc
		(start 256.789936 -10.089896)
		(mid 255.699768 -11.180064)
		(end 256.789936 -12.269978)
		(stroke
			(width 0.05)
			(type default)
		)
		(layer "Edge.Cuts")
	)
	(gr_line
		(start 259.40004 -410.485082)
		(end 259.899912 -410.984954)
		(stroke
			(width 0.05)
			(type default)
		)
		(layer "Edge.Cuts")
	)
	(gr_line
		(start 259.40004 -409.41498)
		(end 252.394974 -409.41498)
		(stroke
			(width 0.05)
			(type default)
		)
		(layer "Edge.Cuts")
	)
	(gr_arc
		(start 259.899912 -432.179984)
		(mid 261.749794 -430.330102)
		(end 259.899912 -428.479966)
		(stroke
			(width 0.05)
			(type default)
		)
		(layer "Edge.Cuts")
	)
	(gr_arc
		(start 259.899912 -428.479966)
		(mid 258.049776 -430.330102)
		(end 259.899912 -432.179984)
		(stroke
			(width 0.05)
			(type default)
		)
		(layer "Edge.Cuts")
	)
	(gr_arc
		(start 259.899912 -425.69003)
		(mid 260.307091 -426.672919)
		(end 261.290054 -427.079918)
		(stroke
			(width 0.05)
			(type default)
		)
		(layer "Edge.Cuts")
	)
	(gr_line
		(start 259.899912 -410.984954)
		(end 259.899912 -425.69003)
		(stroke
			(width 0.05)
			(type default)
		)
		(layer "Edge.Cuts")
	)
	(gr_line
		(start 259.899912 -408.915108)
		(end 259.40004 -409.41498)
		(stroke
			(width 0.05)
			(type default)
		)
		(layer "Edge.Cuts")
	)
	(gr_line
		(start 259.899912 -364.309914)
		(end 259.899912 -408.915108)
		(stroke
			(width 0.05)
			(type default)
		)
		(layer "Edge.Cuts")
	)
	(gr_arc
		(start 259.899912 -361.519978)
		(mid 261.749794 -359.670096)
		(end 259.899912 -357.81996)
		(stroke
			(width 0.05)
			(type default)
		)
		(layer "Edge.Cuts")
	)
	(gr_arc
		(start 259.899912 -357.81996)
		(mid 258.049776 -359.670096)
		(end 259.899912 -361.519978)
		(stroke
			(width 0.05)
			(type default)
		)
		(layer "Edge.Cuts")
	)
	(gr_line
		(start 261.290054 -427.079918)
		(end 262.50011 -427.079918)
		(stroke
			(width 0.05)
			(type default)
		)
		(layer "Edge.Cuts")
	)
	(gr_arc
		(start 261.290054 -362.920026)
		(mid 260.307165 -363.327099)
		(end 259.899912 -364.309914)
		(stroke
			(width 0.05)
			(type default)
		)
		(layer "Edge.Cuts")
	)
	(gr_line
		(start 262.50011 -506.000004)
		(end 0.999998 -506.000004)
		(stroke
			(width 0.05)
			(type default)
		)
		(layer "Edge.Cuts")
	)
	(gr_arc
		(start 262.50011 -506.000004)
		(mid 263.207211 -505.707108)
		(end 263.500108 -505.000006)
		(stroke
			(width 0.05)
			(type default)
		)
		(layer "Edge.Cuts")
	)
	(gr_line
		(start 262.50011 -427.079918)
		(end 263.500108 -428.079916)
		(stroke
			(width 0.05)
			(type default)
		)
		(layer "Edge.Cuts")
	)
	(gr_line
		(start 262.50011 -362.920026)
		(end 261.290054 -362.920026)
		(stroke
			(width 0.05)
			(type default)
		)
		(layer "Edge.Cuts")
	)
	(gr_line
		(start 263.500108 -428.079916)
		(end 263.500108 -505.000006)
		(stroke
			(width 0.05)
			(type default)
		)
		(layer "Edge.Cuts")
	)
	(gr_line
		(start 263.500108 -361.920028)
		(end 262.50011 -362.920026)
		(stroke
			(width 0.05)
			(type default)
		)
		(layer "Edge.Cuts")
	)
	(gr_arc
		(start 263.500108 -0.999998)
		(mid 263.207215 -0.29289)
		(end 262.50011 0)
		(stroke
			(width 0.05)
			(type default)
		)
		(layer "Edge.Cuts")
	)
	(gr_line
		(start 263.500108 -0.999998)
		(end 263.500108 -361.920028)
		(stroke
			(width 0.05)
			(type default)
		)
		(layer "Edge.Cuts")
	)
	(segment
		(start 7.1882 -451.231)
		(end 6.477 -451.231)
		(width 0.174752)
		(layer "F.Cu")
		(net "PE_100M_CLK4_C_P")
	)
	(segment
		(start 3.657854 -448.7418)
		(end 2.249932 -448.7418)
		(width 0.174752)
		(layer "F.Cu")
		(net "PE_100M_CLK4_C_P")
	)
	(segment
		(start 3.908298 -448.992244)
		(end 3.657854 -448.7418)
		(width 0.174752)
		(layer "F.Cu")
		(net "PE_100M_CLK4_C_P")
	)
	(segment
		(start 6.477 -451.231)
		(end 4.238244 -448.992244)
		(width 0.174752)
		(layer "F.Cu")
		(net "PE_100M_CLK4_C_P")
	)
	(segment
		(start 4.238244 -448.992244)
		(end 3.908298 -448.992244)
		(width 0.174752)
		(layer "F.Cu")
		(net "PE_100M_CLK4_C_P")
	)
	(segment
		(start 7.4803 -450.9389)
		(end 7.1882 -451.231)
		(width 0.174752)
		(layer "F.Cu")
		(net "PE_100M_CLK4_C_P")
	)
	(segment
		(start 3.658108 -449.5419)
		(end 2.249932 -449.5419)
		(width 0.174752)
		(layer "F.Cu")
		(net "PE_100M_CLK4_C_N")
	)
	(segment
		(start 3.90271 -449.297298)
		(end 3.658108 -449.5419)
		(width 0.174752)
		(layer "F.Cu")
		(net "PE_100M_CLK4_C_N")
	)
	(segment
		(start 7.4803 -451.8279)
		(end 7.188454 -451.536054)
		(width 0.174752)
		(layer "F.Cu")
		(net "PE_100M_CLK4_C_N")
	)
	(segment
		(start 6.350508 -451.536054)
		(end 4.111752 -449.297298)
		(width 0.174752)
		(layer "F.Cu")
		(net "PE_100M_CLK4_C_N")
	)
	(segment
		(start 7.188454 -451.536054)
		(end 6.350508 -451.536054)
		(width 0.174752)
		(layer "F.Cu")
		(net "PE_100M_CLK4_C_N")
	)
	(segment
		(start 4.111752 -449.297298)
		(end 3.90271 -449.297298)
		(width 0.174752)
		(layer "F.Cu")
		(net "PE_100M_CLK4_C_N")
	)
	(segment
		(start 7.0358 -448.8942)
		(end 7.0358 -449.213732)
		(width 0.174752)
		(layer "F.Cu")
		(net "PE_100M_CLK3_C_P")
	)
	(segment
		(start 14.529054 -431.152808)
		(end 12.065 -433.616862)
		(width 0.174752)
		(layer "F.Cu")
		(net "PE_100M_CLK3_C_P")
	)
	(segment
		(start 7.0358 -449.213732)
		(end 7.2898 -449.467732)
		(width 0.174752)
		(layer "F.Cu")
		(net "PE_100M_CLK3_C_P")
	)
	(segment
		(start 12.065 -433.616862)
		(end 12.065 -443.865)
		(width 0.174752)
		(layer "F.Cu")
		(net "PE_100M_CLK3_C_P")
	)
	(segment
		(start 12.065 -443.865)
		(end 7.0358 -448.8942)
		(width 0.174752)
		(layer "F.Cu")
		(net "PE_100M_CLK3_C_P")
	)
	(segment
		(start 14.826488 -426.287692)
		(end 14.529054 -426.585126)
		(width 0.174752)
		(layer "F.Cu")
		(net "PE_100M_CLK3_C_P")
	)
	(segment
		(start 14.529054 -426.585126)
		(end 14.529054 -431.152808)
		(width 0.174752)
		(layer "F.Cu")
		(net "PE_100M_CLK3_C_P")
	)
	(via
		(at 7.2898 -449.467732)
		(size 0.508)
		(drill 0.254)
		(layers "F.Cu" "B.Cu")
		(net "PE_100M_CLK3_C_P")
	)
	(segment
		(start 1.868932 -447.141854)
		(end 3.658108 -447.141854)
		(width 0.174752)
		(layer "B.Cu")
		(net "PE_100M_CLK3_C_P")
	)
	(segment
		(start 4.92125 -447.38925)
		(end 5.663946 -448.131946)
		(width 0.174752)
		(layer "B.Cu")
		(net "PE_100M_CLK3_C_P")
	)
	(segment
		(start 5.663946 -448.131946)
		(end 6.603492 -448.131946)
		(width 0.174752)
		(layer "B.Cu")
		(net "PE_100M_CLK3_C_P")
	)
	(segment
		(start 3.905504 -447.38925)
		(end 4.92125 -447.38925)
		(width 0.174752)
		(layer "B.Cu")
		(net "PE_100M_CLK3_C_P")
	)
	(segment
		(start 6.603492 -448.131946)
		(end 7.036054 -448.564508)
		(width 0.174752)
		(layer "B.Cu")
		(net "PE_100M_CLK3_C_P")
	)
	(segment
		(start 7.036054 -449.213986)
		(end 7.2898 -449.467732)
		(width 0.174752)
		(layer "B.Cu")
		(net "PE_100M_CLK3_C_P")
	)
	(segment
		(start 7.036054 -448.564508)
		(end 7.036054 -449.213986)
		(width 0.174752)
		(layer "B.Cu")
		(net "PE_100M_CLK3_C_P")
	)
	(segment
		(start 3.658108 -447.141854)
		(end 3.905504 -447.38925)
		(width 0.174752)
		(layer "B.Cu")
		(net "PE_100M_CLK3_C_P")
	)
	(segment
		(start 9.673082 -445.640968)
		(end 9.302496 -446.011808)
		(width 0.174752)
		(layer "F.Cu")
		(net "PE_100M_CLK3_C_N")
	)
	(segment
		(start 11.632184 -435.819296)
		(end 11.632184 -436.343552)
		(width 0.174752)
		(layer "F.Cu")
		(net "PE_100M_CLK3_C_N")
	)
	(segment
		(start 8.376666 -446.954656)
		(end 8.376666 -447.121788)
		(width 0.174752)
		(layer "F.Cu")
		(net "PE_100M_CLK3_C_N")
	)
	(segment
		(start 10.228072 -445.085978)
		(end 10.228072 -445.270382)
		(width 0.174752)
		(layer "F.Cu")
		(net "PE_100M_CLK3_C_N")
	)
	(segment
		(start 11.759946 -433.49037)
		(end 11.759946 -435.691534)
		(width 0.174752)
		(layer "F.Cu")
		(net "PE_100M_CLK3_C_N")
	)
	(segment
		(start 11.759946 -436.471314)
		(end 11.759946 -436.99557)
		(width 0.174752)
		(layer "F.Cu")
		(net "PE_100M_CLK3_C_N")
	)
	(segment
		(start 11.759946 -436.99557)
		(end 11.632184 -437.123332)
		(width 0.174752)
		(layer "F.Cu")
		(net "PE_100M_CLK3_C_N")
	)
	(segment
		(start 14.224 -426.574204)
		(end 14.224 -431.026316)
		(width 0.174752)
		(layer "F.Cu")
		(net "PE_100M_CLK3_C_N")
	)
	(segment
		(start 10.228072 -445.270382)
		(end 9.857486 -445.640968)
		(width 0.174752)
		(layer "F.Cu")
		(net "PE_100M_CLK3_C_N")
	)
	(segment
		(start 11.759946 -437.77535)
		(end 11.759946 -443.738508)
		(width 0.174752)
		(layer "F.Cu")
		(net "PE_100M_CLK3_C_N")
	)
	(segment
		(start 13.937488 -426.287692)
		(end 14.224 -426.574204)
		(width 0.174752)
		(layer "F.Cu")
		(net "PE_100M_CLK3_C_N")
	)
	(segment
		(start 10.783062 -444.715392)
		(end 10.598912 -444.715392)
		(width 0.174752)
		(layer "F.Cu")
		(net "PE_100M_CLK3_C_N")
	)
	(segment
		(start 11.632184 -437.647588)
		(end 11.759946 -437.77535)
		(width 0.174752)
		(layer "F.Cu")
		(net "PE_100M_CLK3_C_N")
	)
	(segment
		(start 9.302496 -446.011808)
		(end 9.302496 -446.195958)
		(width 0.174752)
		(layer "F.Cu")
		(net "PE_100M_CLK3_C_N")
	)
	(segment
		(start 11.759946 -443.738508)
		(end 10.783062 -444.715392)
		(width 0.174752)
		(layer "F.Cu")
		(net "PE_100M_CLK3_C_N")
	)
	(segment
		(start 8.931656 -446.566798)
		(end 8.764524 -446.566798)
		(width 0.174752)
		(layer "F.Cu")
		(net "PE_100M_CLK3_C_N")
	)
	(segment
		(start 11.632184 -437.123332)
		(end 11.632184 -437.647588)
		(width 0.174752)
		(layer "F.Cu")
		(net "PE_100M_CLK3_C_N")
	)
	(segment
		(start 9.302496 -446.195958)
		(end 8.931656 -446.566798)
		(width 0.174752)
		(layer "F.Cu")
		(net "PE_100M_CLK3_C_N")
	)
	(segment
		(start 6.730746 -449.213986)
		(end 6.477 -449.467732)
		(width 0.174752)
		(layer "F.Cu")
		(net "PE_100M_CLK3_C_N")
	)
	(segment
		(start 10.598912 -444.715392)
		(end 10.228072 -445.085978)
		(width 0.174752)
		(layer "F.Cu")
		(net "PE_100M_CLK3_C_N")
	)
	(segment
		(start 8.376666 -447.121788)
		(end 6.730746 -448.767708)
		(width 0.174752)
		(layer "F.Cu")
		(net "PE_100M_CLK3_C_N")
	)
	(segment
		(start 6.730746 -448.767708)
		(end 6.730746 -449.213986)
		(width 0.174752)
		(layer "F.Cu")
		(net "PE_100M_CLK3_C_N")
	)
	(segment
		(start 8.764524 -446.566798)
		(end 8.376666 -446.954656)
		(width 0.174752)
		(layer "F.Cu")
		(net "PE_100M_CLK3_C_N")
	)
	(segment
		(start 14.224 -431.026316)
		(end 11.759946 -433.49037)
		(width 0.174752)
		(layer "F.Cu")
		(net "PE_100M_CLK3_C_N")
	)
	(segment
		(start 9.857486 -445.640968)
		(end 9.673082 -445.640968)
		(width 0.174752)
		(layer "F.Cu")
		(net "PE_100M_CLK3_C_N")
	)
	(segment
		(start 11.632184 -436.343552)
		(end 11.759946 -436.471314)
		(width 0.174752)
		(layer "F.Cu")
		(net "PE_100M_CLK3_C_N")
	)
	(segment
		(start 11.759946 -435.691534)
		(end 11.632184 -435.819296)
		(width 0.174752)
		(layer "F.Cu")
		(net "PE_100M_CLK3_C_N")
	)
	(via
		(at 6.477 -449.467732)
		(size 0.508)
		(drill 0.254)
		(layers "F.Cu" "B.Cu")
		(net "PE_100M_CLK3_C_N")
	)
	(segment
		(start 6.477 -448.437)
		(end 6.731 -448.691)
		(width 0.174752)
		(layer "B.Cu")
		(net "PE_100M_CLK3_C_N")
	)
	(segment
		(start 4.794758 -447.694304)
		(end 5.537454 -448.437)
		(width 0.174752)
		(layer "B.Cu")
		(net "PE_100M_CLK3_C_N")
	)
	(segment
		(start 5.537454 -448.437)
		(end 6.477 -448.437)
		(width 0.174752)
		(layer "B.Cu")
		(net "PE_100M_CLK3_C_N")
	)
	(segment
		(start 3.905504 -447.694304)
		(end 4.794758 -447.694304)
		(width 0.174752)
		(layer "B.Cu")
		(net "PE_100M_CLK3_C_N")
	)
	(segment
		(start 3.657854 -447.941954)
		(end 3.905504 -447.694304)
		(width 0.174752)
		(layer "B.Cu")
		(net "PE_100M_CLK3_C_N")
	)
	(segment
		(start 6.731 -448.691)
		(end 6.731 -449.213732)
		(width 0.174752)
		(layer "B.Cu")
		(net "PE_100M_CLK3_C_N")
	)
	(segment
		(start 6.731 -449.213732)
		(end 6.477 -449.467732)
		(width 0.174752)
		(layer "B.Cu")
		(net "PE_100M_CLK3_C_N")
	)
	(segment
		(start 1.868932 -447.941954)
		(end 3.657854 -447.941954)
		(width 0.174752)
		(layer "B.Cu")
		(net "PE_100M_CLK3_C_N")
	)
	(segment
		(start 8.9408 -384.8354)
		(end 9.2329 -384.5433)
		(width 0.174752)
		(layer "F.Cu")
		(net "PE_100M_CLK2_C_P")
	)
	(segment
		(start 9.195054 -385.603242)
		(end 8.9408 -385.348988)
		(width 0.174752)
		(layer "F.Cu")
		(net "PE_100M_CLK2_C_P")
	)
	(segment
		(start 8.9408 -385.348988)
		(end 8.9408 -384.8354)
		(width 0.174752)
		(layer "F.Cu")
		(net "PE_100M_CLK2_C_P")
	)
	(via
		(at 9.195054 -385.603242)
		(size 0.508)
		(drill 0.254)
		(layers "F.Cu" "B.Cu")
		(net "PE_100M_CLK2_C_P")
	)
	(segment
		(start 5.334254 -384.250946)
		(end 4.802632 -384.782568)
		(width 0.174752)
		(layer "B.Cu")
		(net "PE_100M_CLK2_C_P")
	)
	(segment
		(start 3.808222 -384.741928)
		(end 1.868932 -384.741928)
		(width 0.174752)
		(layer "B.Cu")
		(net "PE_100M_CLK2_C_P")
	)
	(segment
		(start 4.802632 -384.782568)
		(end 3.848862 -384.782568)
		(width 0.174752)
		(layer "B.Cu")
		(net "PE_100M_CLK2_C_P")
	)
	(segment
		(start 8.941054 -384.57759)
		(end 8.61441 -384.250946)
		(width 0.174752)
		(layer "B.Cu")
		(net "PE_100M_CLK2_C_P")
	)
	(segment
		(start 3.848862 -384.782568)
		(end 3.808222 -384.741928)
		(width 0.174752)
		(layer "B.Cu")
		(net "PE_100M_CLK2_C_P")
	)
	(segment
		(start 8.61441 -384.250946)
		(end 5.334254 -384.250946)
		(width 0.174752)
		(layer "B.Cu")
		(net "PE_100M_CLK2_C_P")
	)
	(segment
		(start 9.195054 -385.603242)
		(end 8.941054 -385.349242)
		(width 0.174752)
		(layer "B.Cu")
		(net "PE_100M_CLK2_C_P")
	)
	(segment
		(start 8.941054 -385.349242)
		(end 8.941054 -384.57759)
		(width 0.174752)
		(layer "B.Cu")
		(net "PE_100M_CLK2_C_P")
	)
	(segment
		(start 8.3439 -384.5433)
		(end 8.635746 -384.835146)
		(width 0.174752)
		(layer "F.Cu")
		(net "PE_100M_CLK2_C_N")
	)
	(segment
		(start 8.635746 -385.34975)
		(end 8.382254 -385.603242)
		(width 0.174752)
		(layer "F.Cu")
		(net "PE_100M_CLK2_C_N")
	)
	(segment
		(start 8.635746 -384.835146)
		(end 8.635746 -385.34975)
		(width 0.174752)
		(layer "F.Cu")
		(net "PE_100M_CLK2_C_N")
	)
	(via
		(at 8.382254 -385.603242)
		(size 0.508)
		(drill 0.254)
		(layers "F.Cu" "B.Cu")
		(net "PE_100M_CLK2_C_N")
	)
	(segment
		(start 3.80111 -385.398518)
		(end 3.657854 -385.541774)
		(width 0.174752)
		(layer "B.Cu")
		(net "PE_100M_CLK2_C_N")
	)
	(segment
		(start 6.136894 -384.707638)
		(end 5.985256 -384.556)
		(width 0.174752)
		(layer "B.Cu")
		(net "PE_100M_CLK2_C_N")
	)
	(segment
		(start 7.93115 -384.693922)
		(end 7.427214 -384.693922)
		(width 0.174752)
		(layer "B.Cu")
		(net "PE_100M_CLK2_C_N")
	)
	(segment
		(start 6.613398 -384.707638)
		(end 6.136894 -384.707638)
		(width 0.174752)
		(layer "B.Cu")
		(net "PE_100M_CLK2_C_N")
	)
	(segment
		(start 5.460746 -384.556)
		(end 4.929124 -385.087622)
		(width 0.174752)
		(layer "B.Cu")
		(net "PE_100M_CLK2_C_N")
	)
	(segment
		(start 3.657854 -385.541774)
		(end 1.868932 -385.541774)
		(width 0.174752)
		(layer "B.Cu")
		(net "PE_100M_CLK2_C_N")
	)
	(segment
		(start 6.765036 -384.556)
		(end 6.613398 -384.707638)
		(width 0.174752)
		(layer "B.Cu")
		(net "PE_100M_CLK2_C_N")
	)
	(segment
		(start 8.382254 -385.603242)
		(end 8.636 -385.349496)
		(width 0.174752)
		(layer "B.Cu")
		(net "PE_100M_CLK2_C_N")
	)
	(segment
		(start 8.069072 -384.556)
		(end 7.93115 -384.693922)
		(width 0.174752)
		(layer "B.Cu")
		(net "PE_100M_CLK2_C_N")
	)
	(segment
		(start 5.985256 -384.556)
		(end 5.460746 -384.556)
		(width 0.174752)
		(layer "B.Cu")
		(net "PE_100M_CLK2_C_N")
	)
	(segment
		(start 3.921506 -385.087622)
		(end 3.80111 -385.208018)
		(width 0.174752)
		(layer "B.Cu")
		(net "PE_100M_CLK2_C_N")
	)
	(segment
		(start 7.289292 -384.556)
		(end 6.765036 -384.556)
		(width 0.174752)
		(layer "B.Cu")
		(net "PE_100M_CLK2_C_N")
	)
	(segment
		(start 7.427214 -384.693922)
		(end 7.289292 -384.556)
		(width 0.174752)
		(layer "B.Cu")
		(net "PE_100M_CLK2_C_N")
	)
	(segment
		(start 8.636 -385.349496)
		(end 8.636 -384.704082)
		(width 0.174752)
		(layer "B.Cu")
		(net "PE_100M_CLK2_C_N")
	)
	(segment
		(start 3.80111 -385.208018)
		(end 3.80111 -385.398518)
		(width 0.174752)
		(layer "B.Cu")
		(net "PE_100M_CLK2_C_N")
	)
	(segment
		(start 4.929124 -385.087622)
		(end 3.921506 -385.087622)
		(width 0.174752)
		(layer "B.Cu")
		(net "PE_100M_CLK2_C_N")
	)
	(segment
		(start 8.487918 -384.556)
		(end 8.069072 -384.556)
		(width 0.174752)
		(layer "B.Cu")
		(net "PE_100M_CLK2_C_N")
	)
	(segment
		(start 8.636 -384.704082)
		(end 8.487918 -384.556)
		(width 0.174752)
		(layer "B.Cu")
		(net "PE_100M_CLK2_C_N")
	)
	(segment
		(start 6.527546 -385.3434)
		(end 3.856228 -385.3434)
		(width 0.174752)
		(layer "F.Cu")
		(net "PE_100M_CLK1_C_P")
	)
	(segment
		(start 3.657854 -385.541774)
		(end 2.249932 -385.541774)
		(width 0.174752)
		(layer "F.Cu")
		(net "PE_100M_CLK1_C_P")
	)
	(segment
		(start 7.6708 -378.9299)
		(end 7.366 -379.2347)
		(width 0.174752)
		(layer "F.Cu")
		(net "PE_100M_CLK1_C_P")
	)
	(segment
		(start 3.856228 -385.3434)
		(end 3.657854 -385.541774)
		(width 0.174752)
		(layer "F.Cu")
		(net "PE_100M_CLK1_C_P")
	)
	(segment
		(start 7.366 -379.2347)
		(end 7.366 -384.504946)
		(width 0.174752)
		(layer "F.Cu")
		(net "PE_100M_CLK1_C_P")
	)
	(segment
		(start 7.366 -384.504946)
		(end 6.527546 -385.3434)
		(width 0.174752)
		(layer "F.Cu")
		(net "PE_100M_CLK1_C_P")
	)
	(segment
		(start 7.060946 -382.550162)
		(end 7.060946 -383.074418)
		(width 0.174752)
		(layer "F.Cu")
		(net "PE_100M_CLK1_C_N")
	)
	(segment
		(start 4.60629 -384.910584)
		(end 4.478528 -385.038346)
		(width 0.174752)
		(layer "F.Cu")
		(net "PE_100M_CLK1_C_N")
	)
	(segment
		(start 6.401054 -385.038346)
		(end 5.258308 -385.038346)
		(width 0.174752)
		(layer "F.Cu")
		(net "PE_100M_CLK1_C_N")
	)
	(segment
		(start 7.060946 -380.466346)
		(end 6.933184 -380.594108)
		(width 0.174752)
		(layer "F.Cu")
		(net "PE_100M_CLK1_C_N")
	)
	(segment
		(start 6.7564 -378.9299)
		(end 7.060946 -379.234446)
		(width 0.174752)
		(layer "F.Cu")
		(net "PE_100M_CLK1_C_N")
	)
	(segment
		(start 7.060946 -381.246126)
		(end 7.060946 -381.770382)
		(width 0.174752)
		(layer "F.Cu")
		(net "PE_100M_CLK1_C_N")
	)
	(segment
		(start 5.130546 -384.910584)
		(end 4.60629 -384.910584)
		(width 0.174752)
		(layer "F.Cu")
		(net "PE_100M_CLK1_C_N")
	)
	(segment
		(start 6.933184 -381.118364)
		(end 7.060946 -381.246126)
		(width 0.174752)
		(layer "F.Cu")
		(net "PE_100M_CLK1_C_N")
	)
	(segment
		(start 6.912356 -382.401572)
		(end 7.060946 -382.550162)
		(width 0.174752)
		(layer "F.Cu")
		(net "PE_100M_CLK1_C_N")
	)
	(segment
		(start 6.933184 -380.594108)
		(end 6.933184 -381.118364)
		(width 0.174752)
		(layer "F.Cu")
		(net "PE_100M_CLK1_C_N")
	)
	(segment
		(start 4.478528 -385.038346)
		(end 3.954272 -385.038346)
		(width 0.174752)
		(layer "F.Cu")
		(net "PE_100M_CLK1_C_N")
	)
	(segment
		(start 3.954272 -385.038346)
		(end 3.657854 -384.741928)
		(width 0.174752)
		(layer "F.Cu")
		(net "PE_100M_CLK1_C_N")
	)
	(segment
		(start 6.912356 -381.918972)
		(end 6.912356 -382.401572)
		(width 0.174752)
		(layer "F.Cu")
		(net "PE_100M_CLK1_C_N")
	)
	(segment
		(start 7.060946 -384.378454)
		(end 6.401054 -385.038346)
		(width 0.174752)
		(layer "F.Cu")
		(net "PE_100M_CLK1_C_N")
	)
	(segment
		(start 5.258308 -385.038346)
		(end 5.130546 -384.910584)
		(width 0.174752)
		(layer "F.Cu")
		(net "PE_100M_CLK1_C_N")
	)
	(segment
		(start 6.907784 -383.22758)
		(end 6.907784 -383.701036)
		(width 0.174752)
		(layer "F.Cu")
		(net "PE_100M_CLK1_C_N")
	)
	(segment
		(start 7.060946 -383.854198)
		(end 7.060946 -384.378454)
		(width 0.174752)
		(layer "F.Cu")
		(net "PE_100M_CLK1_C_N")
	)
	(segment
		(start 7.060946 -381.770382)
		(end 6.912356 -381.918972)
		(width 0.174752)
		(layer "F.Cu")
		(net "PE_100M_CLK1_C_N")
	)
	(segment
		(start 7.060946 -383.074418)
		(end 6.907784 -383.22758)
		(width 0.174752)
		(layer "F.Cu")
		(net "PE_100M_CLK1_C_N")
	)
	(segment
		(start 3.657854 -384.741928)
		(end 2.249932 -384.741928)
		(width 0.174752)
		(layer "F.Cu")
		(net "PE_100M_CLK1_C_N")
	)
	(segment
		(start 6.907784 -383.701036)
		(end 7.060946 -383.854198)
		(width 0.174752)
		(layer "F.Cu")
		(net "PE_100M_CLK1_C_N")
	)
	(segment
		(start 7.060946 -379.234446)
		(end 7.060946 -380.466346)
		(width 0.174752)
		(layer "F.Cu")
		(net "PE_100M_CLK1_C_N")
	)
	(segment
		(start 45.697648 -81.004918)
		(end 41.975024 -81.004918)
		(width 0.508)
		(layer "F.Cu")
		(net "12V_PRECH_SSD9")
	)
	(segment
		(start 47.3456 -93.5482)
		(end 47.3456 -82.65287)
		(width 0.508)
		(layer "F.Cu")
		(net "12V_PRECH_SSD9")
	)
	(segment
		(start 47.3456 -93.5482)
		(end 45.4279 -93.5482)
		(width 0.508)
		(layer "F.Cu")
		(net "12V_PRECH_SSD9")
	)
	(segment
		(start 47.3456 -82.65287)
		(end 45.697648 -81.004918)
		(width 0.508)
		(layer "F.Cu")
		(net "12V_PRECH_SSD9")
	)
	(via
		(at 47.3456 -93.5482)
		(size 0.7112)
		(drill 0.3556)
		(layers "F.Cu" "B.Cu")
		(net "12V_PRECH_SSD9")
	)
	(segment
		(start 45.4787 -196.9516)
		(end 47.7012 -196.9516)
		(width 0.508)
		(layer "F.Cu")
		(net "12V_PRECH_SSD8")
	)
	(segment
		(start 47.7012 -185.789316)
		(end 45.91685 -184.004966)
		(width 0.508)
		(layer "F.Cu")
		(net "12V_PRECH_SSD8")
	)
	(segment
		(start 47.7012 -196.9516)
		(end 47.7012 -185.789316)
		(width 0.508)
		(layer "F.Cu")
		(net "12V_PRECH_SSD8")
	)
	(segment
		(start 45.91685 -184.004966)
		(end 41.975024 -184.004966)
		(width 0.508)
		(layer "F.Cu")
		(net "12V_PRECH_SSD8")
	)
	(via
		(at 47.7012 -196.9516)
		(size 0.7112)
		(drill 0.3556)
		(layers "F.Cu" "B.Cu")
		(net "12V_PRECH_SSD8")
	)
	(segment
		(start 47.752 -299.593)
		(end 47.752 -290.576)
		(width 0.508)
		(layer "F.Cu")
		(net "12V_PRECH_SSD7")
	)
	(segment
		(start 47.752 -299.593)
		(end 45.3517 -299.593)
		(width 0.508)
		(layer "F.Cu")
		(net "12V_PRECH_SSD7")
	)
	(segment
		(start 44.181014 -287.005014)
		(end 41.975024 -287.005014)
		(width 0.508)
		(layer "F.Cu")
		(net "12V_PRECH_SSD7")
	)
	(segment
		(start 47.752 -290.576)
		(end 44.181014 -287.005014)
		(width 0.508)
		(layer "F.Cu")
		(net "12V_PRECH_SSD7")
	)
	(via
		(at 47.752 -299.593)
		(size 0.7112)
		(drill 0.3556)
		(layers "F.Cu" "B.Cu")
		(net "12V_PRECH_SSD7")
	)
	(segment
		(start 43.955462 -390.005062)
		(end 41.975024 -390.005062)
		(width 0.508)
		(layer "F.Cu")
		(net "12V_PRECH_SSD6")
	)
	(segment
		(start 47.4218 -402.7678)
		(end 47.4218 -393.4714)
		(width 0.508)
		(layer "F.Cu")
		(net "12V_PRECH_SSD6")
	)
	(segment
		(start 47.4218 -393.4714)
		(end 43.955462 -390.005062)
		(width 0.508)
		(layer "F.Cu")
		(net "12V_PRECH_SSD6")
	)
	(segment
		(start 45.6311 -402.7678)
		(end 47.4218 -402.7678)
		(width 0.508)
		(layer "F.Cu")
		(net "12V_PRECH_SSD6")
	)
	(via
		(at 47.4218 -402.7678)
		(size 0.7112)
		(drill 0.3556)
		(layers "F.Cu" "B.Cu")
		(net "12V_PRECH_SSD6")
	)
	(segment
		(start 36.4363 -502.632218)
		(end 37.105082 -503.301)
		(width 0.508)
		(layer "F.Cu")
		(net "12V_PRECH_SSD5")
	)
	(segment
		(start 36.4363 -501.818656)
		(end 36.4363 -502.632218)
		(width 0.508)
		(layer "F.Cu")
		(net "12V_PRECH_SSD5")
	)
	(segment
		(start 36.4363 -499.1608)
		(end 36.4363 -501.818656)
		(width 0.508)
		(layer "F.Cu")
		(net "12V_PRECH_SSD5")
	)
	(segment
		(start 45.085 -503.301)
		(end 45.986954 -502.399046)
		(width 0.508)
		(layer "F.Cu")
		(net "12V_PRECH_SSD5")
	)
	(segment
		(start 45.986954 -502.399046)
		(end 45.986954 -494.550954)
		(width 0.508)
		(layer "F.Cu")
		(net "12V_PRECH_SSD5")
	)
	(segment
		(start 45.986954 -494.550954)
		(end 44.44111 -493.00511)
		(width 0.508)
		(layer "F.Cu")
		(net "12V_PRECH_SSD5")
	)
	(segment
		(start 37.105082 -503.301)
		(end 45.085 -503.301)
		(width 0.508)
		(layer "F.Cu")
		(net "12V_PRECH_SSD5")
	)
	(segment
		(start 44.44111 -493.00511)
		(end 41.975024 -493.00511)
		(width 0.508)
		(layer "F.Cu")
		(net "12V_PRECH_SSD5")
	)
	(via
		(at 36.4363 -501.818656)
		(size 0.7112)
		(drill 0.3556)
		(layers "F.Cu" "B.Cu")
		(net "12V_PRECH_SSD5")
	)
	(segment
		(start 232.6386 -93.6244)
		(end 232.6386 -82.973164)
		(width 0.508)
		(layer "F.Cu")
		(net "12V_PRECH_SSD4")
	)
	(segment
		(start 230.6955 -93.6244)
		(end 232.6386 -93.6244)
		(width 0.508)
		(layer "F.Cu")
		(net "12V_PRECH_SSD4")
	)
	(segment
		(start 232.6386 -82.973164)
		(end 230.670354 -81.004918)
		(width 0.508)
		(layer "F.Cu")
		(net "12V_PRECH_SSD4")
	)
	(segment
		(start 230.670354 -81.004918)
		(end 226.974908 -81.004918)
		(width 0.508)
		(layer "F.Cu")
		(net "12V_PRECH_SSD4")
	)
	(via
		(at 232.6386 -93.6244)
		(size 0.7112)
		(drill 0.3556)
		(layers "F.Cu" "B.Cu")
		(net "12V_PRECH_SSD4")
	)
	(segment
		(start 231.091486 -184.004966)
		(end 232.6132 -185.52668)
		(width 0.508)
		(layer "F.Cu")
		(net "12V_PRECH_SSD3")
	)
	(segment
		(start 232.6132 -196.7484)
		(end 230.6193 -196.7484)
		(width 0.508)
		(layer "F.Cu")
		(net "12V_PRECH_SSD3")
	)
	(segment
		(start 226.974908 -184.004966)
		(end 231.091486 -184.004966)
		(width 0.508)
		(layer "F.Cu")
		(net "12V_PRECH_SSD3")
	)
	(segment
		(start 232.6132 -185.52668)
		(end 232.6132 -196.7484)
		(width 0.508)
		(layer "F.Cu")
		(net "12V_PRECH_SSD3")
	)
	(via
		(at 232.6132 -196.7484)
		(size 0.7112)
		(drill 0.3556)
		(layers "F.Cu" "B.Cu")
		(net "12V_PRECH_SSD3")
	)
	(segment
		(start 233.4514 -299.8724)
		(end 233.4514 -291.4396)
		(width 0.508)
		(layer "F.Cu")
		(net "12V_PRECH_SSD2")
	)
	(segment
		(start 231.6607 -299.8724)
		(end 233.4514 -299.8724)
		(width 0.508)
		(layer "F.Cu")
		(net "12V_PRECH_SSD2")
	)
	(segment
		(start 233.4514 -291.4396)
		(end 229.016814 -287.005014)
		(width 0.508)
		(layer "F.Cu")
		(net "12V_PRECH_SSD2")
	)
	(segment
		(start 229.016814 -287.005014)
		(end 226.974908 -287.005014)
		(width 0.508)
		(layer "F.Cu")
		(net "12V_PRECH_SSD2")
	)
	(via
		(at 233.4514 -299.8724)
		(size 0.7112)
		(drill 0.3556)
		(layers "F.Cu" "B.Cu")
		(net "12V_PRECH_SSD2")
	)
	(segment
		(start 22.640544 -3.590544)
		(end 24.901398 -3.590544)
		(width 0.508)
		(layer "F.Cu")
		(net "12V_PRECH_SSD14")
	)
	(segment
		(start 17.069054 -2.6162)
		(end 21.6662 -2.6162)
		(width 0.508)
		(layer "F.Cu")
		(net "12V_PRECH_SSD14")
	)
	(segment
		(start 25.7048 -3.590544)
		(end 24.901398 -3.590544)
		(width 0.508)
		(layer "F.Cu")
		(net "12V_PRECH_SSD14")
	)
	(segment
		(start 26.7716 -6.0579)
		(end 26.7462 -4.631944)
		(width 0.508)
		(layer "F.Cu")
		(net "12V_PRECH_SSD14")
	)
	(segment
		(start 16.39824 -3.287014)
		(end 17.069054 -2.6162)
		(width 0.508)
		(layer "F.Cu")
		(net "12V_PRECH_SSD14")
	)
	(segment
		(start 16.39824 -11.050778)
		(end 16.39824 -3.287014)
		(width 0.508)
		(layer "F.Cu")
		(net "12V_PRECH_SSD14")
	)
	(segment
		(start 21.6662 -2.6162)
		(end 22.640544 -3.590544)
		(width 0.508)
		(layer "F.Cu")
		(net "12V_PRECH_SSD14")
	)
	(segment
		(start 18.342356 -12.994894)
		(end 16.39824 -11.050778)
		(width 0.508)
		(layer "F.Cu")
		(net "12V_PRECH_SSD14")
	)
	(segment
		(start 26.7462 -4.631944)
		(end 25.7048 -3.590544)
		(width 0.508)
		(layer "F.Cu")
		(net "12V_PRECH_SSD14")
	)
	(segment
		(start 20.025106 -12.994894)
		(end 18.342356 -12.994894)
		(width 0.508)
		(layer "F.Cu")
		(net "12V_PRECH_SSD14")
	)
	(via
		(at 24.901398 -3.590544)
		(size 0.7112)
		(drill 0.3556)
		(layers "F.Cu" "B.Cu")
		(net "12V_PRECH_SSD14")
	)
	(segment
		(start 16.5862 -100.7872)
		(end 16.0274 -100.7872)
		(width 0.508)
		(layer "F.Cu")
		(net "12V_PRECH_SSD13")
	)
	(segment
		(start 17.1577 -101.2317)
		(end 17.1577 -103.4288)
		(width 0.508)
		(layer "F.Cu")
		(net "12V_PRECH_SSD13")
	)
	(segment
		(start 18.1483 -115.994942)
		(end 20.025106 -115.994942)
		(width 0.508)
		(layer "F.Cu")
		(net "12V_PRECH_SSD13")
	)
	(segment
		(start 16.5862 -100.7872)
		(end 16.7132 -100.7872)
		(width 0.508)
		(layer "F.Cu")
		(net "12V_PRECH_SSD13")
	)
	(segment
		(start 15.2908 -113.137442)
		(end 18.1483 -115.994942)
		(width 0.508)
		(layer "F.Cu")
		(net "12V_PRECH_SSD13")
	)
	(segment
		(start 16.0274 -100.7872)
		(end 15.2908 -101.5238)
		(width 0.508)
		(layer "F.Cu")
		(net "12V_PRECH_SSD13")
	)
	(segment
		(start 15.2908 -101.5238)
		(end 15.2908 -113.137442)
		(width 0.508)
		(layer "F.Cu")
		(net "12V_PRECH_SSD13")
	)
	(segment
		(start 16.7132 -100.7872)
		(end 17.1577 -101.2317)
		(width 0.508)
		(layer "F.Cu")
		(net "12V_PRECH_SSD13")
	)
	(via
		(at 16.5862 -100.7872)
		(size 0.7112)
		(drill 0.3556)
		(layers "F.Cu" "B.Cu")
		(net "12V_PRECH_SSD13")
	)
	(segment
		(start 15.5448 -205.6892)
		(end 15.5448 -216.39149)
		(width 0.508)
		(layer "F.Cu")
		(net "12V_PRECH_SSD12")
	)
	(segment
		(start 17.8181 -204.0001)
		(end 17.2339 -204.0001)
		(width 0.508)
		(layer "F.Cu")
		(net "12V_PRECH_SSD12")
	)
	(segment
		(start 17.2339 -204.0001)
		(end 15.5448 -205.6892)
		(width 0.508)
		(layer "F.Cu")
		(net "12V_PRECH_SSD12")
	)
	(segment
		(start 15.5448 -216.39149)
		(end 18.1483 -218.99499)
		(width 0.508)
		(layer "F.Cu")
		(net "12V_PRECH_SSD12")
	)
	(segment
		(start 18.1483 -218.99499)
		(end 20.025106 -218.99499)
		(width 0.508)
		(layer "F.Cu")
		(net "12V_PRECH_SSD12")
	)
	(segment
		(start 17.8181 -206.5528)
		(end 17.8181 -204.0001)
		(width 0.508)
		(layer "F.Cu")
		(net "12V_PRECH_SSD12")
	)
	(via
		(at 17.8181 -204.0001)
		(size 0.7112)
		(drill 0.3556)
		(layers "F.Cu" "B.Cu")
		(net "12V_PRECH_SSD12")
	)
	(segment
		(start 16.194786 -320.041524)
		(end 18.1483 -321.995038)
		(width 0.508)
		(layer "F.Cu")
		(net "12V_PRECH_SSD11")
	)
	(segment
		(start 17.3101 -306.8828)
		(end 16.5862 -306.8828)
		(width 0.508)
		(layer "F.Cu")
		(net "12V_PRECH_SSD11")
	)
	(segment
		(start 16.5862 -306.8828)
		(end 16.194786 -307.274214)
		(width 0.508)
		(layer "F.Cu")
		(net "12V_PRECH_SSD11")
	)
	(segment
		(start 16.194786 -307.274214)
		(end 16.194786 -320.041524)
		(width 0.508)
		(layer "F.Cu")
		(net "12V_PRECH_SSD11")
	)
	(segment
		(start 17.3101 -309.5498)
		(end 17.3101 -306.8828)
		(width 0.508)
		(layer "F.Cu")
		(net "12V_PRECH_SSD11")
	)
	(segment
		(start 18.1483 -321.995038)
		(end 20.025106 -321.995038)
		(width 0.508)
		(layer "F.Cu")
		(net "12V_PRECH_SSD11")
	)
	(via
		(at 17.3101 -306.8828)
		(size 0.7112)
		(drill 0.3556)
		(layers "F.Cu" "B.Cu")
		(net "12V_PRECH_SSD11")
	)
	(segment
		(start 16.8783 -412.496)
		(end 16.8783 -410.2227)
		(width 0.508)
		(layer "F.Cu")
		(net "12V_PRECH_SSD10")
	)
	(segment
		(start 16.0528 -409.7782)
		(end 15.6464 -409.7782)
		(width 0.508)
		(layer "F.Cu")
		(net "12V_PRECH_SSD10")
	)
	(segment
		(start 15.165832 -410.258768)
		(end 15.165832 -423.781982)
		(width 0.508)
		(layer "F.Cu")
		(net "12V_PRECH_SSD10")
	)
	(segment
		(start 16.8783 -410.2227)
		(end 16.4338 -409.7782)
		(width 0.508)
		(layer "F.Cu")
		(net "12V_PRECH_SSD10")
	)
	(segment
		(start 16.4338 -409.7782)
		(end 16.0528 -409.7782)
		(width 0.508)
		(layer "F.Cu")
		(net "12V_PRECH_SSD10")
	)
	(segment
		(start 15.6464 -409.7782)
		(end 15.165832 -410.258768)
		(width 0.508)
		(layer "F.Cu")
		(net "12V_PRECH_SSD10")
	)
	(segment
		(start 15.165832 -423.781982)
		(end 16.378936 -424.995086)
		(width 0.508)
		(layer "F.Cu")
		(net "12V_PRECH_SSD10")
	)
	(segment
		(start 16.378936 -424.995086)
		(end 20.025106 -424.995086)
		(width 0.508)
		(layer "F.Cu")
		(net "12V_PRECH_SSD10")
	)
	(via
		(at 16.0528 -409.7782)
		(size 0.7112)
		(drill 0.3556)
		(layers "F.Cu" "B.Cu")
		(net "12V_PRECH_SSD10")
	)
	(segment
		(start 233.3244 -402.4884)
		(end 233.3244 -392.65225)
		(width 0.508)
		(layer "F.Cu")
		(net "12V_PRECH_SSD1")
	)
	(segment
		(start 231.2797 -402.4884)
		(end 233.3244 -402.4884)
		(width 0.508)
		(layer "F.Cu")
		(net "12V_PRECH_SSD1")
	)
	(segment
		(start 233.3244 -392.65225)
		(end 230.677212 -390.005062)
		(width 0.508)
		(layer "F.Cu")
		(net "12V_PRECH_SSD1")
	)
	(segment
		(start 230.677212 -390.005062)
		(end 226.974908 -390.005062)
		(width 0.508)
		(layer "F.Cu")
		(net "12V_PRECH_SSD1")
	)
	(via
		(at 233.3244 -402.4884)
		(size 0.7112)
		(drill 0.3556)
		(layers "F.Cu" "B.Cu")
		(net "12V_PRECH_SSD1")
	)
	(segment
		(start 221.4245 -499.237)
		(end 221.4245 -501.777)
		(width 0.508)
		(layer "F.Cu")
		(net "12V_PRECH_SSD0")
	)
	(segment
		(start 229.7684 -503.0216)
		(end 222.0468 -503.0216)
		(width 0.508)
		(layer "F.Cu")
		(net "12V_PRECH_SSD0")
	)
	(segment
		(start 221.4245 -502.3993)
		(end 221.4245 -501.777)
		(width 0.508)
		(layer "F.Cu")
		(net "12V_PRECH_SSD0")
	)
	(segment
		(start 230.632 -502.158)
		(end 229.7684 -503.0216)
		(width 0.508)
		(layer "F.Cu")
		(net "12V_PRECH_SSD0")
	)
	(segment
		(start 226.974908 -493.00511)
		(end 229.606602 -493.00511)
		(width 0.508)
		(layer "F.Cu")
		(net "12V_PRECH_SSD0")
	)
	(segment
		(start 230.632 -494.03)
		(end 230.632 -502.158)
		(width 0.508)
		(layer "F.Cu")
		(net "12V_PRECH_SSD0")
	)
	(segment
		(start 229.606602 -493.00511)
		(end 229.606856 -493.004856)
		(width 0.508)
		(layer "F.Cu")
		(net "12V_PRECH_SSD0")
	)
	(segment
		(start 222.0468 -503.0216)
		(end 221.4245 -502.3993)
		(width 0.508)
		(layer "F.Cu")
		(net "12V_PRECH_SSD0")
	)
	(segment
		(start 229.606856 -493.004856)
		(end 230.632 -494.03)
		(width 0.508)
		(layer "F.Cu")
		(net "12V_PRECH_SSD0")
	)
	(via
		(at 221.4245 -501.777)
		(size 0.7112)
		(drill 0.3556)
		(layers "F.Cu" "B.Cu")
		(net "12V_PRECH_SSD0")
	)
	(segment
		(start 226.6315 -35.563302)
		(end 224.536 -35.563302)
		(width 0.17145)
		(layer "F.Cu")
		(net "SSD4_CLK0_OE_MOS_N")
	)
	(segment
		(start 222.6945 -38.467538)
		(end 221.560644 -39.601394)
		(width 0.17145)
		(layer "F.Cu")
		(net "SSD4_CLK0_OE_MOS_N")
	)
	(segment
		(start 224.536 -35.563302)
		(end 223.961198 -35.563302)
		(width 0.17145)
		(layer "F.Cu")
		(net "SSD4_CLK0_OE_MOS_N")
	)
	(segment
		(start 222.6945 -36.83)
		(end 222.6945 -38.467538)
		(width 0.17145)
		(layer "F.Cu")
		(net "SSD4_CLK0_OE_MOS_N")
	)
	(segment
		(start 223.961198 -35.563302)
		(end 222.6945 -36.83)
		(width 0.17145)
		(layer "F.Cu")
		(net "SSD4_CLK0_OE_MOS_N")
	)
	(segment
		(start 221.560644 -39.601394)
		(end 220.208094 -39.601394)
		(width 0.17145)
		(layer "F.Cu")
		(net "SSD4_CLK0_OE_MOS_N")
	)
	(via
		(at 224.536 -35.563302)
		(size 0.7112)
		(drill 0.3556)
		(layers "F.Cu" "B.Cu")
		(net "SSD4_CLK0_OE_MOS_N")
	)
	(segment
		(start 232.917492 -38.989508)
		(end 232.419398 -38.989508)
		(width 0.17145)
		(layer "F.Cu")
		(net "SSD_ACT_DR4_MOS_N")
	)
	(segment
		(start 227.769674 -39.806372)
		(end 228.27615 -39.299896)
		(width 0.17145)
		(layer "F.Cu")
		(net "SSD_ACT_DR4_MOS_N")
	)
	(segment
		(start 230.854504 -39.299896)
		(end 231.164892 -38.989508)
		(width 0.17145)
		(layer "F.Cu")
		(net "SSD_ACT_DR4_MOS_N")
	)
	(segment
		(start 227.769674 -40.693594)
		(end 227.769674 -39.806372)
		(width 0.17145)
		(layer "F.Cu")
		(net "SSD_ACT_DR4_MOS_N")
	)
	(segment
		(start 231.164892 -38.989508)
		(end 232.419398 -38.989508)
		(width 0.17145)
		(layer "F.Cu")
		(net "SSD_ACT_DR4_MOS_N")
	)
	(segment
		(start 228.27615 -39.299896)
		(end 230.854504 -39.299896)
		(width 0.17145)
		(layer "F.Cu")
		(net "SSD_ACT_DR4_MOS_N")
	)
	(segment
		(start 233.807 -38.1)
		(end 232.917492 -38.989508)
		(width 0.17145)
		(layer "F.Cu")
		(net "SSD_ACT_DR4_MOS_N")
	)
	(segment
		(start 233.807 -34.849562)
		(end 233.807 -38.1)
		(width 0.17145)
		(layer "F.Cu")
		(net "SSD_ACT_DR4_MOS_N")
	)
	(via
		(at 232.419398 -38.989508)
		(size 0.7112)
		(drill 0.3556)
		(layers "F.Cu" "B.Cu")
		(net "SSD_ACT_DR4_MOS_N")
	)
	(segment
		(start 92.05849 -26.5811)
		(end 93.5609 -26.5811)
		(width 0.3048)
		(layer "F.Cu")
		(net "P3V3_SENSE")
	)
	(segment
		(start 95.885 -26.6065)
		(end 97.028 -26.6065)
		(width 0.508)
		(layer "F.Cu")
		(net "P3V3_SENSE")
	)
	(segment
		(start 93.5863 -26.6065)
		(end 93.5609 -26.5811)
		(width 0.508)
		(layer "F.Cu")
		(net "P3V3_SENSE")
	)
	(segment
		(start 94.869 -26.6065)
		(end 93.5863 -26.6065)
		(width 0.508)
		(layer "F.Cu")
		(net "P3V3_SENSE")
	)
	(segment
		(start 95.885 -26.6065)
		(end 94.869 -26.6065)
		(width 0.508)
		(layer "F.Cu")
		(net "P3V3_SENSE")
	)
	(via
		(at 93.5609 -26.5811)
		(size 0.7112)
		(drill 0.3556)
		(layers "F.Cu" "B.Cu")
		(net "P3V3_SENSE")
	)
	(segment
		(start 95.0722 -22.3901)
		(end 93.7133 -22.3901)
		(width 0.508)
		(layer "F.Cu")
		(net "P12V_SSD14_SENSE")
	)
	(segment
		(start 92.05849 -22.4409)
		(end 93.6625 -22.4409)
		(width 0.3048)
		(layer "F.Cu")
		(net "P12V_SSD14_SENSE")
	)
	(segment
		(start 93.7133 -22.3901)
		(end 93.6752 -22.4282)
		(width 0.508)
		(layer "F.Cu")
		(net "P12V_SSD14_SENSE")
	)
	(segment
		(start 97.0788 -22.3901)
		(end 96.0374 -22.3901)
		(width 0.508)
		(layer "F.Cu")
		(net "P12V_SSD14_SENSE")
	)
	(segment
		(start 93.6625 -22.4409)
		(end 93.6752 -22.4282)
		(width 0.3048)
		(layer "F.Cu")
		(net "P12V_SSD14_SENSE")
	)
	(segment
		(start 96.0374 -22.3901)
		(end 95.0722 -22.3901)
		(width 0.508)
		(layer "F.Cu")
		(net "P12V_SSD14_SENSE")
	)
	(via
		(at 93.6752 -22.4282)
		(size 0.7112)
		(drill 0.3556)
		(layers "F.Cu" "B.Cu")
		(net "P12V_SSD14_SENSE")
	)
	(segment
		(start 93.2815 -17.399)
		(end 93.2815 -19.431)
		(width 0.508)
		(layer "F.Cu")
		(net "P12V_SENSE")
	)
	(segment
		(start 91.55938 -21.47062)
		(end 92.329 -20.701)
		(width 0.3048)
		(layer "F.Cu")
		(net "P12V_SENSE")
	)
	(segment
		(start 93.2815 -19.431)
		(end 93.2815 -19.7485)
		(width 0.508)
		(layer "F.Cu")
		(net "P12V_SENSE")
	)
	(segment
		(start 91.55938 -22.4409)
		(end 91.55938 -21.47062)
		(width 0.3048)
		(layer "F.Cu")
		(net "P12V_SENSE")
	)
	(segment
		(start 93.2815 -19.7485)
		(end 92.329 -20.701)
		(width 0.508)
		(layer "F.Cu")
		(net "P12V_SENSE")
	)
	(segment
		(start 93.2815 -16.002)
		(end 93.2815 -14.732)
		(width 0.508)
		(layer "F.Cu")
		(net "P12V_SENSE")
	)
	(segment
		(start 93.2815 -16.002)
		(end 93.2815 -17.399)
		(width 0.508)
		(layer "F.Cu")
		(net "P12V_SENSE")
	)
	(via
		(at 93.2815 -16.002)
		(size 0.7112)
		(drill 0.3556)
		(layers "F.Cu" "B.Cu")
		(net "P12V_SENSE")
	)
	(via
		(at 92.329 -20.701)
		(size 0.7112)
		(drill 0.3556)
		(layers "F.Cu" "B.Cu")
		(net "P12V_SENSE")
	)
	(segment
		(start 48.364902 -138.325098)
		(end 48.641 -138.049)
		(width 0.17145)
		(layer "F.Cu")
		(net "I2C_B_TMP1_A0")
	)
	(segment
		(start 48.8315 -137.8585)
		(end 50.546 -137.8585)
		(width 0.17145)
		(layer "F.Cu")
		(net "I2C_B_TMP1_A0")
	)
	(segment
		(start 46.054772 -138.325098)
		(end 48.364902 -138.325098)
		(width 0.17145)
		(layer "F.Cu")
		(net "I2C_B_TMP1_A0")
	)
	(segment
		(start 50.546 -137.8585)
		(end 51.562 -137.8585)
		(width 0.17145)
		(layer "F.Cu")
		(net "I2C_B_TMP1_A0")
	)
	(segment
		(start 48.641 -138.049)
		(end 48.8315 -137.8585)
		(width 0.17145)
		(layer "F.Cu")
		(net "I2C_B_TMP1_A0")
	)
	(via
		(at 48.641 -138.049)
		(size 0.7112)
		(drill 0.3556)
		(layers "F.Cu" "B.Cu")
		(net "I2C_B_TMP1_A0")
	)
	(segment
		(start 28.6512 -12.4968)
		(end 30.099 -12.4968)
		(width 0.17145)
		(layer "F.Cu")
		(net "DUALPORTEN#14")
	)
	(segment
		(start 28.0924 -12.4968)
		(end 27.314652 -11.719052)
		(width 0.17145)
		(layer "F.Cu")
		(net "DUALPORTEN#14")
	)
	(segment
		(start 24.351234 -10.609834)
		(end 22.800056 -10.609834)
		(width 0.17145)
		(layer "F.Cu")
		(net "DUALPORTEN#14")
	)
	(segment
		(start 25.2984 -11.557)
		(end 24.351234 -10.609834)
		(width 0.17145)
		(layer "F.Cu")
		(net "DUALPORTEN#14")
	)
	(segment
		(start 30.4419 -12.1539)
		(end 30.8864 -12.1539)
		(width 0.17145)
		(layer "F.Cu")
		(net "DUALPORTEN#14")
	)
	(segment
		(start 27.314652 -11.719052)
		(end 27.312366 -11.719052)
		(width 0.17145)
		(layer "F.Cu")
		(net "DUALPORTEN#14")
	)
	(segment
		(start 28.6512 -12.4968)
		(end 28.0924 -12.4968)
		(width 0.17145)
		(layer "F.Cu")
		(net "DUALPORTEN#14")
	)
	(segment
		(start 30.099 -12.4968)
		(end 30.4419 -12.1539)
		(width 0.17145)
		(layer "F.Cu")
		(net "DUALPORTEN#14")
	)
	(segment
		(start 30.8864 -12.1539)
		(end 31.9278 -12.1539)
		(width 0.17145)
		(layer "F.Cu")
		(net "DUALPORTEN#14")
	)
	(segment
		(start 27.312366 -11.719052)
		(end 27.150314 -11.557)
		(width 0.17145)
		(layer "F.Cu")
		(net "DUALPORTEN#14")
	)
	(segment
		(start 27.150314 -11.557)
		(end 25.2984 -11.557)
		(width 0.17145)
		(layer "F.Cu")
		(net "DUALPORTEN#14")
	)
	(via
		(at 28.6512 -12.4968)
		(size 0.7112)
		(drill 0.3556)
		(layers "F.Cu" "B.Cu")
		(net "DUALPORTEN#14")
	)
	(segment
		(start 22.58695 -95.95485)
		(end 23.83155 -95.95485)
		(width 0.17145)
		(layer "F.Cu")
		(net "SSD9_PWREN_R")
	)
	(segment
		(start 25.4635 -95.95485)
		(end 23.83155 -95.95485)
		(width 0.17145)
		(layer "F.Cu")
		(net "SSD9_PWREN_R")
	)
	(via
		(at 23.83155 -95.95485)
		(size 0.7112)
		(drill 0.3556)
		(layers "F.Cu" "B.Cu")
		(net "SSD9_PWREN_R")
	)
	(segment
		(start 41.377616 -35.817302)
		(end 39.89451 -35.817302)
		(width 0.17145)
		(layer "F.Cu")
		(net "SSD9_CLK0_OE_MOS_N")
	)
	(segment
		(start 34.1503 -37.7825)
		(end 33.68675 -37.7825)
		(width 0.17145)
		(layer "F.Cu")
		(net "SSD9_CLK0_OE_MOS_N")
	)
	(segment
		(start 38.354 -37.357812)
		(end 38.354 -37.7825)
		(width 0.17145)
		(layer "F.Cu")
		(net "SSD9_CLK0_OE_MOS_N")
	)
	(segment
		(start 39.476934 -36.234878)
		(end 38.354 -37.357812)
		(width 0.17145)
		(layer "F.Cu")
		(net "SSD9_CLK0_OE_MOS_N")
	)
	(segment
		(start 38.354 -37.7825)
		(end 37.5285 -38.608)
		(width 0.17145)
		(layer "F.Cu")
		(net "SSD9_CLK0_OE_MOS_N")
	)
	(segment
		(start 39.89451 -35.817302)
		(end 39.476934 -36.234878)
		(width 0.17145)
		(layer "F.Cu")
		(net "SSD9_CLK0_OE_MOS_N")
	)
	(segment
		(start 34.9758 -38.608)
		(end 34.1503 -37.7825)
		(width 0.17145)
		(layer "F.Cu")
		(net "SSD9_CLK0_OE_MOS_N")
	)
	(segment
		(start 37.5285 -38.608)
		(end 34.9758 -38.608)
		(width 0.17145)
		(layer "F.Cu")
		(net "SSD9_CLK0_OE_MOS_N")
	)
	(segment
		(start 33.68675 -41.26865)
		(end 33.68675 -37.7825)
		(width 0.17145)
		(layer "F.Cu")
		(net "SSD9_CLK0_OE_MOS_N")
	)
	(via
		(at 39.476934 -36.234878)
		(size 0.7112)
		(drill 0.3556)
		(layers "F.Cu" "B.Cu")
		(net "SSD9_CLK0_OE_MOS_N")
	)
	(segment
		(start 22.58695 -198.95185)
		(end 23.83155 -198.95185)
		(width 0.17145)
		(layer "F.Cu")
		(net "SSD8_PWREN_R")
	)
	(segment
		(start 25.4635 -198.95185)
		(end 23.83155 -198.95185)
		(width 0.17145)
		(layer "F.Cu")
		(net "SSD8_PWREN_R")
	)
	(via
		(at 23.83155 -198.95185)
		(size 0.7112)
		(drill 0.3556)
		(layers "F.Cu" "B.Cu")
		(net "SSD8_PWREN_R")
	)
	(segment
		(start 35.6108 -141.2367)
		(end 35.56 -141.2875)
		(width 0.17145)
		(layer "F.Cu")
		(net "SSD8_CLK0_OE_MOS_N")
	)
	(segment
		(start 38.33876 -139.93876)
		(end 37.973 -139.573)
		(width 0.17145)
		(layer "F.Cu")
		(net "SSD8_CLK0_OE_MOS_N")
	)
	(segment
		(start 35.6108 -139.9032)
		(end 35.6108 -141.2367)
		(width 0.17145)
		(layer "F.Cu")
		(net "SSD8_CLK0_OE_MOS_N")
	)
	(segment
		(start 35.941 -139.573)
		(end 35.6108 -139.9032)
		(width 0.17145)
		(layer "F.Cu")
		(net "SSD8_CLK0_OE_MOS_N")
	)
	(segment
		(start 34.6329 -142.2146)
		(end 35.56 -141.2875)
		(width 0.17145)
		(layer "F.Cu")
		(net "SSD8_CLK0_OE_MOS_N")
	)
	(segment
		(start 32.2326 -142.2146)
		(end 34.6329 -142.2146)
		(width 0.17145)
		(layer "F.Cu")
		(net "SSD8_CLK0_OE_MOS_N")
	)
	(segment
		(start 30.89275 -141.2875)
		(end 30.93085 -141.3256)
		(width 0.17145)
		(layer "F.Cu")
		(net "SSD8_CLK0_OE_MOS_N")
	)
	(segment
		(start 38.33876 -141.4145)
		(end 38.33876 -139.93876)
		(width 0.17145)
		(layer "F.Cu")
		(net "SSD8_CLK0_OE_MOS_N")
	)
	(segment
		(start 31.3436 -141.3256)
		(end 32.2326 -142.2146)
		(width 0.17145)
		(layer "F.Cu")
		(net "SSD8_CLK0_OE_MOS_N")
	)
	(segment
		(start 30.89275 -141.2875)
		(end 30.89275 -143.809212)
		(width 0.17145)
		(layer "F.Cu")
		(net "SSD8_CLK0_OE_MOS_N")
	)
	(segment
		(start 30.93085 -141.3256)
		(end 31.3436 -141.3256)
		(width 0.17145)
		(layer "F.Cu")
		(net "SSD8_CLK0_OE_MOS_N")
	)
	(segment
		(start 30.99435 -143.910812)
		(end 30.99435 -144.68475)
		(width 0.17145)
		(layer "F.Cu")
		(net "SSD8_CLK0_OE_MOS_N")
	)
	(segment
		(start 37.973 -139.573)
		(end 36.7665 -139.573)
		(width 0.17145)
		(layer "F.Cu")
		(net "SSD8_CLK0_OE_MOS_N")
	)
	(segment
		(start 30.89275 -143.809212)
		(end 30.99435 -143.910812)
		(width 0.17145)
		(layer "F.Cu")
		(net "SSD8_CLK0_OE_MOS_N")
	)
	(segment
		(start 36.7665 -139.573)
		(end 35.941 -139.573)
		(width 0.17145)
		(layer "F.Cu")
		(net "SSD8_CLK0_OE_MOS_N")
	)
	(via
		(at 36.7665 -139.573)
		(size 0.7112)
		(drill 0.3556)
		(layers "F.Cu" "B.Cu")
		(net "SSD8_CLK0_OE_MOS_N")
	)
	(segment
		(start 22.58695 -301.94885)
		(end 23.83155 -301.94885)
		(width 0.17145)
		(layer "F.Cu")
		(net "SSD7_PWREN_R")
	)
	(segment
		(start 25.4635 -301.94885)
		(end 23.83155 -301.94885)
		(width 0.17145)
		(layer "F.Cu")
		(net "SSD7_PWREN_R")
	)
	(via
		(at 23.83155 -301.94885)
		(size 0.7112)
		(drill 0.3556)
		(layers "F.Cu" "B.Cu")
		(net "SSD7_PWREN_R")
	)
	(segment
		(start 47.60976 -239.63884)
		(end 47.8536 -239.395)
		(width 0.17145)
		(layer "F.Cu")
		(net "SSD7_CLK0_OE_MOS_N")
	)
	(segment
		(start 47.8536 -239.395)
		(end 48.641 -239.395)
		(width 0.17145)
		(layer "F.Cu")
		(net "SSD7_CLK0_OE_MOS_N")
	)
	(segment
		(start 48.641 -239.395)
		(end 51.377342 -239.395)
		(width 0.17145)
		(layer "F.Cu")
		(net "SSD7_CLK0_OE_MOS_N")
	)
	(segment
		(start 51.377342 -239.395)
		(end 52.07 -240.087658)
		(width 0.17145)
		(layer "F.Cu")
		(net "SSD7_CLK0_OE_MOS_N")
	)
	(segment
		(start 56.73725 -241.992658)
		(end 55.790592 -241.046)
		(width 0.17145)
		(layer "F.Cu")
		(net "SSD7_CLK0_OE_MOS_N")
	)
	(segment
		(start 58.293 -242.119658)
		(end 56.86425 -242.119658)
		(width 0.17145)
		(layer "F.Cu")
		(net "SSD7_CLK0_OE_MOS_N")
	)
	(segment
		(start 55.790592 -241.046)
		(end 54.61 -241.046)
		(width 0.17145)
		(layer "F.Cu")
		(net "SSD7_CLK0_OE_MOS_N")
	)
	(segment
		(start 54.61 -241.046)
		(end 53.651658 -240.087658)
		(width 0.17145)
		(layer "F.Cu")
		(net "SSD7_CLK0_OE_MOS_N")
	)
	(segment
		(start 53.651658 -240.087658)
		(end 52.07 -240.087658)
		(width 0.17145)
		(layer "F.Cu")
		(net "SSD7_CLK0_OE_MOS_N")
	)
	(segment
		(start 47.60976 -241.2365)
		(end 47.60976 -239.63884)
		(width 0.17145)
		(layer "F.Cu")
		(net "SSD7_CLK0_OE_MOS_N")
	)
	(segment
		(start 56.86425 -242.119658)
		(end 56.73725 -241.992658)
		(width 0.17145)
		(layer "F.Cu")
		(net "SSD7_CLK0_OE_MOS_N")
	)
	(via
		(at 48.641 -239.395)
		(size 0.7112)
		(drill 0.3556)
		(layers "F.Cu" "B.Cu")
		(net "SSD7_CLK0_OE_MOS_N")
	)
	(segment
		(start 21.1328 -403.5171)
		(end 19.502374 -403.5171)
		(width 0.17145)
		(layer "F.Cu")
		(net "SSD6_PWREN_R")
	)
	(segment
		(start 22.76475 -403.5171)
		(end 21.1328 -403.5171)
		(width 0.17145)
		(layer "F.Cu")
		(net "SSD6_PWREN_R")
	)
	(segment
		(start 19.502374 -403.5171)
		(end 19.115024 -403.12975)
		(width 0.17145)
		(layer "F.Cu")
		(net "SSD6_PWREN_R")
	)
	(via
		(at 21.1328 -403.5171)
		(size 0.7112)
		(drill 0.3556)
		(layers "F.Cu" "B.Cu")
		(net "SSD6_PWREN_R")
	)
	(segment
		(start 41.377616 -344.563192)
		(end 39.696898 -344.563192)
		(width 0.17145)
		(layer "F.Cu")
		(net "SSD6_CLK0_OE_MOS_N")
	)
	(segment
		(start 35.54476 -347.3704)
		(end 38.52799 -347.3704)
		(width 0.17145)
		(layer "F.Cu")
		(net "SSD6_CLK0_OE_MOS_N")
	)
	(segment
		(start 38.52799 -347.3704)
		(end 39.37 -346.52839)
		(width 0.17145)
		(layer "F.Cu")
		(net "SSD6_CLK0_OE_MOS_N")
	)
	(segment
		(start 34.70275 -350.01454)
		(end 34.70275 -346.52839)
		(width 0.17145)
		(layer "F.Cu")
		(net "SSD6_CLK0_OE_MOS_N")
	)
	(segment
		(start 34.70275 -346.52839)
		(end 35.54476 -347.3704)
		(width 0.17145)
		(layer "F.Cu")
		(net "SSD6_CLK0_OE_MOS_N")
	)
	(segment
		(start 39.696898 -344.563192)
		(end 39.37 -344.89009)
		(width 0.17145)
		(layer "F.Cu")
		(net "SSD6_CLK0_OE_MOS_N")
	)
	(segment
		(start 39.37 -346.52839)
		(end 39.37 -344.89009)
		(width 0.17145)
		(layer "F.Cu")
		(net "SSD6_CLK0_OE_MOS_N")
	)
	(via
		(at 39.37 -344.89009)
		(size 0.7112)
		(drill 0.3556)
		(layers "F.Cu" "B.Cu")
		(net "SSD6_CLK0_OE_MOS_N")
	)
	(segment
		(start 10.64895 -500.17045)
		(end 10.5918 -500.2276)
		(width 0.17145)
		(layer "F.Cu")
		(net "SSD5_PWREN_R")
	)
	(segment
		(start 10.36955 -500.44985)
		(end 10.5918 -500.2276)
		(width 0.17145)
		(layer "F.Cu")
		(net "SSD5_PWREN_R")
	)
	(segment
		(start 9.35355 -500.44985)
		(end 10.36955 -500.44985)
		(width 0.17145)
		(layer "F.Cu")
		(net "SSD5_PWREN_R")
	)
	(segment
		(start 12.1539 -500.17045)
		(end 10.64895 -500.17045)
		(width 0.17145)
		(layer "F.Cu")
		(net "SSD5_PWREN_R")
	)
	(via
		(at 10.5918 -500.2276)
		(size 0.7112)
		(drill 0.3556)
		(layers "F.Cu" "B.Cu")
		(net "SSD5_PWREN_R")
	)
	(segment
		(start 59.87415 -447.0654)
		(end 58.8264 -447.0654)
		(width 0.17145)
		(layer "F.Cu")
		(net "SSD5_CLK0_OE_MOS_N")
	)
	(segment
		(start 52.729384 -449.43776)
		(end 52.729384 -448.133216)
		(width 0.17145)
		(layer "F.Cu")
		(net "SSD5_CLK0_OE_MOS_N")
	)
	(segment
		(start 57.8485 -446.0875)
		(end 56.134 -446.0875)
		(width 0.17145)
		(layer "F.Cu")
		(net "SSD5_CLK0_OE_MOS_N")
	)
	(segment
		(start 61.236606 -449.5546)
		(end 60.80125 -449.119244)
		(width 0.17145)
		(layer "F.Cu")
		(net "SSD5_CLK0_OE_MOS_N")
	)
	(segment
		(start 54.7751 -446.0875)
		(end 53.467 -447.3956)
		(width 0.17145)
		(layer "F.Cu")
		(net "SSD5_CLK0_OE_MOS_N")
	)
	(segment
		(start 56.134 -446.0875)
		(end 54.7751 -446.0875)
		(width 0.17145)
		(layer "F.Cu")
		(net "SSD5_CLK0_OE_MOS_N")
	)
	(segment
		(start 60.80125 -449.119244)
		(end 60.80125 -447.9925)
		(width 0.17145)
		(layer "F.Cu")
		(net "SSD5_CLK0_OE_MOS_N")
	)
	(segment
		(start 52.729384 -448.133216)
		(end 53.467 -447.3956)
		(width 0.17145)
		(layer "F.Cu")
		(net "SSD5_CLK0_OE_MOS_N")
	)
	(segment
		(start 62.1919 -449.5546)
		(end 61.236606 -449.5546)
		(width 0.17145)
		(layer "F.Cu")
		(net "SSD5_CLK0_OE_MOS_N")
	)
	(segment
		(start 60.80125 -447.9925)
		(end 59.87415 -447.0654)
		(width 0.17145)
		(layer "F.Cu")
		(net "SSD5_CLK0_OE_MOS_N")
	)
	(segment
		(start 58.8264 -447.0654)
		(end 57.8485 -446.0875)
		(width 0.17145)
		(layer "F.Cu")
		(net "SSD5_CLK0_OE_MOS_N")
	)
	(via
		(at 53.467 -447.3956)
		(size 0.7112)
		(drill 0.3556)
		(layers "F.Cu" "B.Cu")
		(net "SSD5_CLK0_OE_MOS_N")
	)
	(segment
		(start 207.11795 -95.95485)
		(end 208.36255 -95.95485)
		(width 0.17145)
		(layer "F.Cu")
		(net "SSD4_PWREN_R")
	)
	(segment
		(start 209.9945 -95.95485)
		(end 208.36255 -95.95485)
		(width 0.17145)
		(layer "F.Cu")
		(net "SSD4_PWREN_R")
	)
	(via
		(at 208.36255 -95.95485)
		(size 0.7112)
		(drill 0.3556)
		(layers "F.Cu" "B.Cu")
		(net "SSD4_PWREN_R")
	)
	(segment
		(start 209.9945 -198.95185)
		(end 208.36255 -198.95185)
		(width 0.17145)
		(layer "F.Cu")
		(net "SSD3_PWREN_R")
	)
	(segment
		(start 207.11795 -198.95185)
		(end 208.36255 -198.95185)
		(width 0.17145)
		(layer "F.Cu")
		(net "SSD3_PWREN_R")
	)
	(via
		(at 208.36255 -198.95185)
		(size 0.7112)
		(drill 0.3556)
		(layers "F.Cu" "B.Cu")
		(net "SSD3_PWREN_R")
	)
	(segment
		(start 220.726 -138.99261)
		(end 221.615 -138.99261)
		(width 0.17145)
		(layer "F.Cu")
		(net "SSD3_CLK0_OE_MOS_N")
	)
	(segment
		(start 225.44024 -138.56335)
		(end 226.3775 -138.56335)
		(width 0.17145)
		(layer "F.Cu")
		(net "SSD3_CLK0_OE_MOS_N")
	)
	(segment
		(start 221.13875 -140.23086)
		(end 220.726 -139.81811)
		(width 0.17145)
		(layer "F.Cu")
		(net "SSD3_CLK0_OE_MOS_N")
	)
	(segment
		(start 223.681544 -137.544556)
		(end 224.421446 -137.544556)
		(width 0.17145)
		(layer "F.Cu")
		(net "SSD3_CLK0_OE_MOS_N")
	)
	(segment
		(start 220.345 -141.15161)
		(end 219.7735 -140.58011)
		(width 0.17145)
		(layer "F.Cu")
		(net "SSD3_CLK0_OE_MOS_N")
	)
	(segment
		(start 224.421446 -137.544556)
		(end 225.44024 -138.56335)
		(width 0.17145)
		(layer "F.Cu")
		(net "SSD3_CLK0_OE_MOS_N")
	)
	(segment
		(start 221.615 -138.99261)
		(end 223.063054 -137.544556)
		(width 0.17145)
		(layer "F.Cu")
		(net "SSD3_CLK0_OE_MOS_N")
	)
	(segment
		(start 220.726 -139.81811)
		(end 220.726 -138.99261)
		(width 0.17145)
		(layer "F.Cu")
		(net "SSD3_CLK0_OE_MOS_N")
	)
	(segment
		(start 223.063054 -137.544556)
		(end 223.681544 -137.544556)
		(width 0.17145)
		(layer "F.Cu")
		(net "SSD3_CLK0_OE_MOS_N")
	)
	(segment
		(start 221.13875 -141.15161)
		(end 221.13875 -140.23086)
		(width 0.17145)
		(layer "F.Cu")
		(net "SSD3_CLK0_OE_MOS_N")
	)
	(segment
		(start 221.13875 -141.15161)
		(end 220.345 -141.15161)
		(width 0.17145)
		(layer "F.Cu")
		(net "SSD3_CLK0_OE_MOS_N")
	)
	(via
		(at 223.681544 -137.544556)
		(size 0.7112)
		(drill 0.3556)
		(layers "F.Cu" "B.Cu")
		(net "SSD3_CLK0_OE_MOS_N")
	)
	(segment
		(start 209.9945 -301.94885)
		(end 208.36255 -301.94885)
		(width 0.17145)
		(layer "F.Cu")
		(net "SSD2_PWREN_R")
	)
	(segment
		(start 207.11795 -301.94885)
		(end 208.36255 -301.94885)
		(width 0.17145)
		(layer "F.Cu")
		(net "SSD2_PWREN_R")
	)
	(via
		(at 208.36255 -301.94885)
		(size 0.7112)
		(drill 0.3556)
		(layers "F.Cu" "B.Cu")
		(net "SSD2_PWREN_R")
	)
	(segment
		(start 223.063054 -240.544604)
		(end 223.681544 -240.544604)
		(width 0.17145)
		(layer "F.Cu")
		(net "SSD2_CLK0_OE_MOS_N")
	)
	(segment
		(start 221.615 -241.992658)
		(end 223.063054 -240.544604)
		(width 0.17145)
		(layer "F.Cu")
		(net "SSD2_CLK0_OE_MOS_N")
	)
	(segment
		(start 220.345 -244.151658)
		(end 219.7735 -243.580158)
		(width 0.17145)
		(layer "F.Cu")
		(net "SSD2_CLK0_OE_MOS_N")
	)
	(segment
		(start 224.421446 -240.544604)
		(end 225.44024 -241.563398)
		(width 0.17145)
		(layer "F.Cu")
		(net "SSD2_CLK0_OE_MOS_N")
	)
	(segment
		(start 221.13875 -243.230908)
		(end 220.726 -242.818158)
		(width 0.17145)
		(layer "F.Cu")
		(net "SSD2_CLK0_OE_MOS_N")
	)
	(segment
		(start 225.44024 -241.563398)
		(end 226.3775 -241.563398)
		(width 0.17145)
		(layer "F.Cu")
		(net "SSD2_CLK0_OE_MOS_N")
	)
	(segment
		(start 221.13875 -244.151658)
		(end 221.13875 -243.230908)
		(width 0.17145)
		(layer "F.Cu")
		(net "SSD2_CLK0_OE_MOS_N")
	)
	(segment
		(start 220.726 -242.818158)
		(end 220.726 -241.992658)
		(width 0.17145)
		(layer "F.Cu")
		(net "SSD2_CLK0_OE_MOS_N")
	)
	(segment
		(start 220.726 -241.992658)
		(end 221.615 -241.992658)
		(width 0.17145)
		(layer "F.Cu")
		(net "SSD2_CLK0_OE_MOS_N")
	)
	(segment
		(start 221.13875 -244.151658)
		(end 220.345 -244.151658)
		(width 0.17145)
		(layer "F.Cu")
		(net "SSD2_CLK0_OE_MOS_N")
	)
	(segment
		(start 223.681544 -240.544604)
		(end 224.421446 -240.544604)
		(width 0.17145)
		(layer "F.Cu")
		(net "SSD2_CLK0_OE_MOS_N")
	)
	(via
		(at 223.681544 -240.544604)
		(size 0.7112)
		(drill 0.3556)
		(layers "F.Cu" "B.Cu")
		(net "SSD2_CLK0_OE_MOS_N")
	)
	(segment
		(start 49.3395 -6.02615)
		(end 50.97145 -6.02615)
		(width 0.17145)
		(layer "F.Cu")
		(net "SSD14_PWREN_R")
	)
	(segment
		(start 52.21605 -6.02615)
		(end 50.97145 -6.02615)
		(width 0.17145)
		(layer "F.Cu")
		(net "SSD14_PWREN_R")
	)
	(via
		(at 50.97145 -6.02615)
		(size 0.7112)
		(drill 0.3556)
		(layers "F.Cu" "B.Cu")
		(net "SSD14_PWREN_R")
	)
	(segment
		(start 23.5585 -54.47411)
		(end 21.044408 -54.47411)
		(width 0.17145)
		(layer "F.Cu")
		(net "SSD14_CLK0_OE_MOS_N")
	)
	(segment
		(start 23.9395 -56.88711)
		(end 22.919182 -55.866792)
		(width 0.17145)
		(layer "F.Cu")
		(net "SSD14_CLK0_OE_MOS_N")
	)
	(segment
		(start 23.9395 -56.88711)
		(end 24.823674 -57.771284)
		(width 0.17145)
		(layer "F.Cu")
		(net "SSD14_CLK0_OE_MOS_N")
	)
	(segment
		(start 24.823674 -57.771284)
		(end 24.823674 -59.496198)
		(width 0.17145)
		(layer "F.Cu")
		(net "SSD14_CLK0_OE_MOS_N")
	)
	(segment
		(start 20.499832 -55.669942)
		(end 20.499832 -55.018686)
		(width 0.17145)
		(layer "F.Cu")
		(net "SSD14_CLK0_OE_MOS_N")
	)
	(segment
		(start 22.919182 -55.866792)
		(end 20.696682 -55.866792)
		(width 0.17145)
		(layer "F.Cu")
		(net "SSD14_CLK0_OE_MOS_N")
	)
	(segment
		(start 21.044408 -54.47411)
		(end 20.499832 -55.018686)
		(width 0.17145)
		(layer "F.Cu")
		(net "SSD14_CLK0_OE_MOS_N")
	)
	(segment
		(start 20.696682 -55.866792)
		(end 20.499832 -55.669942)
		(width 0.17145)
		(layer "F.Cu")
		(net "SSD14_CLK0_OE_MOS_N")
	)
	(segment
		(start 24.823674 -59.496198)
		(end 24.823674 -61.433202)
		(width 0.17145)
		(layer "F.Cu")
		(net "SSD14_CLK0_OE_MOS_N")
	)
	(via
		(at 24.823674 -59.496198)
		(size 0.7112)
		(drill 0.3556)
		(layers "F.Cu" "B.Cu")
		(net "SSD14_CLK0_OE_MOS_N")
	)
	(segment
		(start 36.41725 -100.9269)
		(end 38.0492 -100.9269)
		(width 0.17145)
		(layer "F.Cu")
		(net "SSD13_PWREN_R")
	)
	(segment
		(start 39.2938 -100.9269)
		(end 38.0492 -100.9269)
		(width 0.17145)
		(layer "F.Cu")
		(net "SSD13_PWREN_R")
	)
	(via
		(at 38.0492 -100.9269)
		(size 0.7112)
		(drill 0.3556)
		(layers "F.Cu" "B.Cu")
		(net "SSD13_PWREN_R")
	)
	(segment
		(start 21.044408 -157.474158)
		(end 20.499832 -158.018734)
		(width 0.17145)
		(layer "F.Cu")
		(net "SSD13_CLK0_OE_MOS_N")
	)
	(segment
		(start 20.706842 -158.877)
		(end 20.499832 -158.66999)
		(width 0.17145)
		(layer "F.Cu")
		(net "SSD13_CLK0_OE_MOS_N")
	)
	(segment
		(start 24.823674 -162.496246)
		(end 24.823674 -164.43325)
		(width 0.17145)
		(layer "F.Cu")
		(net "SSD13_CLK0_OE_MOS_N")
	)
	(segment
		(start 23.9395 -159.887158)
		(end 24.823674 -160.771332)
		(width 0.17145)
		(layer "F.Cu")
		(net "SSD13_CLK0_OE_MOS_N")
	)
	(segment
		(start 23.9395 -159.887158)
		(end 22.929342 -158.877)
		(width 0.17145)
		(layer "F.Cu")
		(net "SSD13_CLK0_OE_MOS_N")
	)
	(segment
		(start 23.5585 -157.474158)
		(end 21.044408 -157.474158)
		(width 0.17145)
		(layer "F.Cu")
		(net "SSD13_CLK0_OE_MOS_N")
	)
	(segment
		(start 22.929342 -158.877)
		(end 20.706842 -158.877)
		(width 0.17145)
		(layer "F.Cu")
		(net "SSD13_CLK0_OE_MOS_N")
	)
	(segment
		(start 20.499832 -158.66999)
		(end 20.499832 -158.018734)
		(width 0.17145)
		(layer "F.Cu")
		(net "SSD13_CLK0_OE_MOS_N")
	)
	(segment
		(start 24.823674 -160.771332)
		(end 24.823674 -162.496246)
		(width 0.17145)
		(layer "F.Cu")
		(net "SSD13_CLK0_OE_MOS_N")
	)
	(via
		(at 24.823674 -162.496246)
		(size 0.7112)
		(drill 0.3556)
		(layers "F.Cu" "B.Cu")
		(net "SSD13_CLK0_OE_MOS_N")
	)
	(segment
		(start 40.259 -204.2795)
		(end 39.50335 -204.2795)
		(width 0.17145)
		(layer "F.Cu")
		(net "SSD12_PWREN_R")
	)
	(segment
		(start 36.5125 -204.01915)
		(end 38.14445 -204.01915)
		(width 0.17145)
		(layer "F.Cu")
		(net "SSD12_PWREN_R")
	)
	(segment
		(start 39.50335 -204.2795)
		(end 39.243 -204.01915)
		(width 0.17145)
		(layer "F.Cu")
		(net "SSD12_PWREN_R")
	)
	(segment
		(start 39.243 -204.01915)
		(end 38.14445 -204.01915)
		(width 0.17145)
		(layer "F.Cu")
		(net "SSD12_PWREN_R")
	)
	(via
		(at 38.14445 -204.01915)
		(size 0.7112)
		(drill 0.3556)
		(layers "F.Cu" "B.Cu")
		(net "SSD12_PWREN_R")
	)
	(segment
		(start 22.926548 -261.874)
		(end 20.704048 -261.874)
		(width 0.17145)
		(layer "F.Cu")
		(net "SSD12_CLK0_OE_MOS_N")
	)
	(segment
		(start 20.499832 -261.669784)
		(end 20.499832 -261.018528)
		(width 0.17145)
		(layer "F.Cu")
		(net "SSD12_CLK0_OE_MOS_N")
	)
	(segment
		(start 23.9395 -262.886952)
		(end 22.926548 -261.874)
		(width 0.17145)
		(layer "F.Cu")
		(net "SSD12_CLK0_OE_MOS_N")
	)
	(segment
		(start 24.823674 -265.49604)
		(end 24.823674 -267.433044)
		(width 0.17145)
		(layer "F.Cu")
		(net "SSD12_CLK0_OE_MOS_N")
	)
	(segment
		(start 23.9395 -262.886952)
		(end 24.823674 -263.771126)
		(width 0.17145)
		(layer "F.Cu")
		(net "SSD12_CLK0_OE_MOS_N")
	)
	(segment
		(start 21.044408 -260.473952)
		(end 20.499832 -261.018528)
		(width 0.17145)
		(layer "F.Cu")
		(net "SSD12_CLK0_OE_MOS_N")
	)
	(segment
		(start 23.5585 -260.473952)
		(end 21.044408 -260.473952)
		(width 0.17145)
		(layer "F.Cu")
		(net "SSD12_CLK0_OE_MOS_N")
	)
	(segment
		(start 20.704048 -261.874)
		(end 20.499832 -261.669784)
		(width 0.17145)
		(layer "F.Cu")
		(net "SSD12_CLK0_OE_MOS_N")
	)
	(segment
		(start 24.823674 -263.771126)
		(end 24.823674 -265.49604)
		(width 0.17145)
		(layer "F.Cu")
		(net "SSD12_CLK0_OE_MOS_N")
	)
	(via
		(at 24.823674 -265.49604)
		(size 0.7112)
		(drill 0.3556)
		(layers "F.Cu" "B.Cu")
		(net "SSD12_CLK0_OE_MOS_N")
	)
	(segment
		(start 36.5125 -307.01615)
		(end 38.14445 -307.01615)
		(width 0.17145)
		(layer "F.Cu")
		(net "SSD11_PWREN_R")
	)
	(segment
		(start 39.38905 -307.01615)
		(end 38.14445 -307.01615)
		(width 0.17145)
		(layer "F.Cu")
		(net "SSD11_PWREN_R")
	)
	(via
		(at 38.14445 -307.01615)
		(size 0.7112)
		(drill 0.3556)
		(layers "F.Cu" "B.Cu")
		(net "SSD11_PWREN_R")
	)
	(segment
		(start 20.828 -364.998)
		(end 20.499832 -364.669832)
		(width 0.17145)
		(layer "F.Cu")
		(net "SSD11_CLK0_OE_MOS_N")
	)
	(segment
		(start 24.823674 -368.496088)
		(end 24.823674 -370.433092)
		(width 0.17145)
		(layer "F.Cu")
		(net "SSD11_CLK0_OE_MOS_N")
	)
	(segment
		(start 23.5585 -363.474)
		(end 21.044408 -363.474)
		(width 0.17145)
		(layer "F.Cu")
		(net "SSD11_CLK0_OE_MOS_N")
	)
	(segment
		(start 23.9395 -365.887)
		(end 23.0505 -364.998)
		(width 0.17145)
		(layer "F.Cu")
		(net "SSD11_CLK0_OE_MOS_N")
	)
	(segment
		(start 20.499832 -364.669832)
		(end 20.499832 -364.018576)
		(width 0.17145)
		(layer "F.Cu")
		(net "SSD11_CLK0_OE_MOS_N")
	)
	(segment
		(start 23.9395 -365.887)
		(end 24.823674 -366.771174)
		(width 0.17145)
		(layer "F.Cu")
		(net "SSD11_CLK0_OE_MOS_N")
	)
	(segment
		(start 24.823674 -366.771174)
		(end 24.823674 -368.496088)
		(width 0.17145)
		(layer "F.Cu")
		(net "SSD11_CLK0_OE_MOS_N")
	)
	(segment
		(start 21.044408 -363.474)
		(end 20.499832 -364.018576)
		(width 0.17145)
		(layer "F.Cu")
		(net "SSD11_CLK0_OE_MOS_N")
	)
	(segment
		(start 23.0505 -364.998)
		(end 20.828 -364.998)
		(width 0.17145)
		(layer "F.Cu")
		(net "SSD11_CLK0_OE_MOS_N")
	)
	(via
		(at 24.823674 -368.496088)
		(size 0.7112)
		(drill 0.3556)
		(layers "F.Cu" "B.Cu")
		(net "SSD11_CLK0_OE_MOS_N")
	)
	(segment
		(start 39.38905 -410.01315)
		(end 38.14445 -410.01315)
		(width 0.17145)
		(layer "F.Cu")
		(net "SSD10_PWREN_R")
	)
	(segment
		(start 36.5125 -410.01315)
		(end 38.14445 -410.01315)
		(width 0.17145)
		(layer "F.Cu")
		(net "SSD10_PWREN_R")
	)
	(via
		(at 38.14445 -410.01315)
		(size 0.7112)
		(drill 0.3556)
		(layers "F.Cu" "B.Cu")
		(net "SSD10_PWREN_R")
	)
	(segment
		(start 18.15465 -470.4461)
		(end 18.15465 -471.36685)
		(width 0.17145)
		(layer "F.Cu")
		(net "SSD10_CLK0_OE_MOS_N")
	)
	(segment
		(start 18.9357 -468.9221)
		(end 18.15465 -469.70315)
		(width 0.17145)
		(layer "F.Cu")
		(net "SSD10_CLK0_OE_MOS_N")
	)
	(segment
		(start 20.008596 -474.2561)
		(end 18.5674 -474.2561)
		(width 0.17145)
		(layer "F.Cu")
		(net "SSD10_CLK0_OE_MOS_N")
	)
	(segment
		(start 21.75256 -469.1761)
		(end 21.75256 -469.689688)
		(width 0.17145)
		(layer "F.Cu")
		(net "SSD10_CLK0_OE_MOS_N")
	)
	(segment
		(start 22.278594 -471.986102)
		(end 21.200618 -473.064078)
		(width 0.17145)
		(layer "F.Cu")
		(net "SSD10_CLK0_OE_MOS_N")
	)
	(segment
		(start 21.75256 -469.689688)
		(end 22.278594 -470.215722)
		(width 0.17145)
		(layer "F.Cu")
		(net "SSD10_CLK0_OE_MOS_N")
	)
	(segment
		(start 19.5834 -468.9221)
		(end 18.9357 -468.9221)
		(width 0.17145)
		(layer "F.Cu")
		(net "SSD10_CLK0_OE_MOS_N")
	)
	(segment
		(start 21.200618 -473.064078)
		(end 20.008596 -474.2561)
		(width 0.17145)
		(layer "F.Cu")
		(net "SSD10_CLK0_OE_MOS_N")
	)
	(segment
		(start 18.3642 -474.0529)
		(end 18.5674 -474.2561)
		(width 0.17145)
		(layer "F.Cu")
		(net "SSD10_CLK0_OE_MOS_N")
	)
	(segment
		(start 18.3642 -471.5764)
		(end 18.3642 -474.0529)
		(width 0.17145)
		(layer "F.Cu")
		(net "SSD10_CLK0_OE_MOS_N")
	)
	(segment
		(start 18.15465 -471.36685)
		(end 18.3642 -471.5764)
		(width 0.17145)
		(layer "F.Cu")
		(net "SSD10_CLK0_OE_MOS_N")
	)
	(segment
		(start 18.15465 -469.70315)
		(end 18.15465 -470.4461)
		(width 0.17145)
		(layer "F.Cu")
		(net "SSD10_CLK0_OE_MOS_N")
	)
	(segment
		(start 22.278594 -470.215722)
		(end 22.278594 -471.986102)
		(width 0.17145)
		(layer "F.Cu")
		(net "SSD10_CLK0_OE_MOS_N")
	)
	(via
		(at 21.200618 -473.064078)
		(size 0.7112)
		(drill 0.3556)
		(layers "F.Cu" "B.Cu")
		(net "SSD10_CLK0_OE_MOS_N")
	)
	(segment
		(start 207.11795 -404.94585)
		(end 208.36255 -404.94585)
		(width 0.17145)
		(layer "F.Cu")
		(net "SSD1_PWREN_R")
	)
	(segment
		(start 209.9945 -404.94585)
		(end 208.36255 -404.94585)
		(width 0.17145)
		(layer "F.Cu")
		(net "SSD1_PWREN_R")
	)
	(via
		(at 208.36255 -404.94585)
		(size 0.7112)
		(drill 0.3556)
		(layers "F.Cu" "B.Cu")
		(net "SSD1_PWREN_R")
	)
	(segment
		(start 221.13875 -347.151452)
		(end 220.345 -347.151452)
		(width 0.17145)
		(layer "F.Cu")
		(net "SSD1_CLK0_OE_MOS_N")
	)
	(segment
		(start 220.345 -347.151452)
		(end 219.7735 -346.579952)
		(width 0.17145)
		(layer "F.Cu")
		(net "SSD1_CLK0_OE_MOS_N")
	)
	(segment
		(start 220.726 -344.992452)
		(end 221.5515 -344.992452)
		(width 0.17145)
		(layer "F.Cu")
		(net "SSD1_CLK0_OE_MOS_N")
	)
	(segment
		(start 221.5515 -344.992452)
		(end 222.999554 -343.544398)
		(width 0.17145)
		(layer "F.Cu")
		(net "SSD1_CLK0_OE_MOS_N")
	)
	(segment
		(start 225.44024 -344.563192)
		(end 226.3775 -344.563192)
		(width 0.17145)
		(layer "F.Cu")
		(net "SSD1_CLK0_OE_MOS_N")
	)
	(segment
		(start 224.421446 -343.544398)
		(end 225.44024 -344.563192)
		(width 0.17145)
		(layer "F.Cu")
		(net "SSD1_CLK0_OE_MOS_N")
	)
	(segment
		(start 223.681544 -343.544398)
		(end 224.421446 -343.544398)
		(width 0.17145)
		(layer "F.Cu")
		(net "SSD1_CLK0_OE_MOS_N")
	)
	(segment
		(start 222.999554 -343.544398)
		(end 223.681544 -343.544398)
		(width 0.17145)
		(layer "F.Cu")
		(net "SSD1_CLK0_OE_MOS_N")
	)
	(segment
		(start 221.13875 -346.230702)
		(end 220.726 -345.817952)
		(width 0.17145)
		(layer "F.Cu")
		(net "SSD1_CLK0_OE_MOS_N")
	)
	(segment
		(start 221.13875 -347.151452)
		(end 221.13875 -346.230702)
		(width 0.17145)
		(layer "F.Cu")
		(net "SSD1_CLK0_OE_MOS_N")
	)
	(segment
		(start 220.726 -345.817952)
		(end 220.726 -344.992452)
		(width 0.17145)
		(layer "F.Cu")
		(net "SSD1_CLK0_OE_MOS_N")
	)
	(via
		(at 223.681544 -343.544398)
		(size 0.7112)
		(drill 0.3556)
		(layers "F.Cu" "B.Cu")
		(net "SSD1_CLK0_OE_MOS_N")
	)
	(segment
		(start 196.847206 -499.943628)
		(end 195.215256 -499.943628)
		(width 0.17145)
		(layer "F.Cu")
		(net "SSD0_PWREN_R")
	)
	(segment
		(start 193.970656 -499.943628)
		(end 195.215256 -499.943628)
		(width 0.17145)
		(layer "F.Cu")
		(net "SSD0_PWREN_R")
	)
	(via
		(at 195.215256 -499.943628)
		(size 0.7112)
		(drill 0.3556)
		(layers "F.Cu" "B.Cu")
		(net "SSD0_PWREN_R")
	)
	(segment
		(start 221.13875 -450.1515)
		(end 220.345 -450.1515)
		(width 0.17145)
		(layer "F.Cu")
		(net "SSD0_CLK0_OE_MOS_N")
	)
	(segment
		(start 221.13875 -450.1515)
		(end 221.13875 -449.17995)
		(width 0.17145)
		(layer "F.Cu")
		(net "SSD0_CLK0_OE_MOS_N")
	)
	(segment
		(start 221.13875 -449.17995)
		(end 220.726 -448.7672)
		(width 0.17145)
		(layer "F.Cu")
		(net "SSD0_CLK0_OE_MOS_N")
	)
	(segment
		(start 223.935544 -446.417446)
		(end 223.075754 -446.417446)
		(width 0.17145)
		(layer "F.Cu")
		(net "SSD0_CLK0_OE_MOS_N")
	)
	(segment
		(start 223.075754 -446.417446)
		(end 221.5007 -447.9925)
		(width 0.17145)
		(layer "F.Cu")
		(net "SSD0_CLK0_OE_MOS_N")
	)
	(segment
		(start 224.294446 -446.417446)
		(end 223.935544 -446.417446)
		(width 0.17145)
		(layer "F.Cu")
		(net "SSD0_CLK0_OE_MOS_N")
	)
	(segment
		(start 225.44024 -447.56324)
		(end 224.294446 -446.417446)
		(width 0.17145)
		(layer "F.Cu")
		(net "SSD0_CLK0_OE_MOS_N")
	)
	(segment
		(start 220.345 -450.1515)
		(end 219.7735 -449.58)
		(width 0.17145)
		(layer "F.Cu")
		(net "SSD0_CLK0_OE_MOS_N")
	)
	(segment
		(start 226.3775 -447.56324)
		(end 225.44024 -447.56324)
		(width 0.17145)
		(layer "F.Cu")
		(net "SSD0_CLK0_OE_MOS_N")
	)
	(segment
		(start 221.5007 -447.9925)
		(end 220.726 -447.9925)
		(width 0.17145)
		(layer "F.Cu")
		(net "SSD0_CLK0_OE_MOS_N")
	)
	(segment
		(start 220.726 -448.7672)
		(end 220.726 -447.9925)
		(width 0.17145)
		(layer "F.Cu")
		(net "SSD0_CLK0_OE_MOS_N")
	)
	(via
		(at 223.935544 -446.417446)
		(size 0.7112)
		(drill 0.3556)
		(layers "F.Cu" "B.Cu")
		(net "SSD0_CLK0_OE_MOS_N")
	)
	(segment
		(start 46.076616 -35.438588)
		(end 46.076616 -36.206684)
		(width 0.17145)
		(layer "F.Cu")
		(net "SSD_ACT_DR9_R")
	)
	(segment
		(start 46.361604 -35.1536)
		(end 46.076616 -35.438588)
		(width 0.17145)
		(layer "F.Cu")
		(net "SSD_ACT_DR9_R")
	)
	(segment
		(start 46.076616 -37.453062)
		(end 46.076616 -36.206684)
		(width 0.17145)
		(layer "F.Cu")
		(net "SSD_ACT_DR9_R")
	)
	(segment
		(start 47.65675 -35.402774)
		(end 47.407576 -35.1536)
		(width 0.17145)
		(layer "F.Cu")
		(net "SSD_ACT_DR9_R")
	)
	(segment
		(start 47.65675 -37.6555)
		(end 47.65675 -35.402774)
		(width 0.17145)
		(layer "F.Cu")
		(net "SSD_ACT_DR9_R")
	)
	(segment
		(start 47.407576 -35.1536)
		(end 46.361604 -35.1536)
		(width 0.17145)
		(layer "F.Cu")
		(net "SSD_ACT_DR9_R")
	)
	(via
		(at 46.076616 -36.206684)
		(size 0.7112)
		(drill 0.3556)
		(layers "F.Cu" "B.Cu")
		(net "SSD_ACT_DR9_R")
	)
	(segment
		(start 41.663874 -39.306246)
		(end 41.654476 -39.315644)
		(width 0.17145)
		(layer "F.Cu")
		(net "SSD_ACT_DR9_MOS_N")
	)
	(segment
		(start 41.161716 -39.808404)
		(end 41.654476 -39.315644)
		(width 0.17145)
		(layer "F.Cu")
		(net "SSD_ACT_DR9_MOS_N")
	)
	(segment
		(start 41.507156 -40.693594)
		(end 41.161716 -40.348154)
		(width 0.17145)
		(layer "F.Cu")
		(net "SSD_ACT_DR9_MOS_N")
	)
	(segment
		(start 48.641 -35.7505)
		(end 48.641 -38.989)
		(width 0.17145)
		(layer "F.Cu")
		(net "SSD_ACT_DR9_MOS_N")
	)
	(segment
		(start 41.161716 -40.348154)
		(end 41.161716 -39.808404)
		(width 0.17145)
		(layer "F.Cu")
		(net "SSD_ACT_DR9_MOS_N")
	)
	(segment
		(start 47.652432 -39.306246)
		(end 41.663874 -39.306246)
		(width 0.17145)
		(layer "F.Cu")
		(net "SSD_ACT_DR9_MOS_N")
	)
	(segment
		(start 42.76979 -40.693594)
		(end 41.507156 -40.693594)
		(width 0.17145)
		(layer "F.Cu")
		(net "SSD_ACT_DR9_MOS_N")
	)
	(segment
		(start 48.323754 -39.306246)
		(end 47.652432 -39.306246)
		(width 0.17145)
		(layer "F.Cu")
		(net "SSD_ACT_DR9_MOS_N")
	)
	(segment
		(start 48.641 -38.989)
		(end 48.323754 -39.306246)
		(width 0.17145)
		(layer "F.Cu")
		(net "SSD_ACT_DR9_MOS_N")
	)
	(via
		(at 47.652432 -39.306246)
		(size 0.7112)
		(drill 0.3556)
		(layers "F.Cu" "B.Cu")
		(net "SSD_ACT_DR9_MOS_N")
	)
	(segment
		(start 54.0385 -144.526)
		(end 54.7116 -144.526)
		(width 0.17145)
		(layer "F.Cu")
		(net "SSD_ACT_DR8_R")
	)
	(segment
		(start 53.2765 -142.97025)
		(end 54.9148 -142.97025)
		(width 0.17145)
		(layer "F.Cu")
		(net "SSD_ACT_DR8_R")
	)
	(segment
		(start 54.9148 -142.97025)
		(end 55.1688 -143.22425)
		(width 0.17145)
		(layer "F.Cu")
		(net "SSD_ACT_DR8_R")
	)
	(segment
		(start 54.7116 -144.526)
		(end 55.1688 -144.0688)
		(width 0.17145)
		(layer "F.Cu")
		(net "SSD_ACT_DR8_R")
	)
	(segment
		(start 55.1688 -143.22425)
		(end 55.1688 -143.6878)
		(width 0.17145)
		(layer "F.Cu")
		(net "SSD_ACT_DR8_R")
	)
	(segment
		(start 55.1688 -144.0688)
		(end 55.1688 -143.6878)
		(width 0.17145)
		(layer "F.Cu")
		(net "SSD_ACT_DR8_R")
	)
	(via
		(at 55.1688 -143.6878)
		(size 0.7112)
		(drill 0.3556)
		(layers "F.Cu" "B.Cu")
		(net "SSD_ACT_DR8_R")
	)
	(segment
		(start 47.265336 -142.345664)
		(end 43.36923 -142.345664)
		(width 0.17145)
		(layer "F.Cu")
		(net "SSD_ACT_DR8_MOS_N")
	)
	(segment
		(start 47.625 -141.986)
		(end 47.265336 -142.345664)
		(width 0.17145)
		(layer "F.Cu")
		(net "SSD_ACT_DR8_MOS_N")
	)
	(segment
		(start 43.36923 -142.345664)
		(end 43.19397 -142.520924)
		(width 0.17145)
		(layer "F.Cu")
		(net "SSD_ACT_DR8_MOS_N")
	)
	(segment
		(start 51.3715 -141.986)
		(end 47.625 -141.986)
		(width 0.17145)
		(layer "F.Cu")
		(net "SSD_ACT_DR8_MOS_N")
	)
	(segment
		(start 43.19397 -142.520924)
		(end 43.19397 -142.815056)
		(width 0.17145)
		(layer "F.Cu")
		(net "SSD_ACT_DR8_MOS_N")
	)
	(segment
		(start 42.76979 -143.239236)
		(end 42.76979 -143.693642)
		(width 0.17145)
		(layer "F.Cu")
		(net "SSD_ACT_DR8_MOS_N")
	)
	(segment
		(start 43.19397 -142.815056)
		(end 42.76979 -143.239236)
		(width 0.17145)
		(layer "F.Cu")
		(net "SSD_ACT_DR8_MOS_N")
	)
	(via
		(at 47.625 -141.986)
		(size 0.7112)
		(drill 0.3556)
		(layers "F.Cu" "B.Cu")
		(net "SSD_ACT_DR8_MOS_N")
	)
	(segment
		(start 39.46525 -244.7925)
		(end 41.022778 -244.7925)
		(width 0.17145)
		(layer "F.Cu")
		(net "SSD_ACT_DR7_R")
	)
	(segment
		(start 42.206418 -244.493288)
		(end 41.905936 -244.79377)
		(width 0.17145)
		(layer "F.Cu")
		(net "SSD_ACT_DR7_R")
	)
	(segment
		(start 41.905936 -244.79377)
		(end 41.024048 -244.79377)
		(width 0.17145)
		(layer "F.Cu")
		(net "SSD_ACT_DR7_R")
	)
	(segment
		(start 41.022778 -244.7925)
		(end 41.024048 -244.79377)
		(width 0.17145)
		(layer "F.Cu")
		(net "SSD_ACT_DR7_R")
	)
	(segment
		(start 42.206418 -243.84)
		(end 42.206418 -244.493288)
		(width 0.17145)
		(layer "F.Cu")
		(net "SSD_ACT_DR7_R")
	)
	(via
		(at 41.024048 -244.79377)
		(size 0.7112)
		(drill 0.3556)
		(layers "F.Cu" "B.Cu")
		(net "SSD_ACT_DR7_R")
	)
	(segment
		(start 39.876984 -248.157746)
		(end 40.023796 -248.010934)
		(width 0.17145)
		(layer "F.Cu")
		(net "SSD_ACT_DR7_MOS_N")
	)
	(segment
		(start 38.481 -247.440196)
		(end 38.481 -246.6975)
		(width 0.17145)
		(layer "F.Cu")
		(net "SSD_ACT_DR7_MOS_N")
	)
	(segment
		(start 40.955214 -246.69369)
		(end 42.76979 -246.69369)
		(width 0.17145)
		(layer "F.Cu")
		(net "SSD_ACT_DR7_MOS_N")
	)
	(segment
		(start 39.19855 -248.157746)
		(end 38.481 -247.440196)
		(width 0.17145)
		(layer "F.Cu")
		(net "SSD_ACT_DR7_MOS_N")
	)
	(segment
		(start 40.951404 -246.6975)
		(end 40.955214 -246.69369)
		(width 0.17145)
		(layer "F.Cu")
		(net "SSD_ACT_DR7_MOS_N")
	)
	(segment
		(start 40.023796 -247.625108)
		(end 40.951404 -246.6975)
		(width 0.17145)
		(layer "F.Cu")
		(net "SSD_ACT_DR7_MOS_N")
	)
	(segment
		(start 39.876984 -248.157746)
		(end 39.19855 -248.157746)
		(width 0.17145)
		(layer "F.Cu")
		(net "SSD_ACT_DR7_MOS_N")
	)
	(segment
		(start 40.023796 -248.010934)
		(end 40.023796 -247.625108)
		(width 0.17145)
		(layer "F.Cu")
		(net "SSD_ACT_DR7_MOS_N")
	)
	(via
		(at 40.951404 -246.6975)
		(size 0.7112)
		(drill 0.3556)
		(layers "F.Cu" "B.Cu")
		(net "SSD_ACT_DR7_MOS_N")
	)
	(segment
		(start 47.695866 -343.916)
		(end 46.228 -343.916)
		(width 0.17145)
		(layer "F.Cu")
		(net "SSD_ACT_DR6_R")
	)
	(segment
		(start 47.822866 -345.754452)
		(end 47.822866 -344.043)
		(width 0.17145)
		(layer "F.Cu")
		(net "SSD_ACT_DR6_R")
	)
	(segment
		(start 46.076616 -346.071952)
		(end 46.076616 -344.819732)
		(width 0.17145)
		(layer "F.Cu")
		(net "SSD_ACT_DR6_R")
	)
	(segment
		(start 46.228 -343.916)
		(end 46.076616 -344.067384)
		(width 0.17145)
		(layer "F.Cu")
		(net "SSD_ACT_DR6_R")
	)
	(segment
		(start 46.076616 -344.067384)
		(end 46.076616 -344.819732)
		(width 0.17145)
		(layer "F.Cu")
		(net "SSD_ACT_DR6_R")
	)
	(segment
		(start 47.822866 -344.043)
		(end 47.695866 -343.916)
		(width 0.17145)
		(layer "F.Cu")
		(net "SSD_ACT_DR6_R")
	)
	(via
		(at 46.076616 -344.819732)
		(size 0.7112)
		(drill 0.3556)
		(layers "F.Cu" "B.Cu")
		(net "SSD_ACT_DR6_R")
	)
	(segment
		(start 41.672764 -349.37446)
		(end 41.991788 -349.693484)
		(width 0.17145)
		(layer "F.Cu")
		(net "SSD_ACT_DR6_MOS_N")
	)
	(segment
		(start 48.807116 -346.823284)
		(end 48.807116 -343.849452)
		(width 0.17145)
		(layer "F.Cu")
		(net "SSD_ACT_DR6_MOS_N")
	)
	(segment
		(start 42.9514 -348.3864)
		(end 43.3832 -347.9546)
		(width 0.17145)
		(layer "F.Cu")
		(net "SSD_ACT_DR6_MOS_N")
	)
	(segment
		(start 41.672764 -348.380558)
		(end 41.672764 -349.37446)
		(width 0.17145)
		(layer "F.Cu")
		(net "SSD_ACT_DR6_MOS_N")
	)
	(segment
		(start 43.3832 -347.9546)
		(end 47.6758 -347.9546)
		(width 0.17145)
		(layer "F.Cu")
		(net "SSD_ACT_DR6_MOS_N")
	)
	(segment
		(start 41.672764 -348.380558)
		(end 42.945558 -348.380558)
		(width 0.17145)
		(layer "F.Cu")
		(net "SSD_ACT_DR6_MOS_N")
	)
	(segment
		(start 41.991788 -349.693484)
		(end 42.76979 -349.693484)
		(width 0.17145)
		(layer "F.Cu")
		(net "SSD_ACT_DR6_MOS_N")
	)
	(segment
		(start 42.945558 -348.380558)
		(end 42.9514 -348.3864)
		(width 0.17145)
		(layer "F.Cu")
		(net "SSD_ACT_DR6_MOS_N")
	)
	(segment
		(start 47.6758 -347.9546)
		(end 48.807116 -346.823284)
		(width 0.17145)
		(layer "F.Cu")
		(net "SSD_ACT_DR6_MOS_N")
	)
	(via
		(at 42.9514 -348.3864)
		(size 0.7112)
		(drill 0.3556)
		(layers "F.Cu" "B.Cu")
		(net "SSD_ACT_DR6_MOS_N")
	)
	(segment
		(start 48.505618 -448.91325)
		(end 49.4665 -447.952368)
		(width 0.17145)
		(layer "F.Cu")
		(net "SSD_ACT_DR5_R")
	)
	(segment
		(start 49.4665 -447.952368)
		(end 49.4665 -447.548)
		(width 0.17145)
		(layer "F.Cu")
		(net "SSD_ACT_DR5_R")
	)
	(segment
		(start 49.4665 -446.151)
		(end 49.4665 -447.548)
		(width 0.17145)
		(layer "F.Cu")
		(net "SSD_ACT_DR5_R")
	)
	(segment
		(start 47.776384 -448.91325)
		(end 48.505618 -448.91325)
		(width 0.17145)
		(layer "F.Cu")
		(net "SSD_ACT_DR5_R")
	)
	(via
		(at 49.4665 -447.548)
		(size 0.7112)
		(drill 0.3556)
		(layers "F.Cu" "B.Cu")
		(net "SSD_ACT_DR5_R")
	)
	(segment
		(start 42.042588 -450.463412)
		(end 41.91 -450.596)
		(width 0.17145)
		(layer "F.Cu")
		(net "SSD_ACT_DR5_MOS_N")
	)
	(segment
		(start 43.574716 -450.089016)
		(end 43.574716 -449.03898)
		(width 0.17145)
		(layer "F.Cu")
		(net "SSD_ACT_DR5_MOS_N")
	)
	(segment
		(start 41.3512 -451.1548)
		(end 41.91 -450.596)
		(width 0.17145)
		(layer "F.Cu")
		(net "SSD_ACT_DR5_MOS_N")
	)
	(segment
		(start 41.3512 -452.3486)
		(end 41.3512 -451.1548)
		(width 0.17145)
		(layer "F.Cu")
		(net "SSD_ACT_DR5_MOS_N")
	)
	(segment
		(start 43.20032 -450.463412)
		(end 42.042588 -450.463412)
		(width 0.17145)
		(layer "F.Cu")
		(net "SSD_ACT_DR5_MOS_N")
	)
	(segment
		(start 43.574716 -449.03898)
		(end 44.684696 -447.929)
		(width 0.17145)
		(layer "F.Cu")
		(net "SSD_ACT_DR5_MOS_N")
	)
	(segment
		(start 42.76979 -452.693532)
		(end 41.696132 -452.693532)
		(width 0.17145)
		(layer "F.Cu")
		(net "SSD_ACT_DR5_MOS_N")
	)
	(segment
		(start 43.20032 -450.463412)
		(end 43.574716 -450.089016)
		(width 0.17145)
		(layer "F.Cu")
		(net "SSD_ACT_DR5_MOS_N")
	)
	(segment
		(start 44.684696 -447.929)
		(end 45.871384 -447.929)
		(width 0.17145)
		(layer "F.Cu")
		(net "SSD_ACT_DR5_MOS_N")
	)
	(segment
		(start 41.696132 -452.693532)
		(end 41.3512 -452.3486)
		(width 0.17145)
		(layer "F.Cu")
		(net "SSD_ACT_DR5_MOS_N")
	)
	(via
		(at 41.91 -450.596)
		(size 0.7112)
		(drill 0.3556)
		(layers "F.Cu" "B.Cu")
		(net "SSD_ACT_DR5_MOS_N")
	)
	(segment
		(start 231.3305 -35.197542)
		(end 231.582976 -34.945066)
		(width 0.17145)
		(layer "F.Cu")
		(net "SSD_ACT_DR4_R")
	)
	(segment
		(start 231.3305 -35.870642)
		(end 231.3305 -37.199062)
		(width 0.17145)
		(layer "F.Cu")
		(net "SSD_ACT_DR4_R")
	)
	(segment
		(start 232.82275 -35.325812)
		(end 232.82275 -36.754562)
		(width 0.17145)
		(layer "F.Cu")
		(net "SSD_ACT_DR4_R")
	)
	(segment
		(start 232.442004 -34.945066)
		(end 232.82275 -35.325812)
		(width 0.17145)
		(layer "F.Cu")
		(net "SSD_ACT_DR4_R")
	)
	(segment
		(start 231.3305 -35.870642)
		(end 231.3305 -35.197542)
		(width 0.17145)
		(layer "F.Cu")
		(net "SSD_ACT_DR4_R")
	)
	(segment
		(start 231.582976 -34.945066)
		(end 232.442004 -34.945066)
		(width 0.17145)
		(layer "F.Cu")
		(net "SSD_ACT_DR4_R")
	)
	(via
		(at 231.3305 -35.870642)
		(size 0.7112)
		(drill 0.3556)
		(layers "F.Cu" "B.Cu")
		(net "SSD_ACT_DR4_R")
	)
	(segment
		(start 231.0765 -140.19911)
		(end 231.0765 -138.87069)
		(width 0.17145)
		(layer "F.Cu")
		(net "SSD_ACT_DR3_R")
	)
	(segment
		(start 232.82275 -138.32586)
		(end 232.442004 -137.945114)
		(width 0.17145)
		(layer "F.Cu")
		(net "SSD_ACT_DR3_R")
	)
	(segment
		(start 231.328976 -137.945114)
		(end 231.0765 -138.19759)
		(width 0.17145)
		(layer "F.Cu")
		(net "SSD_ACT_DR3_R")
	)
	(segment
		(start 232.442004 -137.945114)
		(end 231.328976 -137.945114)
		(width 0.17145)
		(layer "F.Cu")
		(net "SSD_ACT_DR3_R")
	)
	(segment
		(start 232.82275 -139.75461)
		(end 232.82275 -138.32586)
		(width 0.17145)
		(layer "F.Cu")
		(net "SSD_ACT_DR3_R")
	)
	(segment
		(start 231.0765 -138.19759)
		(end 231.0765 -138.87069)
		(width 0.17145)
		(layer "F.Cu")
		(net "SSD_ACT_DR3_R")
	)
	(via
		(at 231.0765 -138.87069)
		(size 0.7112)
		(drill 0.3556)
		(layers "F.Cu" "B.Cu")
		(net "SSD_ACT_DR3_R")
	)
	(segment
		(start 233.807 -140.3858)
		(end 232.8164 -141.3764)
		(width 0.17145)
		(layer "F.Cu")
		(net "SSD_ACT_DR3_MOS_N")
	)
	(segment
		(start 227.769674 -142.409672)
		(end 227.835714 -142.343632)
		(width 0.17145)
		(layer "F.Cu")
		(net "SSD_ACT_DR3_MOS_N")
	)
	(segment
		(start 233.807 -137.84961)
		(end 233.807 -140.3858)
		(width 0.17145)
		(layer "F.Cu")
		(net "SSD_ACT_DR3_MOS_N")
	)
	(segment
		(start 230.401368 -142.343632)
		(end 230.755444 -141.989556)
		(width 0.17145)
		(layer "F.Cu")
		(net "SSD_ACT_DR3_MOS_N")
	)
	(segment
		(start 227.769674 -143.693642)
		(end 227.769674 -142.409672)
		(width 0.17145)
		(layer "F.Cu")
		(net "SSD_ACT_DR3_MOS_N")
	)
	(segment
		(start 232.203244 -141.989556)
		(end 232.8164 -141.3764)
		(width 0.17145)
		(layer "F.Cu")
		(net "SSD_ACT_DR3_MOS_N")
	)
	(segment
		(start 227.835714 -142.343632)
		(end 230.401368 -142.343632)
		(width 0.17145)
		(layer "F.Cu")
		(net "SSD_ACT_DR3_MOS_N")
	)
	(segment
		(start 230.755444 -141.989556)
		(end 232.203244 -141.989556)
		(width 0.17145)
		(layer "F.Cu")
		(net "SSD_ACT_DR3_MOS_N")
	)
	(via
		(at 232.8164 -141.3764)
		(size 0.7112)
		(drill 0.3556)
		(layers "F.Cu" "B.Cu")
		(net "SSD_ACT_DR3_MOS_N")
	)
	(segment
		(start 232.82275 -241.325908)
		(end 232.442004 -240.945162)
		(width 0.17145)
		(layer "F.Cu")
		(net "SSD_ACT_DR2_R")
	)
	(segment
		(start 232.82275 -242.754658)
		(end 232.82275 -241.325908)
		(width 0.17145)
		(layer "F.Cu")
		(net "SSD_ACT_DR2_R")
	)
	(segment
		(start 232.442004 -240.945162)
		(end 231.328976 -240.945162)
		(width 0.17145)
		(layer "F.Cu")
		(net "SSD_ACT_DR2_R")
	)
	(segment
		(start 231.0765 -241.197638)
		(end 231.0765 -241.870738)
		(width 0.17145)
		(layer "F.Cu")
		(net "SSD_ACT_DR2_R")
	)
	(segment
		(start 231.0765 -243.199158)
		(end 231.0765 -241.870738)
		(width 0.17145)
		(layer "F.Cu")
		(net "SSD_ACT_DR2_R")
	)
	(segment
		(start 231.328976 -240.945162)
		(end 231.0765 -241.197638)
		(width 0.17145)
		(layer "F.Cu")
		(net "SSD_ACT_DR2_R")
	)
	(via
		(at 231.0765 -241.870738)
		(size 0.7112)
		(drill 0.3556)
		(layers "F.Cu" "B.Cu")
		(net "SSD_ACT_DR2_R")
	)
	(segment
		(start 227.769674 -245.467124)
		(end 227.894896 -245.341902)
		(width 0.17145)
		(layer "F.Cu")
		(net "SSD_ACT_DR2_MOS_N")
	)
	(segment
		(start 227.769674 -246.69369)
		(end 227.769674 -245.467124)
		(width 0.17145)
		(layer "F.Cu")
		(net "SSD_ACT_DR2_MOS_N")
	)
	(segment
		(start 233.244644 -244.910356)
		(end 233.807 -244.348)
		(width 0.17145)
		(layer "F.Cu")
		(net "SSD_ACT_DR2_MOS_N")
	)
	(segment
		(start 230.323898 -245.341902)
		(end 230.755444 -244.910356)
		(width 0.17145)
		(layer "F.Cu")
		(net "SSD_ACT_DR2_MOS_N")
	)
	(segment
		(start 232.320084 -244.910356)
		(end 233.244644 -244.910356)
		(width 0.17145)
		(layer "F.Cu")
		(net "SSD_ACT_DR2_MOS_N")
	)
	(segment
		(start 233.807 -244.348)
		(end 233.807 -240.849658)
		(width 0.17145)
		(layer "F.Cu")
		(net "SSD_ACT_DR2_MOS_N")
	)
	(segment
		(start 230.755444 -244.910356)
		(end 232.320084 -244.910356)
		(width 0.17145)
		(layer "F.Cu")
		(net "SSD_ACT_DR2_MOS_N")
	)
	(segment
		(start 227.894896 -245.341902)
		(end 230.323898 -245.341902)
		(width 0.17145)
		(layer "F.Cu")
		(net "SSD_ACT_DR2_MOS_N")
	)
	(via
		(at 232.320084 -244.910356)
		(size 0.7112)
		(drill 0.3556)
		(layers "F.Cu" "B.Cu")
		(net "SSD_ACT_DR2_MOS_N")
	)
	(segment
		(start 17.988026 -58.628788)
		(end 19.4945 -58.628788)
		(width 0.17145)
		(layer "F.Cu")
		(net "SSD_ACT_DR14_R")
	)
	(segment
		(start 17.317212 -58.628788)
		(end 17.11325 -58.83275)
		(width 0.17145)
		(layer "F.Cu")
		(net "SSD_ACT_DR14_R")
	)
	(segment
		(start 17.988026 -58.628788)
		(end 17.317212 -58.628788)
		(width 0.17145)
		(layer "F.Cu")
		(net "SSD_ACT_DR14_R")
	)
	(segment
		(start 17.11325 -58.83275)
		(end 17.11325 -60.37961)
		(width 0.17145)
		(layer "F.Cu")
		(net "SSD_ACT_DR14_R")
	)
	(via
		(at 17.988026 -58.628788)
		(size 0.7112)
		(drill 0.3556)
		(layers "F.Cu" "B.Cu")
		(net "SSD_ACT_DR14_R")
	)
	(segment
		(start 15.1765 -54.823106)
		(end 15.1765 -56.76011)
		(width 0.17145)
		(layer "F.Cu")
		(net "SSD_ACT_DR14_MOS_N")
	)
	(segment
		(start 15.204186 -52.049934)
		(end 14.755114 -52.049934)
		(width 0.17145)
		(layer "F.Cu")
		(net "SSD_ACT_DR14_MOS_N")
	)
	(segment
		(start 15.204186 -52.049934)
		(end 16.29156 -52.049934)
		(width 0.17145)
		(layer "F.Cu")
		(net "SSD_ACT_DR14_MOS_N")
	)
	(segment
		(start 15.1765 -56.76011)
		(end 15.1765 -58.0771)
		(width 0.17145)
		(layer "F.Cu")
		(net "SSD_ACT_DR14_MOS_N")
	)
	(segment
		(start 14.483334 -52.321714)
		(end 14.483334 -54.12994)
		(width 0.17145)
		(layer "F.Cu")
		(net "SSD_ACT_DR14_MOS_N")
	)
	(segment
		(start 14.483334 -54.12994)
		(end 15.1765 -54.823106)
		(width 0.17145)
		(layer "F.Cu")
		(net "SSD_ACT_DR14_MOS_N")
	)
	(segment
		(start 16.29156 -52.049934)
		(end 16.735298 -52.493672)
		(width 0.17145)
		(layer "F.Cu")
		(net "SSD_ACT_DR14_MOS_N")
	)
	(segment
		(start 15.1765 -58.0771)
		(end 16.129 -59.0296)
		(width 0.17145)
		(layer "F.Cu")
		(net "SSD_ACT_DR14_MOS_N")
	)
	(segment
		(start 16.129 -59.0296)
		(end 16.129 -62.28461)
		(width 0.17145)
		(layer "F.Cu")
		(net "SSD_ACT_DR14_MOS_N")
	)
	(segment
		(start 16.735298 -52.493672)
		(end 17.76984 -52.493672)
		(width 0.17145)
		(layer "F.Cu")
		(net "SSD_ACT_DR14_MOS_N")
	)
	(segment
		(start 14.755114 -52.049934)
		(end 14.483334 -52.321714)
		(width 0.17145)
		(layer "F.Cu")
		(net "SSD_ACT_DR14_MOS_N")
	)
	(via
		(at 15.1765 -56.76011)
		(size 0.7112)
		(drill 0.3556)
		(layers "F.Cu" "B.Cu")
		(net "SSD_ACT_DR14_MOS_N")
	)
	(segment
		(start 17.3355 -161.628836)
		(end 17.11325 -161.851086)
		(width 0.17145)
		(layer "F.Cu")
		(net "SSD_ACT_DR13_R")
	)
	(segment
		(start 17.11325 -161.851086)
		(end 17.11325 -163.379658)
		(width 0.17145)
		(layer "F.Cu")
		(net "SSD_ACT_DR13_R")
	)
	(segment
		(start 17.937734 -161.628836)
		(end 17.3355 -161.628836)
		(width 0.17145)
		(layer "F.Cu")
		(net "SSD_ACT_DR13_R")
	)
	(segment
		(start 17.937734 -161.628836)
		(end 19.4945 -161.628836)
		(width 0.17145)
		(layer "F.Cu")
		(net "SSD_ACT_DR13_R")
	)
	(via
		(at 17.937734 -161.628836)
		(size 0.7112)
		(drill 0.3556)
		(layers "F.Cu" "B.Cu")
		(net "SSD_ACT_DR13_R")
	)
	(segment
		(start 16.160242 -156.862526)
		(end 15.626842 -157.395926)
		(width 0.17145)
		(layer "F.Cu")
		(net "SSD_ACT_DR13_MOS_N")
	)
	(segment
		(start 16.129 -162.306)
		(end 15.626842 -161.803842)
		(width 0.17145)
		(layer "F.Cu")
		(net "SSD_ACT_DR13_MOS_N")
	)
	(segment
		(start 16.939768 -155.49372)
		(end 17.76984 -155.49372)
		(width 0.17145)
		(layer "F.Cu")
		(net "SSD_ACT_DR13_MOS_N")
	)
	(segment
		(start 16.160242 -156.11348)
		(end 16.160242 -156.862526)
		(width 0.17145)
		(layer "F.Cu")
		(net "SSD_ACT_DR13_MOS_N")
	)
	(segment
		(start 15.626842 -161.803842)
		(end 15.626842 -160.114996)
		(width 0.17145)
		(layer "F.Cu")
		(net "SSD_ACT_DR13_MOS_N")
	)
	(segment
		(start 15.626842 -157.395926)
		(end 15.626842 -160.114996)
		(width 0.17145)
		(layer "F.Cu")
		(net "SSD_ACT_DR13_MOS_N")
	)
	(segment
		(start 16.160242 -156.11348)
		(end 16.320008 -156.11348)
		(width 0.17145)
		(layer "F.Cu")
		(net "SSD_ACT_DR13_MOS_N")
	)
	(segment
		(start 16.129 -165.284658)
		(end 16.129 -162.306)
		(width 0.17145)
		(layer "F.Cu")
		(net "SSD_ACT_DR13_MOS_N")
	)
	(segment
		(start 16.320008 -156.11348)
		(end 16.939768 -155.49372)
		(width 0.17145)
		(layer "F.Cu")
		(net "SSD_ACT_DR13_MOS_N")
	)
	(via
		(at 15.626842 -160.114996)
		(size 0.7112)
		(drill 0.3556)
		(layers "F.Cu" "B.Cu")
		(net "SSD_ACT_DR13_MOS_N")
	)
	(segment
		(start 19.7485 -264.37463)
		(end 18.14957 -264.37463)
		(width 0.17145)
		(layer "F.Cu")
		(net "SSD_ACT_DR12_R")
	)
	(segment
		(start 18.00225 -264.52195)
		(end 18.00225 -265.176)
		(width 0.17145)
		(layer "F.Cu")
		(net "SSD_ACT_DR12_R")
	)
	(segment
		(start 18.00225 -266.8905)
		(end 18.00225 -265.176)
		(width 0.17145)
		(layer "F.Cu")
		(net "SSD_ACT_DR12_R")
	)
	(segment
		(start 18.14957 -264.37463)
		(end 18.00225 -264.52195)
		(width 0.17145)
		(layer "F.Cu")
		(net "SSD_ACT_DR12_R")
	)
	(via
		(at 18.00225 -265.176)
		(size 0.7112)
		(drill 0.3556)
		(layers "F.Cu" "B.Cu")
		(net "SSD_ACT_DR12_R")
	)
	(segment
		(start 17.00403 -257.158744)
		(end 17.00403 -257.000248)
		(width 0.17145)
		(layer "F.Cu")
		(net "SSD_ACT_DR12_MOS_N")
	)
	(segment
		(start 16.44142 -256.437638)
		(end 15.81658 -256.437638)
		(width 0.17145)
		(layer "F.Cu")
		(net "SSD_ACT_DR12_MOS_N")
	)
	(segment
		(start 17.018 -266.573)
		(end 16.383 -265.938)
		(width 0.17145)
		(layer "F.Cu")
		(net "SSD_ACT_DR12_MOS_N")
	)
	(segment
		(start 17.76984 -257.924554)
		(end 17.00403 -257.158744)
		(width 0.17145)
		(layer "F.Cu")
		(net "SSD_ACT_DR12_MOS_N")
	)
	(segment
		(start 17.018 -268.7955)
		(end 17.018 -266.573)
		(width 0.17145)
		(layer "F.Cu")
		(net "SSD_ACT_DR12_MOS_N")
	)
	(segment
		(start 17.00403 -257.000248)
		(end 16.44142 -256.437638)
		(width 0.17145)
		(layer "F.Cu")
		(net "SSD_ACT_DR12_MOS_N")
	)
	(segment
		(start 15.81658 -256.437638)
		(end 15.489428 -256.76479)
		(width 0.17145)
		(layer "F.Cu")
		(net "SSD_ACT_DR12_MOS_N")
	)
	(segment
		(start 15.489428 -262.631428)
		(end 16.383 -263.525)
		(width 0.17145)
		(layer "F.Cu")
		(net "SSD_ACT_DR12_MOS_N")
	)
	(segment
		(start 15.489428 -256.76479)
		(end 15.489428 -262.631428)
		(width 0.17145)
		(layer "F.Cu")
		(net "SSD_ACT_DR12_MOS_N")
	)
	(segment
		(start 16.383 -265.938)
		(end 16.383 -263.525)
		(width 0.17145)
		(layer "F.Cu")
		(net "SSD_ACT_DR12_MOS_N")
	)
	(segment
		(start 17.76984 -258.493514)
		(end 17.76984 -257.924554)
		(width 0.17145)
		(layer "F.Cu")
		(net "SSD_ACT_DR12_MOS_N")
	)
	(via
		(at 16.383 -263.525)
		(size 0.7112)
		(drill 0.3556)
		(layers "F.Cu" "B.Cu")
		(net "SSD_ACT_DR12_MOS_N")
	)
	(segment
		(start 17.849342 -367.628678)
		(end 19.4945 -367.628678)
		(width 0.17145)
		(layer "F.Cu")
		(net "SSD_ACT_DR11_R")
	)
	(segment
		(start 17.11325 -367.89995)
		(end 17.384522 -367.628678)
		(width 0.17145)
		(layer "F.Cu")
		(net "SSD_ACT_DR11_R")
	)
	(segment
		(start 17.384522 -367.628678)
		(end 17.849342 -367.628678)
		(width 0.17145)
		(layer "F.Cu")
		(net "SSD_ACT_DR11_R")
	)
	(segment
		(start 17.11325 -369.3795)
		(end 17.11325 -367.89995)
		(width 0.17145)
		(layer "F.Cu")
		(net "SSD_ACT_DR11_R")
	)
	(via
		(at 17.849342 -367.628678)
		(size 0.7112)
		(drill 0.3556)
		(layers "F.Cu" "B.Cu")
		(net "SSD_ACT_DR11_R")
	)
	(segment
		(start 15.748 -367.665)
		(end 16.129 -368.046)
		(width 0.17145)
		(layer "F.Cu")
		(net "SSD_ACT_DR11_MOS_N")
	)
	(segment
		(start 15.208758 -360.199686)
		(end 15.208758 -363.829854)
		(width 0.17145)
		(layer "F.Cu")
		(net "SSD_ACT_DR11_MOS_N")
	)
	(segment
		(start 17.16786 -360.14914)
		(end 17.16786 -359.957116)
		(width 0.17145)
		(layer "F.Cu")
		(net "SSD_ACT_DR11_MOS_N")
	)
	(segment
		(start 16.638778 -359.428034)
		(end 15.98041 -359.428034)
		(width 0.17145)
		(layer "F.Cu")
		(net "SSD_ACT_DR11_MOS_N")
	)
	(segment
		(start 15.748 -364.369096)
		(end 15.748 -366.2172)
		(width 0.17145)
		(layer "F.Cu")
		(net "SSD_ACT_DR11_MOS_N")
	)
	(segment
		(start 15.748 -366.2172)
		(end 15.748 -367.665)
		(width 0.17145)
		(layer "F.Cu")
		(net "SSD_ACT_DR11_MOS_N")
	)
	(segment
		(start 17.541494 -360.152696)
		(end 17.76984 -360.381042)
		(width 0.17145)
		(layer "F.Cu")
		(net "SSD_ACT_DR11_MOS_N")
	)
	(segment
		(start 16.129 -368.046)
		(end 16.129 -371.2845)
		(width 0.17145)
		(layer "F.Cu")
		(net "SSD_ACT_DR11_MOS_N")
	)
	(segment
		(start 17.76984 -360.381042)
		(end 17.76984 -361.493562)
		(width 0.17145)
		(layer "F.Cu")
		(net "SSD_ACT_DR11_MOS_N")
	)
	(segment
		(start 17.16786 -360.14914)
		(end 17.541494 -360.152696)
		(width 0.17145)
		(layer "F.Cu")
		(net "SSD_ACT_DR11_MOS_N")
	)
	(segment
		(start 15.98041 -359.428034)
		(end 15.208758 -360.199686)
		(width 0.17145)
		(layer "F.Cu")
		(net "SSD_ACT_DR11_MOS_N")
	)
	(segment
		(start 17.16786 -359.957116)
		(end 16.638778 -359.428034)
		(width 0.17145)
		(layer "F.Cu")
		(net "SSD_ACT_DR11_MOS_N")
	)
	(segment
		(start 15.208758 -363.829854)
		(end 15.748 -364.369096)
		(width 0.17145)
		(layer "F.Cu")
		(net "SSD_ACT_DR11_MOS_N")
	)
	(via
		(at 15.748 -366.2172)
		(size 0.7112)
		(drill 0.3556)
		(layers "F.Cu" "B.Cu")
		(net "SSD_ACT_DR11_MOS_N")
	)
	(segment
		(start 26.7589 -468.9602)
		(end 26.7589 -467.3346)
		(width 0.17145)
		(layer "F.Cu")
		(net "SSD_ACT_DR10_R")
	)
	(segment
		(start 26.7589 -469.67775)
		(end 26.71445 -469.7222)
		(width 0.17145)
		(layer "F.Cu")
		(net "SSD_ACT_DR10_R")
	)
	(segment
		(start 26.71445 -469.7222)
		(end 26.71445 -470.7001)
		(width 0.17145)
		(layer "F.Cu")
		(net "SSD_ACT_DR10_R")
	)
	(segment
		(start 26.7589 -468.9602)
		(end 26.7589 -469.67775)
		(width 0.17145)
		(layer "F.Cu")
		(net "SSD_ACT_DR10_R")
	)
	(via
		(at 26.7589 -468.9602)
		(size 0.7112)
		(drill 0.3556)
		(layers "F.Cu" "B.Cu")
		(net "SSD_ACT_DR10_R")
	)
	(segment
		(start 17.32915 -463.722974)
		(end 17.76984 -464.163664)
		(width 0.17145)
		(layer "F.Cu")
		(net "SSD_ACT_DR10_MOS_N")
	)
	(segment
		(start 17.32915 -463.126074)
		(end 16.756126 -463.126074)
		(width 0.17145)
		(layer "F.Cu")
		(net "SSD_ACT_DR10_MOS_N")
	)
	(segment
		(start 15.5575 -464.3247)
		(end 15.9766 -463.9056)
		(width 0.17145)
		(layer "F.Cu")
		(net "SSD_ACT_DR10_MOS_N")
	)
	(segment
		(start 23.640796 -475.259908)
		(end 17.82064 -475.259908)
		(width 0.17145)
		(layer "F.Cu")
		(net "SSD_ACT_DR10_MOS_N")
	)
	(segment
		(start 15.5575 -472.996768)
		(end 15.5575 -464.3247)
		(width 0.17145)
		(layer "F.Cu")
		(net "SSD_ACT_DR10_MOS_N")
	)
	(segment
		(start 25.7302 -473.170504)
		(end 23.640796 -475.259908)
		(width 0.17145)
		(layer "F.Cu")
		(net "SSD_ACT_DR10_MOS_N")
	)
	(segment
		(start 16.756126 -463.126074)
		(end 15.9766 -463.9056)
		(width 0.17145)
		(layer "F.Cu")
		(net "SSD_ACT_DR10_MOS_N")
	)
	(segment
		(start 17.32915 -463.126074)
		(end 17.32915 -463.722974)
		(width 0.17145)
		(layer "F.Cu")
		(net "SSD_ACT_DR10_MOS_N")
	)
	(segment
		(start 25.7302 -472.6051)
		(end 25.7302 -473.170504)
		(width 0.17145)
		(layer "F.Cu")
		(net "SSD_ACT_DR10_MOS_N")
	)
	(segment
		(start 17.76984 -464.163664)
		(end 17.76984 -464.49361)
		(width 0.17145)
		(layer "F.Cu")
		(net "SSD_ACT_DR10_MOS_N")
	)
	(segment
		(start 17.82064 -475.259908)
		(end 15.5575 -472.996768)
		(width 0.17145)
		(layer "F.Cu")
		(net "SSD_ACT_DR10_MOS_N")
	)
	(via
		(at 15.9766 -463.9056)
		(size 0.7112)
		(drill 0.3556)
		(layers "F.Cu" "B.Cu")
		(net "SSD_ACT_DR10_MOS_N")
	)
	(segment
		(start 232.442004 -343.944956)
		(end 231.328976 -343.944956)
		(width 0.17145)
		(layer "F.Cu")
		(net "SSD_ACT_DR1_R")
	)
	(segment
		(start 231.0765 -346.198952)
		(end 231.0765 -344.870532)
		(width 0.17145)
		(layer "F.Cu")
		(net "SSD_ACT_DR1_R")
	)
	(segment
		(start 231.0765 -344.197432)
		(end 231.0765 -344.870532)
		(width 0.17145)
		(layer "F.Cu")
		(net "SSD_ACT_DR1_R")
	)
	(segment
		(start 231.328976 -343.944956)
		(end 231.0765 -344.197432)
		(width 0.17145)
		(layer "F.Cu")
		(net "SSD_ACT_DR1_R")
	)
	(segment
		(start 232.82275 -345.754452)
		(end 232.82275 -344.325702)
		(width 0.17145)
		(layer "F.Cu")
		(net "SSD_ACT_DR1_R")
	)
	(segment
		(start 232.82275 -344.325702)
		(end 232.442004 -343.944956)
		(width 0.17145)
		(layer "F.Cu")
		(net "SSD_ACT_DR1_R")
	)
	(via
		(at 231.0765 -344.870532)
		(size 0.7112)
		(drill 0.3556)
		(layers "F.Cu" "B.Cu")
		(net "SSD_ACT_DR1_R")
	)
	(segment
		(start 227.769674 -348.34957)
		(end 227.79609 -348.323154)
		(width 0.17145)
		(layer "F.Cu")
		(net "SSD_ACT_DR1_MOS_N")
	)
	(segment
		(start 228.129846 -347.989398)
		(end 227.79609 -348.323154)
		(width 0.17145)
		(layer "F.Cu")
		(net "SSD_ACT_DR1_MOS_N")
	)
	(segment
		(start 233.807 -346.9132)
		(end 232.730802 -347.989398)
		(width 0.17145)
		(layer "F.Cu")
		(net "SSD_ACT_DR1_MOS_N")
	)
	(segment
		(start 233.807 -343.849452)
		(end 233.807 -346.9132)
		(width 0.17145)
		(layer "F.Cu")
		(net "SSD_ACT_DR1_MOS_N")
	)
	(segment
		(start 232.419398 -347.989398)
		(end 228.129846 -347.989398)
		(width 0.17145)
		(layer "F.Cu")
		(net "SSD_ACT_DR1_MOS_N")
	)
	(segment
		(start 232.730802 -347.989398)
		(end 232.419398 -347.989398)
		(width 0.17145)
		(layer "F.Cu")
		(net "SSD_ACT_DR1_MOS_N")
	)
	(segment
		(start 227.769674 -349.693484)
		(end 227.769674 -348.34957)
		(width 0.17145)
		(layer "F.Cu")
		(net "SSD_ACT_DR1_MOS_N")
	)
	(via
		(at 232.419398 -347.989398)
		(size 0.7112)
		(drill 0.3556)
		(layers "F.Cu" "B.Cu")
		(net "SSD_ACT_DR1_MOS_N")
	)
	(segment
		(start 231.39273 -446.945004)
		(end 232.442004 -446.945004)
		(width 0.17145)
		(layer "F.Cu")
		(net "SSD_ACT_DR0_R")
	)
	(segment
		(start 232.442004 -446.945004)
		(end 232.82275 -447.32575)
		(width 0.17145)
		(layer "F.Cu")
		(net "SSD_ACT_DR0_R")
	)
	(segment
		(start 232.82275 -447.32575)
		(end 232.82275 -448.7545)
		(width 0.17145)
		(layer "F.Cu")
		(net "SSD_ACT_DR0_R")
	)
	(segment
		(start 231.0765 -447.261234)
		(end 231.39273 -446.945004)
		(width 0.17145)
		(layer "F.Cu")
		(net "SSD_ACT_DR0_R")
	)
	(segment
		(start 231.0765 -449.199)
		(end 231.0765 -447.87058)
		(width 0.17145)
		(layer "F.Cu")
		(net "SSD_ACT_DR0_R")
	)
	(segment
		(start 231.0765 -447.87058)
		(end 231.0765 -447.261234)
		(width 0.17145)
		(layer "F.Cu")
		(net "SSD_ACT_DR0_R")
	)
	(via
		(at 231.0765 -447.87058)
		(size 0.7112)
		(drill 0.3556)
		(layers "F.Cu" "B.Cu")
		(net "SSD_ACT_DR0_R")
	)
	(segment
		(start 233.807 -446.8495)
		(end 233.807 -449.4276)
		(width 0.17145)
		(layer "F.Cu")
		(net "SSD_ACT_DR0_MOS_N")
	)
	(segment
		(start 227.922836 -451.285864)
		(end 227.8761 -451.3326)
		(width 0.17145)
		(layer "F.Cu")
		(net "SSD_ACT_DR0_MOS_N")
	)
	(segment
		(start 231.948736 -451.285864)
		(end 227.922836 -451.285864)
		(width 0.17145)
		(layer "F.Cu")
		(net "SSD_ACT_DR0_MOS_N")
	)
	(segment
		(start 232.6894 -450.5452)
		(end 231.948736 -451.285864)
		(width 0.17145)
		(layer "F.Cu")
		(net "SSD_ACT_DR0_MOS_N")
	)
	(segment
		(start 227.769674 -452.693532)
		(end 227.769674 -452.058278)
		(width 0.17145)
		(layer "F.Cu")
		(net "SSD_ACT_DR0_MOS_N")
	)
	(segment
		(start 227.769674 -452.058278)
		(end 227.8761 -451.951852)
		(width 0.17145)
		(layer "F.Cu")
		(net "SSD_ACT_DR0_MOS_N")
	)
	(segment
		(start 227.8761 -451.951852)
		(end 227.8761 -451.3326)
		(width 0.17145)
		(layer "F.Cu")
		(net "SSD_ACT_DR0_MOS_N")
	)
	(segment
		(start 233.807 -449.4276)
		(end 232.6894 -450.5452)
		(width 0.17145)
		(layer "F.Cu")
		(net "SSD_ACT_DR0_MOS_N")
	)
	(via
		(at 232.6894 -450.5452)
		(size 0.7112)
		(drill 0.3556)
		(layers "F.Cu" "B.Cu")
		(net "SSD_ACT_DR0_MOS_N")
	)
	(segment
		(start 32.3215 -94.9706)
		(end 32.3215 -95.9612)
		(width 0.508)
		(layer "F.Cu")
		(net "P12V_MOST9_GATE_D")
	)
	(segment
		(start 34.843466 -96.4438)
		(end 35.306 -95.981266)
		(width 0.508)
		(layer "F.Cu")
		(net "P12V_MOST9_GATE_D")
	)
	(segment
		(start 35.306 -95.981266)
		(end 35.306 -95.3262)
		(width 0.508)
		(layer "F.Cu")
		(net "P12V_MOST9_GATE_D")
	)
	(segment
		(start 33.8074 -96.4438)
		(end 34.843466 -96.4438)
		(width 0.508)
		(layer "F.Cu")
		(net "P12V_MOST9_GATE_D")
	)
	(segment
		(start 32.3215 -95.9612)
		(end 32.8041 -96.4438)
		(width 0.508)
		(layer "F.Cu")
		(net "P12V_MOST9_GATE_D")
	)
	(segment
		(start 32.8041 -96.4438)
		(end 33.8074 -96.4438)
		(width 0.508)
		(layer "F.Cu")
		(net "P12V_MOST9_GATE_D")
	)
	(via
		(at 33.8074 -96.4438)
		(size 0.7112)
		(drill 0.3556)
		(layers "F.Cu" "B.Cu")
		(net "P12V_MOST9_GATE_D")
	)
	(segment
		(start 28.8671 -94.9706)
		(end 28.8671 -96.209866)
		(width 0.17145)
		(layer "F.Cu")
		(net "P12V_MOST9_GATE")
	)
	(segment
		(start 28.8671 -94.9706)
		(end 27.3685 -94.9706)
		(width 0.17145)
		(layer "F.Cu")
		(net "P12V_MOST9_GATE")
	)
	(segment
		(start 30.161484 -96.209866)
		(end 30.4165 -95.95485)
		(width 0.17145)
		(layer "F.Cu")
		(net "P12V_MOST9_GATE")
	)
	(segment
		(start 28.8671 -96.209866)
		(end 30.161484 -96.209866)
		(width 0.17145)
		(layer "F.Cu")
		(net "P12V_MOST9_GATE")
	)
	(via
		(at 28.8671 -96.209866)
		(size 0.7112)
		(drill 0.3556)
		(layers "F.Cu" "B.Cu")
		(net "P12V_MOST9_GATE")
	)
	(segment
		(start 32.3215 -198.749158)
		(end 32.3215 -197.9676)
		(width 0.508)
		(layer "F.Cu")
		(net "P12V_MOST8_GATE_D")
	)
	(segment
		(start 33.7566 -199.1106)
		(end 34.4932 -199.1106)
		(width 0.508)
		(layer "F.Cu")
		(net "P12V_MOST8_GATE_D")
	)
	(segment
		(start 34.4932 -199.1106)
		(end 35.3314 -198.2724)
		(width 0.508)
		(layer "F.Cu")
		(net "P12V_MOST8_GATE_D")
	)
	(segment
		(start 33.7566 -199.1106)
		(end 32.682942 -199.1106)
		(width 0.508)
		(layer "F.Cu")
		(net "P12V_MOST8_GATE_D")
	)
	(segment
		(start 32.682942 -199.1106)
		(end 32.3215 -198.749158)
		(width 0.508)
		(layer "F.Cu")
		(net "P12V_MOST8_GATE_D")
	)
	(via
		(at 33.7566 -199.1106)
		(size 0.7112)
		(drill 0.3556)
		(layers "F.Cu" "B.Cu")
		(net "P12V_MOST8_GATE_D")
	)
	(segment
		(start 30.161484 -199.206866)
		(end 30.4165 -198.95185)
		(width 0.17145)
		(layer "F.Cu")
		(net "P12V_MOST8_GATE")
	)
	(segment
		(start 28.8671 -197.9676)
		(end 27.3685 -197.9676)
		(width 0.17145)
		(layer "F.Cu")
		(net "P12V_MOST8_GATE")
	)
	(segment
		(start 28.8671 -199.206866)
		(end 30.161484 -199.206866)
		(width 0.17145)
		(layer "F.Cu")
		(net "P12V_MOST8_GATE")
	)
	(segment
		(start 28.8671 -197.9676)
		(end 28.8671 -199.206866)
		(width 0.17145)
		(layer "F.Cu")
		(net "P12V_MOST8_GATE")
	)
	(via
		(at 28.8671 -199.206866)
		(size 0.7112)
		(drill 0.3556)
		(layers "F.Cu" "B.Cu")
		(net "P12V_MOST8_GATE")
	)
	(segment
		(start 32.8803 -302.6918)
		(end 33.8074 -302.6918)
		(width 0.508)
		(layer "F.Cu")
		(net "P12V_MOST7_GATE_D")
	)
	(segment
		(start 34.9758 -302.2092)
		(end 34.9758 -301.2186)
		(width 0.508)
		(layer "F.Cu")
		(net "P12V_MOST7_GATE_D")
	)
	(segment
		(start 34.4932 -302.6918)
		(end 34.9758 -302.2092)
		(width 0.508)
		(layer "F.Cu")
		(net "P12V_MOST7_GATE_D")
	)
	(segment
		(start 33.8074 -302.6918)
		(end 34.4932 -302.6918)
		(width 0.508)
		(layer "F.Cu")
		(net "P12V_MOST7_GATE_D")
	)
	(segment
		(start 32.3215 -302.133)
		(end 32.8803 -302.6918)
		(width 0.508)
		(layer "F.Cu")
		(net "P12V_MOST7_GATE_D")
	)
	(segment
		(start 32.3215 -300.9646)
		(end 32.3215 -302.133)
		(width 0.508)
		(layer "F.Cu")
		(net "P12V_MOST7_GATE_D")
	)
	(via
		(at 33.8074 -302.6918)
		(size 0.7112)
		(drill 0.3556)
		(layers "F.Cu" "B.Cu")
		(net "P12V_MOST7_GATE_D")
	)
	(segment
		(start 28.8671 -300.9646)
		(end 27.3685 -300.9646)
		(width 0.17145)
		(layer "F.Cu")
		(net "P12V_MOST7_GATE")
	)
	(segment
		(start 28.8671 -300.9646)
		(end 28.8671 -302.203866)
		(width 0.17145)
		(layer "F.Cu")
		(net "P12V_MOST7_GATE")
	)
	(segment
		(start 28.8671 -302.203866)
		(end 30.161484 -302.203866)
		(width 0.17145)
		(layer "F.Cu")
		(net "P12V_MOST7_GATE")
	)
	(segment
		(start 30.161484 -302.203866)
		(end 30.4165 -301.94885)
		(width 0.17145)
		(layer "F.Cu")
		(net "P12V_MOST7_GATE")
	)
	(via
		(at 28.8671 -302.203866)
		(size 0.7112)
		(drill 0.3556)
		(layers "F.Cu" "B.Cu")
		(net "P12V_MOST7_GATE")
	)
	(segment
		(start 30.915864 -402.53285)
		(end 31.252668 -402.196046)
		(width 0.508)
		(layer "F.Cu")
		(net "P12V_MOST6_GATE_D")
	)
	(segment
		(start 32.95015 -401.60575)
		(end 31.842964 -401.60575)
		(width 0.508)
		(layer "F.Cu")
		(net "P12V_MOST6_GATE_D")
	)
	(segment
		(start 31.842964 -401.60575)
		(end 31.252668 -402.196046)
		(width 0.508)
		(layer "F.Cu")
		(net "P12V_MOST6_GATE_D")
	)
	(segment
		(start 29.62275 -402.53285)
		(end 30.915864 -402.53285)
		(width 0.508)
		(layer "F.Cu")
		(net "P12V_MOST6_GATE_D")
	)
	(via
		(at 31.252668 -402.196046)
		(size 0.7112)
		(drill 0.3556)
		(layers "F.Cu" "B.Cu")
		(net "P12V_MOST6_GATE_D")
	)
	(segment
		(start 27.462734 -403.772116)
		(end 27.71775 -403.5171)
		(width 0.17145)
		(layer "F.Cu")
		(net "P12V_MOST6_GATE")
	)
	(segment
		(start 26.16835 -402.53285)
		(end 24.66975 -402.53285)
		(width 0.17145)
		(layer "F.Cu")
		(net "P12V_MOST6_GATE")
	)
	(segment
		(start 26.16835 -402.53285)
		(end 26.16835 -403.772116)
		(width 0.17145)
		(layer "F.Cu")
		(net "P12V_MOST6_GATE")
	)
	(segment
		(start 26.16835 -403.772116)
		(end 27.462734 -403.772116)
		(width 0.17145)
		(layer "F.Cu")
		(net "P12V_MOST6_GATE")
	)
	(via
		(at 26.16835 -403.772116)
		(size 0.7112)
		(drill 0.3556)
		(layers "F.Cu" "B.Cu")
		(net "P12V_MOST6_GATE")
	)
	(segment
		(start 22.1488 -497.9416)
		(end 21.3868 -497.9416)
		(width 0.508)
		(layer "F.Cu")
		(net "P12V_MOST5_GATE_D")
	)
	(segment
		(start 21.3868 -497.9416)
		(end 20.4724 -498.856)
		(width 0.508)
		(layer "F.Cu")
		(net "P12V_MOST5_GATE_D")
	)
	(segment
		(start 20.1676 -499.1608)
		(end 20.4724 -498.856)
		(width 0.508)
		(layer "F.Cu")
		(net "P12V_MOST5_GATE_D")
	)
	(segment
		(start 18.9103 -499.1608)
		(end 20.1676 -499.1608)
		(width 0.508)
		(layer "F.Cu")
		(net "P12V_MOST5_GATE_D")
	)
	(via
		(at 20.4724 -498.856)
		(size 0.7112)
		(drill 0.3556)
		(layers "F.Cu" "B.Cu")
		(net "P12V_MOST5_GATE_D")
	)
	(segment
		(start 14.0589 -499.1862)
		(end 15.5067 -499.1862)
		(width 0.17145)
		(layer "F.Cu")
		(net "P12V_MOST5_GATE")
	)
	(segment
		(start 15.3924 -500.4562)
		(end 15.9004 -500.4562)
		(width 0.17145)
		(layer "F.Cu")
		(net "P12V_MOST5_GATE")
	)
	(segment
		(start 15.9004 -500.4562)
		(end 16.21155 -500.14505)
		(width 0.17145)
		(layer "F.Cu")
		(net "P12V_MOST5_GATE")
	)
	(segment
		(start 16.21155 -500.14505)
		(end 17.0053 -500.14505)
		(width 0.17145)
		(layer "F.Cu")
		(net "P12V_MOST5_GATE")
	)
	(segment
		(start 15.5067 -499.5672)
		(end 15.5067 -499.1862)
		(width 0.17145)
		(layer "F.Cu")
		(net "P12V_MOST5_GATE")
	)
	(segment
		(start 15.3924 -499.6815)
		(end 15.5067 -499.5672)
		(width 0.17145)
		(layer "F.Cu")
		(net "P12V_MOST5_GATE")
	)
	(segment
		(start 15.3924 -500.4562)
		(end 15.3924 -499.6815)
		(width 0.17145)
		(layer "F.Cu")
		(net "P12V_MOST5_GATE")
	)
	(via
		(at 15.3924 -500.4562)
		(size 0.7112)
		(drill 0.3556)
		(layers "F.Cu" "B.Cu")
		(net "P12V_MOST5_GATE")
	)
	(segment
		(start 217.173556 -97.285556)
		(end 218.92006 -97.285556)
		(width 0.508)
		(layer "F.Cu")
		(net "P12V_MOST4_GATE_D")
	)
	(segment
		(start 218.92006 -97.285556)
		(end 219.706444 -97.285556)
		(width 0.508)
		(layer "F.Cu")
		(net "P12V_MOST4_GATE_D")
	)
	(segment
		(start 219.706444 -97.285556)
		(end 220.1672 -96.8248)
		(width 0.508)
		(layer "F.Cu")
		(net "P12V_MOST4_GATE_D")
	)
	(segment
		(start 220.1672 -96.8248)
		(end 220.1672 -95.6056)
		(width 0.508)
		(layer "F.Cu")
		(net "P12V_MOST4_GATE_D")
	)
	(segment
		(start 216.8525 -94.9706)
		(end 216.8525 -96.9645)
		(width 0.508)
		(layer "F.Cu")
		(net "P12V_MOST4_GATE_D")
	)
	(segment
		(start 216.8525 -96.9645)
		(end 217.173556 -97.285556)
		(width 0.508)
		(layer "F.Cu")
		(net "P12V_MOST4_GATE_D")
	)
	(via
		(at 218.92006 -97.285556)
		(size 0.7112)
		(drill 0.3556)
		(layers "F.Cu" "B.Cu")
		(net "P12V_MOST4_GATE_D")
	)
	(segment
		(start 213.3981 -94.9706)
		(end 211.8995 -94.9706)
		(width 0.17145)
		(layer "F.Cu")
		(net "P12V_MOST4_GATE")
	)
	(segment
		(start 214.692484 -96.209866)
		(end 214.9475 -95.95485)
		(width 0.17145)
		(layer "F.Cu")
		(net "P12V_MOST4_GATE")
	)
	(segment
		(start 213.3981 -94.9706)
		(end 213.3981 -96.209866)
		(width 0.17145)
		(layer "F.Cu")
		(net "P12V_MOST4_GATE")
	)
	(segment
		(start 213.3981 -96.209866)
		(end 214.692484 -96.209866)
		(width 0.17145)
		(layer "F.Cu")
		(net "P12V_MOST4_GATE")
	)
	(via
		(at 213.3981 -96.209866)
		(size 0.7112)
		(drill 0.3556)
		(layers "F.Cu" "B.Cu")
		(net "P12V_MOST4_GATE")
	)
	(segment
		(start 216.8525 -200.2155)
		(end 217.212418 -200.575418)
		(width 0.508)
		(layer "F.Cu")
		(net "P12V_MOST3_GATE_D")
	)
	(segment
		(start 219.540582 -200.575418)
		(end 220.0402 -200.0758)
		(width 0.508)
		(layer "F.Cu")
		(net "P12V_MOST3_GATE_D")
	)
	(segment
		(start 217.212418 -200.575418)
		(end 218.373198 -200.575418)
		(width 0.508)
		(layer "F.Cu")
		(net "P12V_MOST3_GATE_D")
	)
	(segment
		(start 220.0402 -200.0758)
		(end 220.0402 -198.6026)
		(width 0.508)
		(layer "F.Cu")
		(net "P12V_MOST3_GATE_D")
	)
	(segment
		(start 218.373198 -200.575418)
		(end 219.540582 -200.575418)
		(width 0.508)
		(layer "F.Cu")
		(net "P12V_MOST3_GATE_D")
	)
	(segment
		(start 216.8525 -197.9676)
		(end 216.8525 -200.2155)
		(width 0.508)
		(layer "F.Cu")
		(net "P12V_MOST3_GATE_D")
	)
	(via
		(at 218.373198 -200.575418)
		(size 0.7112)
		(drill 0.3556)
		(layers "F.Cu" "B.Cu")
		(net "P12V_MOST3_GATE_D")
	)
	(segment
		(start 213.3981 -197.9676)
		(end 213.3981 -199.206866)
		(width 0.17145)
		(layer "F.Cu")
		(net "P12V_MOST3_GATE")
	)
	(segment
		(start 214.692484 -199.206866)
		(end 214.9475 -198.95185)
		(width 0.17145)
		(layer "F.Cu")
		(net "P12V_MOST3_GATE")
	)
	(segment
		(start 213.3981 -197.9676)
		(end 211.8995 -197.9676)
		(width 0.17145)
		(layer "F.Cu")
		(net "P12V_MOST3_GATE")
	)
	(segment
		(start 213.3981 -199.206866)
		(end 214.692484 -199.206866)
		(width 0.17145)
		(layer "F.Cu")
		(net "P12V_MOST3_GATE")
	)
	(via
		(at 213.3981 -199.206866)
		(size 0.7112)
		(drill 0.3556)
		(layers "F.Cu" "B.Cu")
		(net "P12V_MOST3_GATE")
	)
	(segment
		(start 219.61602 -303.36998)
		(end 220.0402 -302.9458)
		(width 0.508)
		(layer "F.Cu")
		(net "P12V_MOST2_GATE_D")
	)
	(segment
		(start 218.509088 -303.36998)
		(end 219.61602 -303.36998)
		(width 0.508)
		(layer "F.Cu")
		(net "P12V_MOST2_GATE_D")
	)
	(segment
		(start 216.8525 -300.9646)
		(end 216.8525 -302.9585)
		(width 0.508)
		(layer "F.Cu")
		(net "P12V_MOST2_GATE_D")
	)
	(segment
		(start 217.26398 -303.36998)
		(end 218.509088 -303.36998)
		(width 0.508)
		(layer "F.Cu")
		(net "P12V_MOST2_GATE_D")
	)
	(segment
		(start 220.0402 -302.9458)
		(end 220.0402 -301.5996)
		(width 0.508)
		(layer "F.Cu")
		(net "P12V_MOST2_GATE_D")
	)
	(segment
		(start 216.8525 -302.9585)
		(end 217.26398 -303.36998)
		(width 0.508)
		(layer "F.Cu")
		(net "P12V_MOST2_GATE_D")
	)
	(via
		(at 218.509088 -303.36998)
		(size 0.7112)
		(drill 0.3556)
		(layers "F.Cu" "B.Cu")
		(net "P12V_MOST2_GATE_D")
	)
	(segment
		(start 213.3981 -300.9646)
		(end 213.3981 -302.203866)
		(width 0.17145)
		(layer "F.Cu")
		(net "P12V_MOST2_GATE")
	)
	(segment
		(start 213.3981 -300.9646)
		(end 211.8995 -300.9646)
		(width 0.17145)
		(layer "F.Cu")
		(net "P12V_MOST2_GATE")
	)
	(segment
		(start 213.3981 -302.203866)
		(end 214.692484 -302.203866)
		(width 0.17145)
		(layer "F.Cu")
		(net "P12V_MOST2_GATE")
	)
	(segment
		(start 214.692484 -302.203866)
		(end 214.9475 -301.94885)
		(width 0.17145)
		(layer "F.Cu")
		(net "P12V_MOST2_GATE")
	)
	(via
		(at 213.3981 -302.203866)
		(size 0.7112)
		(drill 0.3556)
		(layers "F.Cu" "B.Cu")
		(net "P12V_MOST2_GATE")
	)
	(segment
		(start 42.4815 -7.0104)
		(end 42.4815 -9.2075)
		(width 0.508)
		(layer "F.Cu")
		(net "P12V_MOST14_GATE_D")
	)
	(segment
		(start 41.0464 -9.6012)
		(end 40.7416 -9.2964)
		(width 0.508)
		(layer "F.Cu")
		(net "P12V_MOST14_GATE_D")
	)
	(segment
		(start 42.4815 -9.2075)
		(end 42.0878 -9.6012)
		(width 0.508)
		(layer "F.Cu")
		(net "P12V_MOST14_GATE_D")
	)
	(segment
		(start 42.0878 -9.6012)
		(end 41.0464 -9.6012)
		(width 0.508)
		(layer "F.Cu")
		(net "P12V_MOST14_GATE_D")
	)
	(via
		(at 42.0878 -9.6012)
		(size 0.7112)
		(drill 0.3556)
		(layers "F.Cu" "B.Cu")
		(net "P12V_MOST14_GATE_D")
	)
	(segment
		(start 45.9359 -7.0104)
		(end 45.9359 -5.771134)
		(width 0.17145)
		(layer "F.Cu")
		(net "P12V_MOST14_GATE")
	)
	(segment
		(start 45.9359 -7.0104)
		(end 47.4345 -7.0104)
		(width 0.17145)
		(layer "F.Cu")
		(net "P12V_MOST14_GATE")
	)
	(segment
		(start 44.641516 -5.771134)
		(end 44.3865 -6.02615)
		(width 0.17145)
		(layer "F.Cu")
		(net "P12V_MOST14_GATE")
	)
	(segment
		(start 45.9359 -5.771134)
		(end 44.641516 -5.771134)
		(width 0.17145)
		(layer "F.Cu")
		(net "P12V_MOST14_GATE")
	)
	(via
		(at 45.9359 -5.771134)
		(size 0.7112)
		(drill 0.3556)
		(layers "F.Cu" "B.Cu")
		(net "P12V_MOST14_GATE")
	)
	(segment
		(start 29.2354 -100.6602)
		(end 29.55925 -100.98405)
		(width 0.508)
		(layer "F.Cu")
		(net "P12V_MOST13_GATE_D")
	)
	(segment
		(start 28.0924 -100.6602)
		(end 29.2354 -100.6602)
		(width 0.508)
		(layer "F.Cu")
		(net "P12V_MOST13_GATE_D")
	)
	(segment
		(start 28.0924 -100.6602)
		(end 27.305 -100.6602)
		(width 0.508)
		(layer "F.Cu")
		(net "P12V_MOST13_GATE_D")
	)
	(segment
		(start 26.67635 -101.28885)
		(end 26.67635 -101.86035)
		(width 0.508)
		(layer "F.Cu")
		(net "P12V_MOST13_GATE_D")
	)
	(segment
		(start 27.305 -100.6602)
		(end 26.67635 -101.28885)
		(width 0.508)
		(layer "F.Cu")
		(net "P12V_MOST13_GATE_D")
	)
	(segment
		(start 29.55925 -100.98405)
		(end 29.55925 -101.91115)
		(width 0.508)
		(layer "F.Cu")
		(net "P12V_MOST13_GATE_D")
	)
	(via
		(at 28.0924 -100.6602)
		(size 0.7112)
		(drill 0.3556)
		(layers "F.Cu" "B.Cu")
		(net "P12V_MOST13_GATE_D")
	)
	(segment
		(start 33.01365 -101.91115)
		(end 33.01365 -100.671884)
		(width 0.17145)
		(layer "F.Cu")
		(net "P12V_MOST13_GATE")
	)
	(segment
		(start 31.719266 -100.671884)
		(end 31.46425 -100.9269)
		(width 0.17145)
		(layer "F.Cu")
		(net "P12V_MOST13_GATE")
	)
	(segment
		(start 33.01365 -100.671884)
		(end 31.719266 -100.671884)
		(width 0.17145)
		(layer "F.Cu")
		(net "P12V_MOST13_GATE")
	)
	(segment
		(start 33.01365 -101.91115)
		(end 34.51225 -101.91115)
		(width 0.17145)
		(layer "F.Cu")
		(net "P12V_MOST13_GATE")
	)
	(via
		(at 33.01365 -100.671884)
		(size 0.7112)
		(drill 0.3556)
		(layers "F.Cu" "B.Cu")
		(net "P12V_MOST13_GATE")
	)
	(segment
		(start 26.7208 -204.6478)
		(end 26.7208 -204.255116)
		(width 0.508)
		(layer "F.Cu")
		(net "P12V_MOST12_GATE_D")
	)
	(segment
		(start 27.2542 -203.721716)
		(end 28.2448 -203.721716)
		(width 0.508)
		(layer "F.Cu")
		(net "P12V_MOST12_GATE_D")
	)
	(segment
		(start 29.6545 -204.090016)
		(end 29.6545 -205.0034)
		(width 0.508)
		(layer "F.Cu")
		(net "P12V_MOST12_GATE_D")
	)
	(segment
		(start 29.2862 -203.721716)
		(end 29.6545 -204.090016)
		(width 0.508)
		(layer "F.Cu")
		(net "P12V_MOST12_GATE_D")
	)
	(segment
		(start 28.2448 -203.721716)
		(end 29.2862 -203.721716)
		(width 0.508)
		(layer "F.Cu")
		(net "P12V_MOST12_GATE_D")
	)
	(segment
		(start 26.7208 -204.255116)
		(end 27.2542 -203.721716)
		(width 0.508)
		(layer "F.Cu")
		(net "P12V_MOST12_GATE_D")
	)
	(via
		(at 28.2448 -203.721716)
		(size 0.7112)
		(drill 0.3556)
		(layers "F.Cu" "B.Cu")
		(net "P12V_MOST12_GATE_D")
	)
	(segment
		(start 33.1089 -205.0034)
		(end 34.6075 -205.0034)
		(width 0.17145)
		(layer "F.Cu")
		(net "P12V_MOST12_GATE")
	)
	(segment
		(start 33.1089 -203.764134)
		(end 31.814516 -203.764134)
		(width 0.17145)
		(layer "F.Cu")
		(net "P12V_MOST12_GATE")
	)
	(segment
		(start 33.1089 -205.0034)
		(end 33.1089 -203.764134)
		(width 0.17145)
		(layer "F.Cu")
		(net "P12V_MOST12_GATE")
	)
	(segment
		(start 31.814516 -203.764134)
		(end 31.5595 -204.01915)
		(width 0.17145)
		(layer "F.Cu")
		(net "P12V_MOST12_GATE")
	)
	(via
		(at 33.1089 -203.764134)
		(size 0.7112)
		(drill 0.3556)
		(layers "F.Cu" "B.Cu")
		(net "P12V_MOST12_GATE")
	)
	(segment
		(start 26.6954 -307.4416)
		(end 26.6954 -307.7972)
		(width 0.508)
		(layer "F.Cu")
		(net "P12V_MOST11_GATE_D")
	)
	(segment
		(start 28.194 -306.7812)
		(end 29.21 -306.7812)
		(width 0.508)
		(layer "F.Cu")
		(net "P12V_MOST11_GATE_D")
	)
	(segment
		(start 27.3558 -306.7812)
		(end 26.6954 -307.4416)
		(width 0.508)
		(layer "F.Cu")
		(net "P12V_MOST11_GATE_D")
	)
	(segment
		(start 28.194 -306.7812)
		(end 27.3558 -306.7812)
		(width 0.508)
		(layer "F.Cu")
		(net "P12V_MOST11_GATE_D")
	)
	(segment
		(start 29.6545 -307.2257)
		(end 29.6545 -308.0004)
		(width 0.508)
		(layer "F.Cu")
		(net "P12V_MOST11_GATE_D")
	)
	(segment
		(start 29.21 -306.7812)
		(end 29.6545 -307.2257)
		(width 0.508)
		(layer "F.Cu")
		(net "P12V_MOST11_GATE_D")
	)
	(via
		(at 28.194 -306.7812)
		(size 0.7112)
		(drill 0.3556)
		(layers "F.Cu" "B.Cu")
		(net "P12V_MOST11_GATE_D")
	)
	(segment
		(start 31.814516 -306.761134)
		(end 31.5595 -307.01615)
		(width 0.17145)
		(layer "F.Cu")
		(net "P12V_MOST11_GATE")
	)
	(segment
		(start 33.1089 -308.0004)
		(end 33.1089 -306.761134)
		(width 0.17145)
		(layer "F.Cu")
		(net "P12V_MOST11_GATE")
	)
	(segment
		(start 33.1089 -306.761134)
		(end 31.814516 -306.761134)
		(width 0.17145)
		(layer "F.Cu")
		(net "P12V_MOST11_GATE")
	)
	(segment
		(start 33.1089 -308.0004)
		(end 34.6075 -308.0004)
		(width 0.17145)
		(layer "F.Cu")
		(net "P12V_MOST11_GATE")
	)
	(via
		(at 33.1089 -306.761134)
		(size 0.7112)
		(drill 0.3556)
		(layers "F.Cu" "B.Cu")
		(net "P12V_MOST11_GATE")
	)
	(segment
		(start 29.337 -409.7528)
		(end 29.6545 -410.0703)
		(width 0.508)
		(layer "F.Cu")
		(net "P12V_MOST10_GATE_D")
	)
	(segment
		(start 28.194 -409.7528)
		(end 29.337 -409.7528)
		(width 0.508)
		(layer "F.Cu")
		(net "P12V_MOST10_GATE_D")
	)
	(segment
		(start 27.559 -409.7528)
		(end 26.67 -410.6418)
		(width 0.508)
		(layer "F.Cu")
		(net "P12V_MOST10_GATE_D")
	)
	(segment
		(start 29.6545 -410.0703)
		(end 29.6545 -410.9974)
		(width 0.508)
		(layer "F.Cu")
		(net "P12V_MOST10_GATE_D")
	)
	(segment
		(start 28.194 -409.7528)
		(end 27.559 -409.7528)
		(width 0.508)
		(layer "F.Cu")
		(net "P12V_MOST10_GATE_D")
	)
	(via
		(at 28.194 -409.7528)
		(size 0.7112)
		(drill 0.3556)
		(layers "F.Cu" "B.Cu")
		(net "P12V_MOST10_GATE_D")
	)
	(segment
		(start 33.677352 -411.2514)
		(end 33.931352 -410.9974)
		(width 0.17145)
		(layer "F.Cu")
		(net "P12V_MOST10_GATE")
	)
	(segment
		(start 33.1089 -409.758134)
		(end 33.1089 -411.2514)
		(width 0.17145)
		(layer "F.Cu")
		(net "P12V_MOST10_GATE")
	)
	(segment
		(start 33.1089 -409.758134)
		(end 31.814516 -409.758134)
		(width 0.17145)
		(layer "F.Cu")
		(net "P12V_MOST10_GATE")
	)
	(segment
		(start 33.931352 -410.9974)
		(end 34.6075 -410.9974)
		(width 0.17145)
		(layer "F.Cu")
		(net "P12V_MOST10_GATE")
	)
	(segment
		(start 33.1089 -411.2514)
		(end 33.677352 -411.2514)
		(width 0.17145)
		(layer "F.Cu")
		(net "P12V_MOST10_GATE")
	)
	(segment
		(start 31.814516 -409.758134)
		(end 31.5595 -410.01315)
		(width 0.17145)
		(layer "F.Cu")
		(net "P12V_MOST10_GATE")
	)
	(via
		(at 33.1089 -409.758134)
		(size 0.7112)
		(drill 0.3556)
		(layers "F.Cu" "B.Cu")
		(net "P12V_MOST10_GATE")
	)
	(segment
		(start 220.0402 -405.920702)
		(end 220.0402 -404.9776)
		(width 0.508)
		(layer "F.Cu")
		(net "P12V_MOST1_GATE_D")
	)
	(segment
		(start 217.97899 -406.657302)
		(end 219.3036 -406.657302)
		(width 0.508)
		(layer "F.Cu")
		(net "P12V_MOST1_GATE_D")
	)
	(segment
		(start 219.3036 -406.657302)
		(end 220.0402 -405.920702)
		(width 0.508)
		(layer "F.Cu")
		(net "P12V_MOST1_GATE_D")
	)
	(segment
		(start 216.8525 -406.273)
		(end 217.236802 -406.657302)
		(width 0.508)
		(layer "F.Cu")
		(net "P12V_MOST1_GATE_D")
	)
	(segment
		(start 216.8525 -403.9616)
		(end 216.8525 -406.273)
		(width 0.508)
		(layer "F.Cu")
		(net "P12V_MOST1_GATE_D")
	)
	(segment
		(start 217.236802 -406.657302)
		(end 217.97899 -406.657302)
		(width 0.508)
		(layer "F.Cu")
		(net "P12V_MOST1_GATE_D")
	)
	(via
		(at 217.97899 -406.657302)
		(size 0.7112)
		(drill 0.3556)
		(layers "F.Cu" "B.Cu")
		(net "P12V_MOST1_GATE_D")
	)
	(segment
		(start 213.3981 -403.9616)
		(end 211.8995 -403.9616)
		(width 0.17145)
		(layer "F.Cu")
		(net "P12V_MOST1_GATE")
	)
	(segment
		(start 213.3981 -405.200866)
		(end 214.692484 -405.200866)
		(width 0.17145)
		(layer "F.Cu")
		(net "P12V_MOST1_GATE")
	)
	(segment
		(start 213.3981 -403.9616)
		(end 213.3981 -405.200866)
		(width 0.17145)
		(layer "F.Cu")
		(net "P12V_MOST1_GATE")
	)
	(segment
		(start 214.692484 -405.200866)
		(end 214.9475 -404.94585)
		(width 0.17145)
		(layer "F.Cu")
		(net "P12V_MOST1_GATE")
	)
	(via
		(at 213.3981 -405.200866)
		(size 0.7112)
		(drill 0.3556)
		(layers "F.Cu" "B.Cu")
		(net "P12V_MOST1_GATE")
	)
	(segment
		(start 203.705206 -498.959378)
		(end 204.835506 -498.959378)
		(width 0.508)
		(layer "F.Cu")
		(net "P12V_MOST0_GATE_D")
	)
	(segment
		(start 206.105506 -497.689378)
		(end 205.318106 -498.476778)
		(width 0.508)
		(layer "F.Cu")
		(net "P12V_MOST0_GATE_D")
	)
	(segment
		(start 204.835506 -498.959378)
		(end 205.318106 -498.476778)
		(width 0.508)
		(layer "F.Cu")
		(net "P12V_MOST0_GATE_D")
	)
	(segment
		(start 207.096106 -497.689378)
		(end 206.105506 -497.689378)
		(width 0.508)
		(layer "F.Cu")
		(net "P12V_MOST0_GATE_D")
	)
	(via
		(at 205.318106 -498.476778)
		(size 0.7112)
		(drill 0.3556)
		(layers "F.Cu" "B.Cu")
		(net "P12V_MOST0_GATE_D")
	)
	(segment
		(start 201.800206 -499.943628)
		(end 201.54519 -500.198644)
		(width 0.17145)
		(layer "F.Cu")
		(net "P12V_MOST0_GATE")
	)
	(segment
		(start 200.250806 -498.959378)
		(end 198.752206 -498.959378)
		(width 0.17145)
		(layer "F.Cu")
		(net "P12V_MOST0_GATE")
	)
	(segment
		(start 201.54519 -500.198644)
		(end 200.250806 -500.198644)
		(width 0.17145)
		(layer "F.Cu")
		(net "P12V_MOST0_GATE")
	)
	(segment
		(start 200.250806 -498.959378)
		(end 200.250806 -500.198644)
		(width 0.17145)
		(layer "F.Cu")
		(net "P12V_MOST0_GATE")
	)
	(via
		(at 200.250806 -500.198644)
		(size 0.7112)
		(drill 0.3556)
		(layers "F.Cu" "B.Cu")
		(net "P12V_MOST0_GATE")
	)
	(segment
		(start 89.55659 -99.84994)
		(end 88.41994 -99.84994)
		(width 0.17145)
		(layer "F.Cu")
		(net "I2C_SDA_BUF_8_EU4_R")
	)
	(segment
		(start 86.995 -97.79)
		(end 87.122 -97.917)
		(width 0.17145)
		(layer "F.Cu")
		(net "I2C_SDA_BUF_8_EU4_R")
	)
	(segment
		(start 88.41994 -99.84994)
		(end 87.20455 -98.63455)
		(width 0.17145)
		(layer "F.Cu")
		(net "I2C_SDA_BUF_8_EU4_R")
	)
	(segment
		(start 87.20455 -97.99955)
		(end 87.122 -97.917)
		(width 0.17145)
		(layer "F.Cu")
		(net "I2C_SDA_BUF_8_EU4_R")
	)
	(segment
		(start 87.20455 -98.63455)
		(end 87.20455 -97.99955)
		(width 0.17145)
		(layer "F.Cu")
		(net "I2C_SDA_BUF_8_EU4_R")
	)
	(segment
		(start 84.8995 -97.79)
		(end 86.995 -97.79)
		(width 0.17145)
		(layer "F.Cu")
		(net "I2C_SDA_BUF_8_EU4_R")
	)
	(via
		(at 87.122 -97.917)
		(size 0.7112)
		(drill 0.3556)
		(layers "F.Cu" "B.Cu")
		(net "I2C_SDA_BUF_8_EU4_R")
	)
	(segment
		(start 87.122 -207.137)
		(end 87.122 -207.054704)
		(width 0.17145)
		(layer "F.Cu")
		(net "I2C_SDA_BUF_8_EU3_R")
	)
	(segment
		(start 87.20455 -207.80375)
		(end 88.47074 -209.06994)
		(width 0.17145)
		(layer "F.Cu")
		(net "I2C_SDA_BUF_8_EU3_R")
	)
	(segment
		(start 86.613746 -206.54645)
		(end 85.36305 -206.54645)
		(width 0.17145)
		(layer "F.Cu")
		(net "I2C_SDA_BUF_8_EU3_R")
	)
	(segment
		(start 87.122 -207.054704)
		(end 86.613746 -206.54645)
		(width 0.17145)
		(layer "F.Cu")
		(net "I2C_SDA_BUF_8_EU3_R")
	)
	(segment
		(start 88.47074 -209.06994)
		(end 89.55659 -209.06994)
		(width 0.17145)
		(layer "F.Cu")
		(net "I2C_SDA_BUF_8_EU3_R")
	)
	(segment
		(start 87.122 -207.137)
		(end 87.20455 -207.21955)
		(width 0.17145)
		(layer "F.Cu")
		(net "I2C_SDA_BUF_8_EU3_R")
	)
	(segment
		(start 85.36305 -206.54645)
		(end 84.8995 -207.01)
		(width 0.17145)
		(layer "F.Cu")
		(net "I2C_SDA_BUF_8_EU3_R")
	)
	(segment
		(start 87.20455 -207.21955)
		(end 87.20455 -207.80375)
		(width 0.17145)
		(layer "F.Cu")
		(net "I2C_SDA_BUF_8_EU3_R")
	)
	(via
		(at 87.122 -207.137)
		(size 0.7112)
		(drill 0.3556)
		(layers "F.Cu" "B.Cu")
		(net "I2C_SDA_BUF_8_EU3_R")
	)
	(segment
		(start 87.249 -97.1804)
		(end 87.0204 -97.1804)
		(width 0.17145)
		(layer "F.Cu")
		(net "I2C_SCL_BUF_8_EU4_R")
	)
	(segment
		(start 85.598 -96.774)
		(end 86.106 -96.266)
		(width 0.17145)
		(layer "F.Cu")
		(net "I2C_SCL_BUF_8_EU4_R")
	)
	(segment
		(start 87.0204 -97.1804)
		(end 86.106 -96.266)
		(width 0.17145)
		(layer "F.Cu")
		(net "I2C_SCL_BUF_8_EU4_R")
	)
	(segment
		(start 87.757 -98.405696)
		(end 87.757 -97.6884)
		(width 0.17145)
		(layer "F.Cu")
		(net "I2C_SCL_BUF_8_EU4_R")
	)
	(segment
		(start 88.700864 -99.34956)
		(end 87.757 -98.405696)
		(width 0.17145)
		(layer "F.Cu")
		(net "I2C_SCL_BUF_8_EU4_R")
	)
	(segment
		(start 87.757 -97.6884)
		(end 87.249 -97.1804)
		(width 0.17145)
		(layer "F.Cu")
		(net "I2C_SCL_BUF_8_EU4_R")
	)
	(segment
		(start 89.55659 -99.34956)
		(end 88.700864 -99.34956)
		(width 0.17145)
		(layer "F.Cu")
		(net "I2C_SCL_BUF_8_EU4_R")
	)
	(segment
		(start 84.8995 -96.774)
		(end 85.598 -96.774)
		(width 0.17145)
		(layer "F.Cu")
		(net "I2C_SCL_BUF_8_EU4_R")
	)
	(via
		(at 86.106 -96.266)
		(size 0.7112)
		(drill 0.3556)
		(layers "F.Cu" "B.Cu")
		(net "I2C_SCL_BUF_8_EU4_R")
	)
	(segment
		(start 87.757 -207.574896)
		(end 88.751664 -208.56956)
		(width 0.17145)
		(layer "F.Cu")
		(net "I2C_SCL_BUF_8_EU3_R")
	)
	(segment
		(start 86.116414 -205.496414)
		(end 86.345014 -205.496414)
		(width 0.17145)
		(layer "F.Cu")
		(net "I2C_SCL_BUF_8_EU3_R")
	)
	(segment
		(start 86.106 -205.486)
		(end 85.598 -205.994)
		(width 0.17145)
		(layer "F.Cu")
		(net "I2C_SCL_BUF_8_EU3_R")
	)
	(segment
		(start 87.757 -206.9084)
		(end 87.757 -207.574896)
		(width 0.17145)
		(layer "F.Cu")
		(net "I2C_SCL_BUF_8_EU3_R")
	)
	(segment
		(start 85.598 -205.994)
		(end 84.8995 -205.994)
		(width 0.17145)
		(layer "F.Cu")
		(net "I2C_SCL_BUF_8_EU3_R")
	)
	(segment
		(start 88.751664 -208.56956)
		(end 89.55659 -208.56956)
		(width 0.17145)
		(layer "F.Cu")
		(net "I2C_SCL_BUF_8_EU3_R")
	)
	(segment
		(start 86.345014 -205.496414)
		(end 87.757 -206.9084)
		(width 0.17145)
		(layer "F.Cu")
		(net "I2C_SCL_BUF_8_EU3_R")
	)
	(segment
		(start 86.106 -205.486)
		(end 86.116414 -205.496414)
		(width 0.17145)
		(layer "F.Cu")
		(net "I2C_SCL_BUF_8_EU3_R")
	)
	(via
		(at 86.106 -205.486)
		(size 0.7112)
		(drill 0.3556)
		(layers "F.Cu" "B.Cu")
		(net "I2C_SCL_BUF_8_EU3_R")
	)
	(segment
		(start 32.621982 -84.218018)
		(end 33.1216 -83.7184)
		(width 0.17145)
		(layer "F.Cu")
		(net "DUALPORTEN#9")
	)
	(segment
		(start 37.7952 -83.0072)
		(end 38.177978 -83.389978)
		(width 0.17145)
		(layer "F.Cu")
		(net "DUALPORTEN#9")
	)
	(segment
		(start 35.9664 -83.0072)
		(end 37.7952 -83.0072)
		(width 0.17145)
		(layer "F.Cu")
		(net "DUALPORTEN#9")
	)
	(segment
		(start 38.177978 -83.389978)
		(end 39.200074 -83.389978)
		(width 0.17145)
		(layer "F.Cu")
		(net "DUALPORTEN#9")
	)
	(segment
		(start 35.2552 -83.7184)
		(end 35.9664 -83.0072)
		(width 0.17145)
		(layer "F.Cu")
		(net "DUALPORTEN#9")
	)
	(segment
		(start 29.03093 -84.218018)
		(end 30.57398 -84.218018)
		(width 0.17145)
		(layer "F.Cu")
		(net "DUALPORTEN#9")
	)
	(segment
		(start 32.11703 -84.218018)
		(end 32.621982 -84.218018)
		(width 0.17145)
		(layer "F.Cu")
		(net "DUALPORTEN#9")
	)
	(segment
		(start 33.1216 -83.7184)
		(end 35.2552 -83.7184)
		(width 0.17145)
		(layer "F.Cu")
		(net "DUALPORTEN#9")
	)
	(segment
		(start 32.11703 -84.218018)
		(end 30.57398 -84.218018)
		(width 0.17145)
		(layer "F.Cu")
		(net "DUALPORTEN#9")
	)
	(via
		(at 30.57398 -84.218018)
		(size 0.7112)
		(drill 0.3556)
		(layers "F.Cu" "B.Cu")
		(net "DUALPORTEN#9")
	)
	(segment
		(start 35.4838 -186.7154)
		(end 33.1724 -186.7154)
		(width 0.17145)
		(layer "F.Cu")
		(net "DUALPORTEN#8")
	)
	(segment
		(start 38.33876 -186.390026)
		(end 37.978334 -186.0296)
		(width 0.17145)
		(layer "F.Cu")
		(net "DUALPORTEN#8")
	)
	(segment
		(start 39.200074 -186.390026)
		(end 38.33876 -186.390026)
		(width 0.17145)
		(layer "F.Cu")
		(net "DUALPORTEN#8")
	)
	(segment
		(start 33.1724 -186.7154)
		(end 32.6644 -187.2234)
		(width 0.17145)
		(layer "F.Cu")
		(net "DUALPORTEN#8")
	)
	(segment
		(start 29.95803 -187.240418)
		(end 31.10103 -187.240418)
		(width 0.17145)
		(layer "F.Cu")
		(net "DUALPORTEN#8")
	)
	(segment
		(start 32.367982 -187.240418)
		(end 32.385 -187.2234)
		(width 0.17145)
		(layer "F.Cu")
		(net "DUALPORTEN#8")
	)
	(segment
		(start 37.978334 -186.0296)
		(end 36.1696 -186.0296)
		(width 0.17145)
		(layer "F.Cu")
		(net "DUALPORTEN#8")
	)
	(segment
		(start 31.10103 -187.240418)
		(end 32.367982 -187.240418)
		(width 0.17145)
		(layer "F.Cu")
		(net "DUALPORTEN#8")
	)
	(segment
		(start 36.1696 -186.0296)
		(end 35.4838 -186.7154)
		(width 0.17145)
		(layer "F.Cu")
		(net "DUALPORTEN#8")
	)
	(segment
		(start 32.6644 -187.2234)
		(end 32.385 -187.2234)
		(width 0.17145)
		(layer "F.Cu")
		(net "DUALPORTEN#8")
	)
	(via
		(at 32.385 -187.2234)
		(size 0.7112)
		(drill 0.3556)
		(layers "F.Cu" "B.Cu")
		(net "DUALPORTEN#8")
	)
	(segment
		(start 32.8422 -289.7378)
		(end 35.0012 -289.7378)
		(width 0.17145)
		(layer "F.Cu")
		(net "DUALPORTEN#7")
	)
	(segment
		(start 31.0896 -290.2077)
		(end 32.3723 -290.2077)
		(width 0.17145)
		(layer "F.Cu")
		(net "DUALPORTEN#7")
	)
	(segment
		(start 32.385 -290.195)
		(end 32.8422 -289.7378)
		(width 0.17145)
		(layer "F.Cu")
		(net "DUALPORTEN#7")
	)
	(segment
		(start 35.0012 -289.7378)
		(end 35.687 -289.052)
		(width 0.17145)
		(layer "F.Cu")
		(net "DUALPORTEN#7")
	)
	(segment
		(start 32.3723 -290.2077)
		(end 32.385 -290.195)
		(width 0.17145)
		(layer "F.Cu")
		(net "DUALPORTEN#7")
	)
	(segment
		(start 37.7952 -289.052)
		(end 38.133274 -289.390074)
		(width 0.17145)
		(layer "F.Cu")
		(net "DUALPORTEN#7")
	)
	(segment
		(start 35.687 -289.052)
		(end 37.7952 -289.052)
		(width 0.17145)
		(layer "F.Cu")
		(net "DUALPORTEN#7")
	)
	(segment
		(start 38.133274 -289.390074)
		(end 39.200074 -289.390074)
		(width 0.17145)
		(layer "F.Cu")
		(net "DUALPORTEN#7")
	)
	(segment
		(start 31.0896 -290.2077)
		(end 29.9466 -290.2077)
		(width 0.17145)
		(layer "F.Cu")
		(net "DUALPORTEN#7")
	)
	(via
		(at 32.385 -290.195)
		(size 0.7112)
		(drill 0.3556)
		(layers "F.Cu" "B.Cu")
		(net "DUALPORTEN#7")
	)
	(segment
		(start 28.5877 -393.2428)
		(end 29.9974 -393.2428)
		(width 0.17145)
		(layer "F.Cu")
		(net "DUALPORTEN#6")
	)
	(segment
		(start 39.200074 -392.390122)
		(end 38.085268 -392.390122)
		(width 0.17145)
		(layer "F.Cu")
		(net "DUALPORTEN#6")
	)
	(segment
		(start 35.3314 -392.684)
		(end 32.766 -392.684)
		(width 0.17145)
		(layer "F.Cu")
		(net "DUALPORTEN#6")
	)
	(segment
		(start 38.085268 -392.390122)
		(end 37.752528 -392.057382)
		(width 0.17145)
		(layer "F.Cu")
		(net "DUALPORTEN#6")
	)
	(segment
		(start 35.958018 -392.057382)
		(end 35.3314 -392.684)
		(width 0.17145)
		(layer "F.Cu")
		(net "DUALPORTEN#6")
	)
	(segment
		(start 28.5877 -393.2428)
		(end 28.5877 -392.0998)
		(width 0.17145)
		(layer "F.Cu")
		(net "DUALPORTEN#6")
	)
	(segment
		(start 32.766 -392.684)
		(end 32.4104 -393.0396)
		(width 0.17145)
		(layer "F.Cu")
		(net "DUALPORTEN#6")
	)
	(segment
		(start 32.4104 -393.0396)
		(end 31.115 -393.0396)
		(width 0.17145)
		(layer "F.Cu")
		(net "DUALPORTEN#6")
	)
	(segment
		(start 30.2006 -393.0396)
		(end 31.115 -393.0396)
		(width 0.17145)
		(layer "F.Cu")
		(net "DUALPORTEN#6")
	)
	(segment
		(start 29.9974 -393.2428)
		(end 30.2006 -393.0396)
		(width 0.17145)
		(layer "F.Cu")
		(net "DUALPORTEN#6")
	)
	(segment
		(start 37.752528 -392.057382)
		(end 35.958018 -392.057382)
		(width 0.17145)
		(layer "F.Cu")
		(net "DUALPORTEN#6")
	)
	(via
		(at 31.115 -393.0396)
		(size 0.7112)
		(drill 0.3556)
		(layers "F.Cu" "B.Cu")
		(net "DUALPORTEN#6")
	)
	(segment
		(start 37.78377 -495.39017)
		(end 37.4904 -495.0968)
		(width 0.17145)
		(layer "F.Cu")
		(net "DUALPORTEN#5")
	)
	(segment
		(start 32.131 -493.7125)
		(end 34.5059 -493.7125)
		(width 0.17145)
		(layer "F.Cu")
		(net "DUALPORTEN#5")
	)
	(segment
		(start 34.5059 -493.7125)
		(end 35.0774 -494.284)
		(width 0.17145)
		(layer "F.Cu")
		(net "DUALPORTEN#5")
	)
	(segment
		(start 39.200074 -495.39017)
		(end 37.78377 -495.39017)
		(width 0.17145)
		(layer "F.Cu")
		(net "DUALPORTEN#5")
	)
	(segment
		(start 32.0929 -493.7506)
		(end 32.131 -493.7125)
		(width 0.17145)
		(layer "F.Cu")
		(net "DUALPORTEN#5")
	)
	(segment
		(start 37.4904 -495.0968)
		(end 35.8902 -495.0968)
		(width 0.17145)
		(layer "F.Cu")
		(net "DUALPORTEN#5")
	)
	(segment
		(start 31.1023 -493.7506)
		(end 32.0929 -493.7506)
		(width 0.17145)
		(layer "F.Cu")
		(net "DUALPORTEN#5")
	)
	(segment
		(start 35.8902 -495.0968)
		(end 35.0774 -494.284)
		(width 0.17145)
		(layer "F.Cu")
		(net "DUALPORTEN#5")
	)
	(via
		(at 35.0774 -494.284)
		(size 0.7112)
		(drill 0.3556)
		(layers "F.Cu" "B.Cu")
		(net "DUALPORTEN#5")
	)
	(segment
		(start 214.3887 -84.0105)
		(end 215.93175 -84.0105)
		(width 0.17145)
		(layer "F.Cu")
		(net "DUALPORTEN#4")
	)
	(segment
		(start 221.107 -83.693)
		(end 221.410022 -83.389978)
		(width 0.17145)
		(layer "F.Cu")
		(net "DUALPORTEN#4")
	)
	(segment
		(start 217.4748 -84.0105)
		(end 217.7923 -83.693)
		(width 0.17145)
		(layer "F.Cu")
		(net "DUALPORTEN#4")
	)
	(segment
		(start 221.410022 -83.389978)
		(end 224.199958 -83.389978)
		(width 0.17145)
		(layer "F.Cu")
		(net "DUALPORTEN#4")
	)
	(segment
		(start 217.7923 -83.693)
		(end 221.107 -83.693)
		(width 0.17145)
		(layer "F.Cu")
		(net "DUALPORTEN#4")
	)
	(segment
		(start 215.93175 -84.0105)
		(end 217.4748 -84.0105)
		(width 0.17145)
		(layer "F.Cu")
		(net "DUALPORTEN#4")
	)
	(via
		(at 215.93175 -84.0105)
		(size 0.7112)
		(drill 0.3556)
		(layers "F.Cu" "B.Cu")
		(net "DUALPORTEN#4")
	)
	(segment
		(start 217.7669 -187.1345)
		(end 218.1606 -186.7408)
		(width 0.17145)
		(layer "F.Cu")
		(net "DUALPORTEN#3")
	)
	(segment
		(start 216.1921 -187.1345)
		(end 217.4494 -187.1345)
		(width 0.17145)
		(layer "F.Cu")
		(net "DUALPORTEN#3")
	)
	(segment
		(start 217.4494 -187.1345)
		(end 217.7669 -187.1345)
		(width 0.17145)
		(layer "F.Cu")
		(net "DUALPORTEN#3")
	)
	(segment
		(start 216.1921 -187.1345)
		(end 214.9348 -187.1345)
		(width 0.17145)
		(layer "F.Cu")
		(net "DUALPORTEN#3")
	)
	(segment
		(start 218.1606 -186.7408)
		(end 220.2688 -186.7408)
		(width 0.17145)
		(layer "F.Cu")
		(net "DUALPORTEN#3")
	)
	(segment
		(start 220.2688 -186.7408)
		(end 220.619574 -186.390026)
		(width 0.17145)
		(layer "F.Cu")
		(net "DUALPORTEN#3")
	)
	(segment
		(start 220.619574 -186.390026)
		(end 224.199958 -186.390026)
		(width 0.17145)
		(layer "F.Cu")
		(net "DUALPORTEN#3")
	)
	(via
		(at 216.1921 -187.1345)
		(size 0.7112)
		(drill 0.3556)
		(layers "F.Cu" "B.Cu")
		(net "DUALPORTEN#3")
	)
	(segment
		(start 215.7857 -290.1061)
		(end 214.5284 -290.1061)
		(width 0.17145)
		(layer "F.Cu")
		(net "DUALPORTEN#2")
	)
	(segment
		(start 218.186 -289.687)
		(end 220.276674 -289.687)
		(width 0.17145)
		(layer "F.Cu")
		(net "DUALPORTEN#2")
	)
	(segment
		(start 217.043 -290.1061)
		(end 215.7857 -290.1061)
		(width 0.17145)
		(layer "F.Cu")
		(net "DUALPORTEN#2")
	)
	(segment
		(start 220.276674 -289.687)
		(end 220.5736 -289.390074)
		(width 0.17145)
		(layer "F.Cu")
		(net "DUALPORTEN#2")
	)
	(segment
		(start 220.5736 -289.390074)
		(end 224.199958 -289.390074)
		(width 0.17145)
		(layer "F.Cu")
		(net "DUALPORTEN#2")
	)
	(segment
		(start 217.043 -290.1061)
		(end 217.7669 -290.1061)
		(width 0.17145)
		(layer "F.Cu")
		(net "DUALPORTEN#2")
	)
	(segment
		(start 217.7669 -290.1061)
		(end 218.186 -289.687)
		(width 0.17145)
		(layer "F.Cu")
		(net "DUALPORTEN#2")
	)
	(via
		(at 215.7857 -290.1061)
		(size 0.7112)
		(drill 0.3556)
		(layers "F.Cu" "B.Cu")
		(net "DUALPORTEN#2")
	)
	(segment
		(start 30.6832 -112.9157)
		(end 31.8262 -112.9157)
		(width 0.17145)
		(layer "F.Cu")
		(net "DUALPORTEN#13")
	)
	(segment
		(start 29.4132 -112.9284)
		(end 30.6705 -112.9284)
		(width 0.17145)
		(layer "F.Cu")
		(net "DUALPORTEN#13")
	)
	(segment
		(start 22.800056 -113.609882)
		(end 23.770082 -113.609882)
		(width 0.17145)
		(layer "F.Cu")
		(net "DUALPORTEN#13")
	)
	(segment
		(start 23.770082 -113.609882)
		(end 24.0538 -113.8936)
		(width 0.17145)
		(layer "F.Cu")
		(net "DUALPORTEN#13")
	)
	(segment
		(start 30.6705 -112.9284)
		(end 30.6832 -112.9157)
		(width 0.17145)
		(layer "F.Cu")
		(net "DUALPORTEN#13")
	)
	(segment
		(start 26.6446 -113.3094)
		(end 29.0322 -113.3094)
		(width 0.17145)
		(layer "F.Cu")
		(net "DUALPORTEN#13")
	)
	(segment
		(start 26.0604 -113.8936)
		(end 26.6446 -113.3094)
		(width 0.17145)
		(layer "F.Cu")
		(net "DUALPORTEN#13")
	)
	(segment
		(start 29.0322 -113.3094)
		(end 29.4132 -112.9284)
		(width 0.17145)
		(layer "F.Cu")
		(net "DUALPORTEN#13")
	)
	(segment
		(start 24.0538 -113.8936)
		(end 26.0604 -113.8936)
		(width 0.17145)
		(layer "F.Cu")
		(net "DUALPORTEN#13")
	)
	(via
		(at 29.4132 -112.9284)
		(size 0.7112)
		(drill 0.3556)
		(layers "F.Cu" "B.Cu")
		(net "DUALPORTEN#13")
	)
	(segment
		(start 31.051754 -215.644984)
		(end 29.820616 -215.644984)
		(width 0.17145)
		(layer "F.Cu")
		(net "DUALPORTEN#12")
	)
	(segment
		(start 31.051754 -215.644984)
		(end 32.193484 -215.644984)
		(width 0.17145)
		(layer "F.Cu")
		(net "DUALPORTEN#12")
	)
	(segment
		(start 29.820616 -215.644984)
		(end 29.718 -215.7476)
		(width 0.17145)
		(layer "F.Cu")
		(net "DUALPORTEN#12")
	)
	(segment
		(start 23.79853 -216.60993)
		(end 22.800056 -216.60993)
		(width 0.17145)
		(layer "F.Cu")
		(net "DUALPORTEN#12")
	)
	(segment
		(start 29.1846 -216.281)
		(end 26.4414 -216.281)
		(width 0.17145)
		(layer "F.Cu")
		(net "DUALPORTEN#12")
	)
	(segment
		(start 29.718 -215.7476)
		(end 29.1846 -216.281)
		(width 0.17145)
		(layer "F.Cu")
		(net "DUALPORTEN#12")
	)
	(segment
		(start 26.4414 -216.281)
		(end 25.7556 -216.9668)
		(width 0.17145)
		(layer "F.Cu")
		(net "DUALPORTEN#12")
	)
	(segment
		(start 32.193484 -215.644984)
		(end 32.2072 -215.6587)
		(width 0.17145)
		(layer "F.Cu")
		(net "DUALPORTEN#12")
	)
	(segment
		(start 25.7556 -216.9668)
		(end 24.1554 -216.9668)
		(width 0.17145)
		(layer "F.Cu")
		(net "DUALPORTEN#12")
	)
	(segment
		(start 24.1554 -216.9668)
		(end 23.79853 -216.60993)
		(width 0.17145)
		(layer "F.Cu")
		(net "DUALPORTEN#12")
	)
	(via
		(at 29.718 -215.7476)
		(size 0.7112)
		(drill 0.3556)
		(layers "F.Cu" "B.Cu")
		(net "DUALPORTEN#12")
	)
	(segment
		(start 26.4922 -319.2526)
		(end 29.1846 -319.2526)
		(width 0.17145)
		(layer "F.Cu")
		(net "DUALPORTEN#11")
	)
	(segment
		(start 29.5529 -318.9097)
		(end 29.5402 -318.897)
		(width 0.17145)
		(layer "F.Cu")
		(net "DUALPORTEN#11")
	)
	(segment
		(start 23.852378 -319.609978)
		(end 24.1554 -319.913)
		(width 0.17145)
		(layer "F.Cu")
		(net "DUALPORTEN#11")
	)
	(segment
		(start 29.1846 -319.2526)
		(end 29.5402 -318.897)
		(width 0.17145)
		(layer "F.Cu")
		(net "DUALPORTEN#11")
	)
	(segment
		(start 30.861 -318.9097)
		(end 32.004 -318.9097)
		(width 0.17145)
		(layer "F.Cu")
		(net "DUALPORTEN#11")
	)
	(segment
		(start 30.861 -318.9097)
		(end 29.5529 -318.9097)
		(width 0.17145)
		(layer "F.Cu")
		(net "DUALPORTEN#11")
	)
	(segment
		(start 24.1554 -319.913)
		(end 25.8318 -319.913)
		(width 0.17145)
		(layer "F.Cu")
		(net "DUALPORTEN#11")
	)
	(segment
		(start 22.800056 -319.609978)
		(end 23.852378 -319.609978)
		(width 0.17145)
		(layer "F.Cu")
		(net "DUALPORTEN#11")
	)
	(segment
		(start 25.8318 -319.913)
		(end 26.4922 -319.2526)
		(width 0.17145)
		(layer "F.Cu")
		(net "DUALPORTEN#11")
	)
	(via
		(at 29.5402 -318.897)
		(size 0.7112)
		(drill 0.3556)
		(layers "F.Cu" "B.Cu")
		(net "DUALPORTEN#11")
	)
	(segment
		(start 30.9753 -421.9575)
		(end 32.2326 -421.9575)
		(width 0.17145)
		(layer "F.Cu")
		(net "DUALPORTEN#10")
	)
	(segment
		(start 29.718 -421.9575)
		(end 29.4005 -422.275)
		(width 0.17145)
		(layer "F.Cu")
		(net "DUALPORTEN#10")
	)
	(segment
		(start 26.8732 -422.275)
		(end 26.1874 -422.9608)
		(width 0.17145)
		(layer "F.Cu")
		(net "DUALPORTEN#10")
	)
	(segment
		(start 26.1874 -422.9608)
		(end 24.090122 -422.9608)
		(width 0.17145)
		(layer "F.Cu")
		(net "DUALPORTEN#10")
	)
	(segment
		(start 23.739348 -422.610026)
		(end 22.800056 -422.610026)
		(width 0.17145)
		(layer "F.Cu")
		(net "DUALPORTEN#10")
	)
	(segment
		(start 30.9753 -421.9575)
		(end 29.718 -421.9575)
		(width 0.17145)
		(layer "F.Cu")
		(net "DUALPORTEN#10")
	)
	(segment
		(start 29.4005 -422.275)
		(end 26.8732 -422.275)
		(width 0.17145)
		(layer "F.Cu")
		(net "DUALPORTEN#10")
	)
	(segment
		(start 24.090122 -422.9608)
		(end 23.739348 -422.610026)
		(width 0.17145)
		(layer "F.Cu")
		(net "DUALPORTEN#10")
	)
	(via
		(at 30.9753 -421.9575)
		(size 0.7112)
		(drill 0.3556)
		(layers "F.Cu" "B.Cu")
		(net "DUALPORTEN#10")
	)
	(segment
		(start 217.297 -393.1285)
		(end 216.0397 -393.1285)
		(width 0.17145)
		(layer "F.Cu")
		(net "DUALPORTEN#1")
	)
	(segment
		(start 220.218 -392.684)
		(end 220.511878 -392.390122)
		(width 0.17145)
		(layer "F.Cu")
		(net "DUALPORTEN#1")
	)
	(segment
		(start 217.7415 -392.684)
		(end 220.218 -392.684)
		(width 0.17145)
		(layer "F.Cu")
		(net "DUALPORTEN#1")
	)
	(segment
		(start 220.511878 -392.390122)
		(end 224.199958 -392.390122)
		(width 0.17145)
		(layer "F.Cu")
		(net "DUALPORTEN#1")
	)
	(segment
		(start 216.0397 -393.1285)
		(end 214.7824 -393.1285)
		(width 0.17145)
		(layer "F.Cu")
		(net "DUALPORTEN#1")
	)
	(segment
		(start 217.297 -393.1285)
		(end 217.7415 -392.684)
		(width 0.17145)
		(layer "F.Cu")
		(net "DUALPORTEN#1")
	)
	(via
		(at 216.0397 -393.1285)
		(size 0.7112)
		(drill 0.3556)
		(layers "F.Cu" "B.Cu")
		(net "DUALPORTEN#1")
	)
	(segment
		(start 217.6526 -494.6904)
		(end 218.3892 -493.9538)
		(width 0.17145)
		(layer "F.Cu")
		(net "DUALPORTEN#0")
	)
	(segment
		(start 222.847916 -495.389916)
		(end 224.199704 -495.389916)
		(width 0.17145)
		(layer "F.Cu")
		(net "DUALPORTEN#0")
	)
	(segment
		(start 224.199704 -495.389916)
		(end 224.199958 -495.39017)
		(width 0.17145)
		(layer "F.Cu")
		(net "DUALPORTEN#0")
	)
	(segment
		(start 217.1192 -495.2238)
		(end 217.6526 -494.6904)
		(width 0.17145)
		(layer "F.Cu")
		(net "DUALPORTEN#0")
	)
	(segment
		(start 218.3892 -493.9538)
		(end 220.534992 -493.9538)
		(width 0.17145)
		(layer "F.Cu")
		(net "DUALPORTEN#0")
	)
	(segment
		(start 216.2429 -494.0808)
		(end 216.2429 -495.2238)
		(width 0.17145)
		(layer "F.Cu")
		(net "DUALPORTEN#0")
	)
	(segment
		(start 220.534992 -493.9538)
		(end 221.601792 -495.0206)
		(width 0.17145)
		(layer "F.Cu")
		(net "DUALPORTEN#0")
	)
	(segment
		(start 216.2429 -495.2238)
		(end 217.1192 -495.2238)
		(width 0.17145)
		(layer "F.Cu")
		(net "DUALPORTEN#0")
	)
	(segment
		(start 222.4786 -495.0206)
		(end 222.847916 -495.389916)
		(width 0.17145)
		(layer "F.Cu")
		(net "DUALPORTEN#0")
	)
	(segment
		(start 221.601792 -495.0206)
		(end 222.4786 -495.0206)
		(width 0.17145)
		(layer "F.Cu")
		(net "DUALPORTEN#0")
	)
	(via
		(at 217.6526 -494.6904)
		(size 0.7112)
		(drill 0.3556)
		(layers "F.Cu" "B.Cu")
		(net "DUALPORTEN#0")
	)
	(segment
		(start 42.76979 -42.680128)
		(end 42.571924 -42.877994)
		(width 0.17145)
		(layer "F.Cu")
		(net "ATTN_LED_DR9_MOS_N")
	)
	(segment
		(start 35.1409 -39.6875)
		(end 34.671 -39.6875)
		(width 0.17145)
		(layer "F.Cu")
		(net "ATTN_LED_DR9_MOS_N")
	)
	(segment
		(start 36.959794 -41.506394)
		(end 35.1409 -39.6875)
		(width 0.17145)
		(layer "F.Cu")
		(net "ATTN_LED_DR9_MOS_N")
	)
	(segment
		(start 40.258238 -41.506394)
		(end 36.959794 -41.506394)
		(width 0.17145)
		(layer "F.Cu")
		(net "ATTN_LED_DR9_MOS_N")
	)
	(segment
		(start 42.76979 -41.506394)
		(end 42.76979 -42.680128)
		(width 0.17145)
		(layer "F.Cu")
		(net "ATTN_LED_DR9_MOS_N")
	)
	(segment
		(start 41.629838 -42.877994)
		(end 40.258238 -41.506394)
		(width 0.17145)
		(layer "F.Cu")
		(net "ATTN_LED_DR9_MOS_N")
	)
	(segment
		(start 42.571924 -42.877994)
		(end 41.629838 -42.877994)
		(width 0.17145)
		(layer "F.Cu")
		(net "ATTN_LED_DR9_MOS_N")
	)
	(via
		(at 40.258238 -41.506394)
		(size 0.7112)
		(drill 0.3556)
		(layers "F.Cu" "B.Cu")
		(net "ATTN_LED_DR9_MOS_N")
	)
	(segment
		(start 51.601116 -37.23513)
		(end 51.601116 -35.421062)
		(width 0.17145)
		(layer "F.Cu")
		(net "ATTN_LED_DR9_AND_R")
	)
	(segment
		(start 49.2125 -34.29)
		(end 51.28768 -34.29)
		(width 0.17145)
		(layer "F.Cu")
		(net "ATTN_LED_DR9_AND_R")
	)
	(segment
		(start 51.601116 -34.603436)
		(end 51.601116 -35.421062)
		(width 0.17145)
		(layer "F.Cu")
		(net "ATTN_LED_DR9_AND_R")
	)
	(segment
		(start 49.62525 -37.6555)
		(end 51.180746 -37.6555)
		(width 0.17145)
		(layer "F.Cu")
		(net "ATTN_LED_DR9_AND_R")
	)
	(segment
		(start 51.28768 -34.29)
		(end 51.601116 -34.603436)
		(width 0.17145)
		(layer "F.Cu")
		(net "ATTN_LED_DR9_AND_R")
	)
	(segment
		(start 51.180746 -37.6555)
		(end 51.601116 -37.23513)
		(width 0.17145)
		(layer "F.Cu")
		(net "ATTN_LED_DR9_AND_R")
	)
	(via
		(at 51.601116 -35.421062)
		(size 0.7112)
		(drill 0.3556)
		(layers "F.Cu" "B.Cu")
		(net "ATTN_LED_DR9_AND_R")
	)
	(segment
		(start 43.867578 -34.516822)
		(end 44.0944 -34.29)
		(width 0.17145)
		(layer "F.Cu")
		(net "ATTN_LED_DR9_AND")
	)
	(segment
		(start 43.028616 -34.516822)
		(end 43.867578 -34.516822)
		(width 0.17145)
		(layer "F.Cu")
		(net "ATTN_LED_DR9_AND")
	)
	(segment
		(start 46.375828 -34.29)
		(end 48.3235 -34.29)
		(width 0.17145)
		(layer "F.Cu")
		(net "ATTN_LED_DR9_AND")
	)
	(segment
		(start 44.0944 -34.29)
		(end 46.375828 -34.29)
		(width 0.17145)
		(layer "F.Cu")
		(net "ATTN_LED_DR9_AND")
	)
	(via
		(at 46.375828 -34.29)
		(size 0.7112)
		(drill 0.3556)
		(layers "F.Cu" "B.Cu")
		(net "ATTN_LED_DR9_AND")
	)
	(segment
		(start 42.019728 -146.12239)
		(end 41.184576 -146.12239)
		(width 0.17145)
		(layer "F.Cu")
		(net "ATTN_LED_DR8_MOS_N")
	)
	(segment
		(start 34.29 -144.78)
		(end 32.893 -144.78)
		(width 0.17145)
		(layer "F.Cu")
		(net "ATTN_LED_DR8_MOS_N")
	)
	(segment
		(start 42.76979 -145.372328)
		(end 42.019728 -146.12239)
		(width 0.17145)
		(layer "F.Cu")
		(net "ATTN_LED_DR8_MOS_N")
	)
	(segment
		(start 42.76979 -144.506442)
		(end 42.76979 -145.372328)
		(width 0.17145)
		(layer "F.Cu")
		(net "ATTN_LED_DR8_MOS_N")
	)
	(segment
		(start 34.29 -144.78)
		(end 36.195 -146.685)
		(width 0.17145)
		(layer "F.Cu")
		(net "ATTN_LED_DR8_MOS_N")
	)
	(segment
		(start 40.621966 -146.685)
		(end 41.184576 -146.12239)
		(width 0.17145)
		(layer "F.Cu")
		(net "ATTN_LED_DR8_MOS_N")
	)
	(segment
		(start 32.893 -144.78)
		(end 31.877 -143.764)
		(width 0.17145)
		(layer "F.Cu")
		(net "ATTN_LED_DR8_MOS_N")
	)
	(segment
		(start 31.877 -143.764)
		(end 31.877 -143.1925)
		(width 0.17145)
		(layer "F.Cu")
		(net "ATTN_LED_DR8_MOS_N")
	)
	(segment
		(start 36.195 -146.685)
		(end 40.621966 -146.685)
		(width 0.17145)
		(layer "F.Cu")
		(net "ATTN_LED_DR8_MOS_N")
	)
	(via
		(at 34.29 -144.78)
		(size 0.7112)
		(drill 0.3556)
		(layers "F.Cu" "B.Cu")
		(net "ATTN_LED_DR8_MOS_N")
	)
	(segment
		(start 45.320458 -141.309852)
		(end 45.32249 -141.30782)
		(width 0.17145)
		(layer "F.Cu")
		(net "ATTN_LED_DR8_AND_R")
	)
	(segment
		(start 53.2765 -141.00175)
		(end 49.276 -141.00175)
		(width 0.17145)
		(layer "F.Cu")
		(net "ATTN_LED_DR8_AND_R")
	)
	(segment
		(start 47.21098 -141.30782)
		(end 47.51705 -141.00175)
		(width 0.17145)
		(layer "F.Cu")
		(net "ATTN_LED_DR8_AND_R")
	)
	(segment
		(start 43.89501 -141.30782)
		(end 43.897042 -141.309852)
		(width 0.17145)
		(layer "F.Cu")
		(net "ATTN_LED_DR8_AND_R")
	)
	(segment
		(start 43.897042 -141.309852)
		(end 45.320458 -141.309852)
		(width 0.17145)
		(layer "F.Cu")
		(net "ATTN_LED_DR8_AND_R")
	)
	(segment
		(start 47.51705 -141.00175)
		(end 49.276 -141.00175)
		(width 0.17145)
		(layer "F.Cu")
		(net "ATTN_LED_DR8_AND_R")
	)
	(segment
		(start 45.611542 -141.309852)
		(end 47.161958 -141.309852)
		(width 0.17145)
		(layer "F.Cu")
		(net "ATTN_LED_DR8_AND_R")
	)
	(segment
		(start 45.32249 -141.30782)
		(end 45.60951 -141.30782)
		(width 0.17145)
		(layer "F.Cu")
		(net "ATTN_LED_DR8_AND_R")
	)
	(segment
		(start 45.60951 -141.30782)
		(end 45.611542 -141.309852)
		(width 0.17145)
		(layer "F.Cu")
		(net "ATTN_LED_DR8_AND_R")
	)
	(segment
		(start 47.161958 -141.309852)
		(end 47.16399 -141.30782)
		(width 0.17145)
		(layer "F.Cu")
		(net "ATTN_LED_DR8_AND_R")
	)
	(segment
		(start 43.3705 -141.30782)
		(end 43.89501 -141.30782)
		(width 0.17145)
		(layer "F.Cu")
		(net "ATTN_LED_DR8_AND_R")
	)
	(segment
		(start 47.16399 -141.30782)
		(end 47.21098 -141.30782)
		(width 0.17145)
		(layer "F.Cu")
		(net "ATTN_LED_DR8_AND_R")
	)
	(via
		(at 49.276 -141.00175)
		(size 0.7112)
		(drill 0.3556)
		(layers "F.Cu" "B.Cu")
		(net "ATTN_LED_DR8_AND_R")
	)
	(segment
		(start 41.67378 -141.30782)
		(end 41.2242 -141.7574)
		(width 0.17145)
		(layer "F.Cu")
		(net "ATTN_LED_DR8_AND")
	)
	(segment
		(start 40.4495 -143.0655)
		(end 41.2242 -142.2908)
		(width 0.17145)
		(layer "F.Cu")
		(net "ATTN_LED_DR8_AND")
	)
	(segment
		(start 42.4815 -141.30782)
		(end 41.67378 -141.30782)
		(width 0.17145)
		(layer "F.Cu")
		(net "ATTN_LED_DR8_AND")
	)
	(segment
		(start 41.2242 -142.2908)
		(end 41.2242 -141.7574)
		(width 0.17145)
		(layer "F.Cu")
		(net "ATTN_LED_DR8_AND")
	)
	(segment
		(start 39.63924 -143.0655)
		(end 40.4495 -143.0655)
		(width 0.17145)
		(layer "F.Cu")
		(net "ATTN_LED_DR8_AND")
	)
	(via
		(at 41.2242 -141.7574)
		(size 0.7112)
		(drill 0.3556)
		(layers "F.Cu" "B.Cu")
		(net "ATTN_LED_DR8_AND")
	)
	(segment
		(start 38.1 -242.57)
		(end 39.868348 -240.801652)
		(width 0.17145)
		(layer "F.Cu")
		(net "ATTN_LED_DR7_MOS_N")
	)
	(segment
		(start 36.45408 -243.575332)
		(end 36.45408 -246.690388)
		(width 0.17145)
		(layer "F.Cu")
		(net "ATTN_LED_DR7_MOS_N")
	)
	(segment
		(start 39.868348 -240.801652)
		(end 44.440348 -240.801652)
		(width 0.17145)
		(layer "F.Cu")
		(net "ATTN_LED_DR7_MOS_N")
	)
	(segment
		(start 42.76979 -248.824496)
		(end 42.74312 -248.851166)
		(width 0.17145)
		(layer "F.Cu")
		(net "ATTN_LED_DR7_MOS_N")
	)
	(segment
		(start 37.459412 -242.57)
		(end 36.45408 -243.575332)
		(width 0.17145)
		(layer "F.Cu")
		(net "ATTN_LED_DR7_MOS_N")
	)
	(segment
		(start 44.440348 -240.801652)
		(end 46.4566 -238.7854)
		(width 0.17145)
		(layer "F.Cu")
		(net "ATTN_LED_DR7_MOS_N")
	)
	(segment
		(start 42.76979 -247.50649)
		(end 42.76979 -248.824496)
		(width 0.17145)
		(layer "F.Cu")
		(net "ATTN_LED_DR7_MOS_N")
	)
	(segment
		(start 38.1 -242.57)
		(end 37.459412 -242.57)
		(width 0.17145)
		(layer "F.Cu")
		(net "ATTN_LED_DR7_MOS_N")
	)
	(segment
		(start 46.4566 -238.7854)
		(end 55.1434 -238.7854)
		(width 0.17145)
		(layer "F.Cu")
		(net "ATTN_LED_DR7_MOS_N")
	)
	(segment
		(start 42.094658 -249.824748)
		(end 42.74312 -249.176286)
		(width 0.17145)
		(layer "F.Cu")
		(net "ATTN_LED_DR7_MOS_N")
	)
	(segment
		(start 36.45408 -246.690388)
		(end 39.58844 -249.824748)
		(width 0.17145)
		(layer "F.Cu")
		(net "ATTN_LED_DR7_MOS_N")
	)
	(segment
		(start 42.74312 -249.176286)
		(end 42.74312 -248.851166)
		(width 0.17145)
		(layer "F.Cu")
		(net "ATTN_LED_DR7_MOS_N")
	)
	(segment
		(start 55.753 -239.395)
		(end 55.753 -240.087658)
		(width 0.17145)
		(layer "F.Cu")
		(net "ATTN_LED_DR7_MOS_N")
	)
	(segment
		(start 39.58844 -249.824748)
		(end 42.094658 -249.824748)
		(width 0.17145)
		(layer "F.Cu")
		(net "ATTN_LED_DR7_MOS_N")
	)
	(segment
		(start 55.1434 -238.7854)
		(end 55.753 -239.395)
		(width 0.17145)
		(layer "F.Cu")
		(net "ATTN_LED_DR7_MOS_N")
	)
	(via
		(at 38.1 -242.57)
		(size 0.7112)
		(drill 0.3556)
		(layers "F.Cu" "B.Cu")
		(net "ATTN_LED_DR7_MOS_N")
	)
	(segment
		(start 43.047158 -245.618)
		(end 38.7604 -245.618)
		(width 0.17145)
		(layer "F.Cu")
		(net "ATTN_LED_DR7_AND_R")
	)
	(segment
		(start 43.555158 -245.11)
		(end 43.047158 -245.618)
		(width 0.17145)
		(layer "F.Cu")
		(net "ATTN_LED_DR7_AND_R")
	)
	(segment
		(start 43.936158 -244.729)
		(end 43.555158 -245.11)
		(width 0.17145)
		(layer "F.Cu")
		(net "ATTN_LED_DR7_AND_R")
	)
	(segment
		(start 38.7604 -245.618)
		(end 37.9349 -244.7925)
		(width 0.17145)
		(layer "F.Cu")
		(net "ATTN_LED_DR7_AND_R")
	)
	(segment
		(start 44.8945 -244.729)
		(end 43.936158 -244.729)
		(width 0.17145)
		(layer "F.Cu")
		(net "ATTN_LED_DR7_AND_R")
	)
	(segment
		(start 37.9349 -244.7925)
		(end 37.49675 -244.7925)
		(width 0.17145)
		(layer "F.Cu")
		(net "ATTN_LED_DR7_AND_R")
	)
	(via
		(at 43.555158 -245.11)
		(size 0.7112)
		(drill 0.3556)
		(layers "F.Cu" "B.Cu")
		(net "ATTN_LED_DR7_AND_R")
	)
	(segment
		(start 45.9867 -244.9322)
		(end 45.7835 -244.729)
		(width 0.17145)
		(layer "F.Cu")
		(net "ATTN_LED_DR7_AND")
	)
	(segment
		(start 48.91024 -242.8875)
		(end 48.91024 -244.53596)
		(width 0.17145)
		(layer "F.Cu")
		(net "ATTN_LED_DR7_AND")
	)
	(segment
		(start 48.514 -244.9322)
		(end 45.9867 -244.9322)
		(width 0.17145)
		(layer "F.Cu")
		(net "ATTN_LED_DR7_AND")
	)
	(segment
		(start 48.91024 -244.53596)
		(end 48.514 -244.9322)
		(width 0.17145)
		(layer "F.Cu")
		(net "ATTN_LED_DR7_AND")
	)
	(via
		(at 48.514 -244.9322)
		(size 0.7112)
		(drill 0.3556)
		(layers "F.Cu" "B.Cu")
		(net "ATTN_LED_DR7_AND")
	)
	(segment
		(start 42.76979 -351.678748)
		(end 42.576496 -351.872042)
		(width 0.17145)
		(layer "F.Cu")
		(net "ATTN_LED_DR6_MOS_N")
	)
	(segment
		(start 37.759894 -350.506284)
		(end 35.687 -348.43339)
		(width 0.17145)
		(layer "F.Cu")
		(net "ATTN_LED_DR6_MOS_N")
	)
	(segment
		(start 41.623996 -351.872042)
		(end 40.258238 -350.506284)
		(width 0.17145)
		(layer "F.Cu")
		(net "ATTN_LED_DR6_MOS_N")
	)
	(segment
		(start 40.258238 -350.506284)
		(end 37.759894 -350.506284)
		(width 0.17145)
		(layer "F.Cu")
		(net "ATTN_LED_DR6_MOS_N")
	)
	(segment
		(start 42.576496 -351.872042)
		(end 41.623996 -351.872042)
		(width 0.17145)
		(layer "F.Cu")
		(net "ATTN_LED_DR6_MOS_N")
	)
	(segment
		(start 42.76979 -350.506284)
		(end 42.76979 -351.678748)
		(width 0.17145)
		(layer "F.Cu")
		(net "ATTN_LED_DR6_MOS_N")
	)
	(via
		(at 40.258238 -350.506284)
		(size 0.7112)
		(drill 0.3556)
		(layers "F.Cu" "B.Cu")
		(net "ATTN_LED_DR6_MOS_N")
	)
	(segment
		(start 51.1048 -342.338152)
		(end 51.1048 -343.7636)
		(width 0.17145)
		(layer "F.Cu")
		(net "ATTN_LED_DR6_AND_R")
	)
	(segment
		(start 51.1048 -343.7636)
		(end 49.791366 -345.077034)
		(width 0.17145)
		(layer "F.Cu")
		(net "ATTN_LED_DR6_AND_R")
	)
	(segment
		(start 49.505616 -342.007952)
		(end 50.7746 -342.007952)
		(width 0.17145)
		(layer "F.Cu")
		(net "ATTN_LED_DR6_AND_R")
	)
	(segment
		(start 49.791366 -345.077034)
		(end 49.791366 -345.754452)
		(width 0.17145)
		(layer "F.Cu")
		(net "ATTN_LED_DR6_AND_R")
	)
	(segment
		(start 50.7746 -342.007952)
		(end 51.1048 -342.338152)
		(width 0.17145)
		(layer "F.Cu")
		(net "ATTN_LED_DR6_AND_R")
	)
	(via
		(at 50.7746 -342.007952)
		(size 0.7112)
		(drill 0.3556)
		(layers "F.Cu" "B.Cu")
		(net "ATTN_LED_DR6_AND_R")
	)
	(segment
		(start 44.087288 -343.262712)
		(end 45.3136 -342.0364)
		(width 0.17145)
		(layer "F.Cu")
		(net "ATTN_LED_DR6_AND")
	)
	(segment
		(start 45.3136 -342.0364)
		(end 47.2694 -342.0364)
		(width 0.17145)
		(layer "F.Cu")
		(net "ATTN_LED_DR6_AND")
	)
	(segment
		(start 43.028616 -343.262712)
		(end 44.087288 -343.262712)
		(width 0.17145)
		(layer "F.Cu")
		(net "ATTN_LED_DR6_AND")
	)
	(segment
		(start 47.297848 -342.007952)
		(end 47.2694 -342.0364)
		(width 0.17145)
		(layer "F.Cu")
		(net "ATTN_LED_DR6_AND")
	)
	(segment
		(start 48.616616 -342.007952)
		(end 47.297848 -342.007952)
		(width 0.17145)
		(layer "F.Cu")
		(net "ATTN_LED_DR6_AND")
	)
	(via
		(at 47.2694 -342.0364)
		(size 0.7112)
		(drill 0.3556)
		(layers "F.Cu" "B.Cu")
		(net "ATTN_LED_DR6_AND")
	)
	(segment
		(start 42.530268 -454.835768)
		(end 41.706546 -454.835768)
		(width 0.17145)
		(layer "F.Cu")
		(net "ATTN_LED_DR5_MOS_N")
	)
	(segment
		(start 41.706546 -454.835768)
		(end 40.79875 -453.927972)
		(width 0.17145)
		(layer "F.Cu")
		(net "ATTN_LED_DR5_MOS_N")
	)
	(segment
		(start 42.76979 -453.506332)
		(end 42.76979 -454.596246)
		(width 0.17145)
		(layer "F.Cu")
		(net "ATTN_LED_DR5_MOS_N")
	)
	(segment
		(start 42.76979 -454.596246)
		(end 42.530268 -454.835768)
		(width 0.17145)
		(layer "F.Cu")
		(net "ATTN_LED_DR5_MOS_N")
	)
	(segment
		(start 47.371 -444.246)
		(end 43.562524 -448.054476)
		(width 0.17145)
		(layer "F.Cu")
		(net "ATTN_LED_DR5_MOS_N")
	)
	(segment
		(start 40.79875 -453.927972)
		(end 40.79875 -450.81825)
		(width 0.17145)
		(layer "F.Cu")
		(net "ATTN_LED_DR5_MOS_N")
	)
	(segment
		(start 57.9755 -444.246)
		(end 47.371 -444.246)
		(width 0.17145)
		(layer "F.Cu")
		(net "ATTN_LED_DR5_MOS_N")
	)
	(segment
		(start 59.817 -446.0875)
		(end 57.9755 -444.246)
		(width 0.17145)
		(layer "F.Cu")
		(net "ATTN_LED_DR5_MOS_N")
	)
	(segment
		(start 40.79875 -450.81825)
		(end 43.562524 -448.054476)
		(width 0.17145)
		(layer "F.Cu")
		(net "ATTN_LED_DR5_MOS_N")
	)
	(via
		(at 43.562524 -448.054476)
		(size 0.7112)
		(drill 0.3556)
		(layers "F.Cu" "B.Cu")
		(net "ATTN_LED_DR5_MOS_N")
	)
	(segment
		(start 44.45 -450.723)
		(end 44.138342 -450.411342)
		(width 0.17145)
		(layer "F.Cu")
		(net "ATTN_LED_DR5_AND_R")
	)
	(segment
		(start 44.138342 -450.411342)
		(end 44.138342 -449.952364)
		(width 0.17145)
		(layer "F.Cu")
		(net "ATTN_LED_DR5_AND_R")
	)
	(segment
		(start 45.319442 -448.771264)
		(end 46.403768 -448.771264)
		(width 0.17145)
		(layer "F.Cu")
		(net "ATTN_LED_DR5_AND_R")
	)
	(segment
		(start 44.138342 -449.952364)
		(end 45.319442 -448.771264)
		(width 0.17145)
		(layer "F.Cu")
		(net "ATTN_LED_DR5_AND_R")
	)
	(segment
		(start 46.125384 -450.723)
		(end 44.45 -450.723)
		(width 0.17145)
		(layer "F.Cu")
		(net "ATTN_LED_DR5_AND_R")
	)
	(segment
		(start 46.403768 -448.771264)
		(end 47.776384 -447.398648)
		(width 0.17145)
		(layer "F.Cu")
		(net "ATTN_LED_DR5_AND_R")
	)
	(segment
		(start 47.776384 -447.398648)
		(end 47.776384 -446.94475)
		(width 0.17145)
		(layer "F.Cu")
		(net "ATTN_LED_DR5_AND_R")
	)
	(via
		(at 44.45 -450.723)
		(size 0.7112)
		(drill 0.3556)
		(layers "F.Cu" "B.Cu")
		(net "ATTN_LED_DR5_AND_R")
	)
	(segment
		(start 47.014384 -450.723)
		(end 47.338996 -450.723)
		(width 0.17145)
		(layer "F.Cu")
		(net "ATTN_LED_DR5_AND")
	)
	(segment
		(start 49.728628 -451.257162)
		(end 50.24755 -450.73824)
		(width 0.17145)
		(layer "F.Cu")
		(net "ATTN_LED_DR5_AND")
	)
	(segment
		(start 50.24755 -450.73824)
		(end 51.078384 -450.73824)
		(width 0.17145)
		(layer "F.Cu")
		(net "ATTN_LED_DR5_AND")
	)
	(segment
		(start 47.338996 -450.723)
		(end 47.873158 -451.257162)
		(width 0.17145)
		(layer "F.Cu")
		(net "ATTN_LED_DR5_AND")
	)
	(segment
		(start 48.327564 -451.257162)
		(end 49.728628 -451.257162)
		(width 0.17145)
		(layer "F.Cu")
		(net "ATTN_LED_DR5_AND")
	)
	(segment
		(start 47.873158 -451.257162)
		(end 48.327564 -451.257162)
		(width 0.17145)
		(layer "F.Cu")
		(net "ATTN_LED_DR5_AND")
	)
	(via
		(at 48.327564 -451.257162)
		(size 0.7112)
		(drill 0.3556)
		(layers "F.Cu" "B.Cu")
		(net "ATTN_LED_DR5_AND")
	)
	(segment
		(start 223.266 -43.053)
		(end 223.696022 -43.483022)
		(width 0.17145)
		(layer "F.Cu")
		(net "ATTN_LED_DR4_MOS_N")
	)
	(segment
		(start 227.769674 -41.506394)
		(end 227.098606 -41.506394)
		(width 0.17145)
		(layer "F.Cu")
		(net "ATTN_LED_DR4_MOS_N")
	)
	(segment
		(start 226.203764 -42.892472)
		(end 226.203764 -42.761916)
		(width 0.17145)
		(layer "F.Cu")
		(net "ATTN_LED_DR4_MOS_N")
	)
	(segment
		(start 227.098606 -41.506394)
		(end 226.822 -41.783)
		(width 0.17145)
		(layer "F.Cu")
		(net "ATTN_LED_DR4_MOS_N")
	)
	(segment
		(start 222.544894 -41.506394)
		(end 222.544894 -42.331894)
		(width 0.17145)
		(layer "F.Cu")
		(net "ATTN_LED_DR4_MOS_N")
	)
	(segment
		(start 226.822 -41.783)
		(end 226.822 -42.14368)
		(width 0.17145)
		(layer "F.Cu")
		(net "ATTN_LED_DR4_MOS_N")
	)
	(segment
		(start 225.613214 -43.483022)
		(end 226.203764 -42.892472)
		(width 0.17145)
		(layer "F.Cu")
		(net "ATTN_LED_DR4_MOS_N")
	)
	(segment
		(start 223.696022 -43.483022)
		(end 225.613214 -43.483022)
		(width 0.17145)
		(layer "F.Cu")
		(net "ATTN_LED_DR4_MOS_N")
	)
	(segment
		(start 222.544894 -42.331894)
		(end 223.266 -43.053)
		(width 0.17145)
		(layer "F.Cu")
		(net "ATTN_LED_DR4_MOS_N")
	)
	(segment
		(start 226.822 -42.14368)
		(end 226.203764 -42.761916)
		(width 0.17145)
		(layer "F.Cu")
		(net "ATTN_LED_DR4_MOS_N")
	)
	(via
		(at 223.266 -43.053)
		(size 0.7112)
		(drill 0.3556)
		(layers "F.Cu" "B.Cu")
		(net "ATTN_LED_DR4_MOS_N")
	)
	(segment
		(start 235.585 -33.008062)
		(end 236.601 -34.024062)
		(width 0.17145)
		(layer "F.Cu")
		(net "ATTN_LED_DR4_AND_R")
	)
	(segment
		(start 236.0295 -36.754562)
		(end 234.79125 -36.754562)
		(width 0.17145)
		(layer "F.Cu")
		(net "ATTN_LED_DR4_AND_R")
	)
	(segment
		(start 236.601 -35.421062)
		(end 236.601 -36.183062)
		(width 0.17145)
		(layer "F.Cu")
		(net "ATTN_LED_DR4_AND_R")
	)
	(segment
		(start 236.601 -36.183062)
		(end 236.0295 -36.754562)
		(width 0.17145)
		(layer "F.Cu")
		(net "ATTN_LED_DR4_AND_R")
	)
	(segment
		(start 234.5055 -33.008062)
		(end 235.585 -33.008062)
		(width 0.17145)
		(layer "F.Cu")
		(net "ATTN_LED_DR4_AND_R")
	)
	(segment
		(start 236.601 -34.024062)
		(end 236.601 -35.421062)
		(width 0.17145)
		(layer "F.Cu")
		(net "ATTN_LED_DR4_AND_R")
	)
	(via
		(at 236.601 -35.421062)
		(size 0.7112)
		(drill 0.3556)
		(layers "F.Cu" "B.Cu")
		(net "ATTN_LED_DR4_AND_R")
	)
	(segment
		(start 229.32263 -34.262822)
		(end 228.2825 -34.262822)
		(width 0.17145)
		(layer "F.Cu")
		(net "ATTN_LED_DR4_AND")
	)
	(segment
		(start 231.109774 -33.52546)
		(end 230.059992 -33.52546)
		(width 0.17145)
		(layer "F.Cu")
		(net "ATTN_LED_DR4_AND")
	)
	(segment
		(start 232.4989 -33.008062)
		(end 233.6165 -33.008062)
		(width 0.17145)
		(layer "F.Cu")
		(net "ATTN_LED_DR4_AND")
	)
	(segment
		(start 230.059992 -33.52546)
		(end 229.32263 -34.262822)
		(width 0.17145)
		(layer "F.Cu")
		(net "ATTN_LED_DR4_AND")
	)
	(segment
		(start 231.109774 -33.52546)
		(end 231.981502 -33.52546)
		(width 0.17145)
		(layer "F.Cu")
		(net "ATTN_LED_DR4_AND")
	)
	(segment
		(start 231.981502 -33.52546)
		(end 232.4989 -33.008062)
		(width 0.17145)
		(layer "F.Cu")
		(net "ATTN_LED_DR4_AND")
	)
	(via
		(at 231.109774 -33.52546)
		(size 0.7112)
		(drill 0.3556)
		(layers "F.Cu" "B.Cu")
		(net "ATTN_LED_DR4_AND")
	)
	(segment
		(start 227.769674 -144.506442)
		(end 227.769674 -145.698718)
		(width 0.17145)
		(layer "F.Cu")
		(net "ATTN_LED_DR3_MOS_N")
	)
	(segment
		(start 222.123 -143.88211)
		(end 222.123 -143.05661)
		(width 0.17145)
		(layer "F.Cu")
		(net "ATTN_LED_DR3_MOS_N")
	)
	(segment
		(start 225.258122 -144.506442)
		(end 222.747332 -144.506442)
		(width 0.17145)
		(layer "F.Cu")
		(net "ATTN_LED_DR3_MOS_N")
	)
	(segment
		(start 222.747332 -144.506442)
		(end 222.123 -143.88211)
		(width 0.17145)
		(layer "F.Cu")
		(net "ATTN_LED_DR3_MOS_N")
	)
	(segment
		(start 227.769674 -145.698718)
		(end 227.565204 -145.903188)
		(width 0.17145)
		(layer "F.Cu")
		(net "ATTN_LED_DR3_MOS_N")
	)
	(segment
		(start 226.654868 -145.903188)
		(end 225.258122 -144.506442)
		(width 0.17145)
		(layer "F.Cu")
		(net "ATTN_LED_DR3_MOS_N")
	)
	(segment
		(start 227.565204 -145.903188)
		(end 226.654868 -145.903188)
		(width 0.17145)
		(layer "F.Cu")
		(net "ATTN_LED_DR3_MOS_N")
	)
	(via
		(at 225.258122 -144.506442)
		(size 0.7112)
		(drill 0.3556)
		(layers "F.Cu" "B.Cu")
		(net "ATTN_LED_DR3_MOS_N")
	)
	(segment
		(start 234.5055 -136.00811)
		(end 235.585 -136.00811)
		(width 0.17145)
		(layer "F.Cu")
		(net "ATTN_LED_DR3_AND_R")
	)
	(segment
		(start 236.0295 -139.75461)
		(end 234.79125 -139.75461)
		(width 0.17145)
		(layer "F.Cu")
		(net "ATTN_LED_DR3_AND_R")
	)
	(segment
		(start 236.601 -138.42111)
		(end 236.601 -139.18311)
		(width 0.17145)
		(layer "F.Cu")
		(net "ATTN_LED_DR3_AND_R")
	)
	(segment
		(start 236.601 -137.02411)
		(end 236.601 -138.42111)
		(width 0.17145)
		(layer "F.Cu")
		(net "ATTN_LED_DR3_AND_R")
	)
	(segment
		(start 236.601 -139.18311)
		(end 236.0295 -139.75461)
		(width 0.17145)
		(layer "F.Cu")
		(net "ATTN_LED_DR3_AND_R")
	)
	(segment
		(start 235.585 -136.00811)
		(end 236.601 -137.02411)
		(width 0.17145)
		(layer "F.Cu")
		(net "ATTN_LED_DR3_AND_R")
	)
	(via
		(at 236.601 -138.42111)
		(size 0.7112)
		(drill 0.3556)
		(layers "F.Cu" "B.Cu")
		(net "ATTN_LED_DR3_AND_R")
	)
	(segment
		(start 232.32745 -136.356598)
		(end 230.502968 -136.356598)
		(width 0.17145)
		(layer "F.Cu")
		(net "ATTN_LED_DR3_AND")
	)
	(segment
		(start 229.974902 -136.356598)
		(end 229.06863 -137.26287)
		(width 0.17145)
		(layer "F.Cu")
		(net "ATTN_LED_DR3_AND")
	)
	(segment
		(start 230.502968 -136.356598)
		(end 229.974902 -136.356598)
		(width 0.17145)
		(layer "F.Cu")
		(net "ATTN_LED_DR3_AND")
	)
	(segment
		(start 233.6165 -136.00811)
		(end 232.675938 -136.00811)
		(width 0.17145)
		(layer "F.Cu")
		(net "ATTN_LED_DR3_AND")
	)
	(segment
		(start 229.06863 -137.26287)
		(end 228.0285 -137.26287)
		(width 0.17145)
		(layer "F.Cu")
		(net "ATTN_LED_DR3_AND")
	)
	(segment
		(start 232.675938 -136.00811)
		(end 232.32745 -136.356598)
		(width 0.17145)
		(layer "F.Cu")
		(net "ATTN_LED_DR3_AND")
	)
	(via
		(at 230.502968 -136.356598)
		(size 0.7112)
		(drill 0.3556)
		(layers "F.Cu" "B.Cu")
		(net "ATTN_LED_DR3_AND")
	)
	(segment
		(start 226.446588 -248.248678)
		(end 227.188776 -247.50649)
		(width 0.17145)
		(layer "F.Cu")
		(net "ATTN_LED_DR2_MOS_N")
	)
	(segment
		(start 226.036886 -248.248678)
		(end 226.446588 -248.248678)
		(width 0.17145)
		(layer "F.Cu")
		(net "ATTN_LED_DR2_MOS_N")
	)
	(segment
		(start 223.094042 -247.8532)
		(end 222.123 -246.882158)
		(width 0.17145)
		(layer "F.Cu")
		(net "ATTN_LED_DR2_MOS_N")
	)
	(segment
		(start 223.864678 -248.248678)
		(end 223.4692 -247.8532)
		(width 0.17145)
		(layer "F.Cu")
		(net "ATTN_LED_DR2_MOS_N")
	)
	(segment
		(start 223.4692 -247.8532)
		(end 223.094042 -247.8532)
		(width 0.17145)
		(layer "F.Cu")
		(net "ATTN_LED_DR2_MOS_N")
	)
	(segment
		(start 227.188776 -247.50649)
		(end 227.769674 -247.50649)
		(width 0.17145)
		(layer "F.Cu")
		(net "ATTN_LED_DR2_MOS_N")
	)
	(segment
		(start 226.036886 -248.248678)
		(end 223.864678 -248.248678)
		(width 0.17145)
		(layer "F.Cu")
		(net "ATTN_LED_DR2_MOS_N")
	)
	(segment
		(start 222.123 -246.882158)
		(end 222.123 -246.056658)
		(width 0.17145)
		(layer "F.Cu")
		(net "ATTN_LED_DR2_MOS_N")
	)
	(via
		(at 223.4692 -247.8532)
		(size 0.7112)
		(drill 0.3556)
		(layers "F.Cu" "B.Cu")
		(net "ATTN_LED_DR2_MOS_N")
	)
	(segment
		(start 236.601 -241.421158)
		(end 236.601 -242.183158)
		(width 0.17145)
		(layer "F.Cu")
		(net "ATTN_LED_DR2_AND_R")
	)
	(segment
		(start 234.5055 -239.008158)
		(end 235.585 -239.008158)
		(width 0.17145)
		(layer "F.Cu")
		(net "ATTN_LED_DR2_AND_R")
	)
	(segment
		(start 236.601 -242.183158)
		(end 236.0295 -242.754658)
		(width 0.17145)
		(layer "F.Cu")
		(net "ATTN_LED_DR2_AND_R")
	)
	(segment
		(start 236.0295 -242.754658)
		(end 234.79125 -242.754658)
		(width 0.17145)
		(layer "F.Cu")
		(net "ATTN_LED_DR2_AND_R")
	)
	(segment
		(start 235.585 -239.008158)
		(end 236.601 -240.024158)
		(width 0.17145)
		(layer "F.Cu")
		(net "ATTN_LED_DR2_AND_R")
	)
	(segment
		(start 236.601 -240.024158)
		(end 236.601 -241.421158)
		(width 0.17145)
		(layer "F.Cu")
		(net "ATTN_LED_DR2_AND_R")
	)
	(via
		(at 236.601 -241.421158)
		(size 0.7112)
		(drill 0.3556)
		(layers "F.Cu" "B.Cu")
		(net "ATTN_LED_DR2_AND_R")
	)
	(segment
		(start 229.06863 -240.262918)
		(end 228.0285 -240.262918)
		(width 0.17145)
		(layer "F.Cu")
		(net "ATTN_LED_DR2_AND")
	)
	(segment
		(start 233.6165 -239.008158)
		(end 232.137966 -239.008158)
		(width 0.17145)
		(layer "F.Cu")
		(net "ATTN_LED_DR2_AND")
	)
	(segment
		(start 230.676958 -239.453166)
		(end 229.878382 -239.453166)
		(width 0.17145)
		(layer "F.Cu")
		(net "ATTN_LED_DR2_AND")
	)
	(segment
		(start 231.692958 -239.453166)
		(end 230.676958 -239.453166)
		(width 0.17145)
		(layer "F.Cu")
		(net "ATTN_LED_DR2_AND")
	)
	(segment
		(start 232.137966 -239.008158)
		(end 231.692958 -239.453166)
		(width 0.17145)
		(layer "F.Cu")
		(net "ATTN_LED_DR2_AND")
	)
	(segment
		(start 229.878382 -239.453166)
		(end 229.06863 -240.262918)
		(width 0.17145)
		(layer "F.Cu")
		(net "ATTN_LED_DR2_AND")
	)
	(via
		(at 230.676958 -239.453166)
		(size 0.7112)
		(drill 0.3556)
		(layers "F.Cu" "B.Cu")
		(net "ATTN_LED_DR2_AND")
	)
	(segment
		(start 17.217136 -56.002936)
		(end 16.496538 -55.282338)
		(width 0.17145)
		(layer "F.Cu")
		(net "ATTN_LED_DR14_MOS_N")
	)
	(segment
		(start 18.594832 -56.002936)
		(end 17.217136 -56.002936)
		(width 0.17145)
		(layer "F.Cu")
		(net "ATTN_LED_DR14_MOS_N")
	)
	(segment
		(start 17.76984 -53.306472)
		(end 16.93672 -53.306472)
		(width 0.17145)
		(layer "F.Cu")
		(net "ATTN_LED_DR14_MOS_N")
	)
	(segment
		(start 16.496538 -55.282338)
		(end 16.442436 -55.282338)
		(width 0.17145)
		(layer "F.Cu")
		(net "ATTN_LED_DR14_MOS_N")
	)
	(segment
		(start 16.231362 -54.01183)
		(end 16.231362 -55.071264)
		(width 0.17145)
		(layer "F.Cu")
		(net "ATTN_LED_DR14_MOS_N")
	)
	(segment
		(start 16.93672 -53.306472)
		(end 16.231362 -54.01183)
		(width 0.17145)
		(layer "F.Cu")
		(net "ATTN_LED_DR14_MOS_N")
	)
	(segment
		(start 16.231362 -55.071264)
		(end 16.442436 -55.282338)
		(width 0.17145)
		(layer "F.Cu")
		(net "ATTN_LED_DR14_MOS_N")
	)
	(via
		(at 16.442436 -55.282338)
		(size 0.7112)
		(drill 0.3556)
		(layers "F.Cu" "B.Cu")
		(net "ATTN_LED_DR14_MOS_N")
	)
	(segment
		(start 15.14475 -63.64986)
		(end 15.14475 -60.37961)
		(width 0.17145)
		(layer "F.Cu")
		(net "ATTN_LED_DR14_AND_R")
	)
	(segment
		(start 19.6215 -64.38011)
		(end 18.288 -64.38011)
		(width 0.17145)
		(layer "F.Cu")
		(net "ATTN_LED_DR14_AND_R")
	)
	(segment
		(start 15.875 -64.38011)
		(end 15.14475 -63.64986)
		(width 0.17145)
		(layer "F.Cu")
		(net "ATTN_LED_DR14_AND_R")
	)
	(segment
		(start 18.288 -64.38011)
		(end 15.875 -64.38011)
		(width 0.17145)
		(layer "F.Cu")
		(net "ATTN_LED_DR14_AND_R")
	)
	(via
		(at 18.288 -64.38011)
		(size 0.7112)
		(drill 0.3556)
		(layers "F.Cu" "B.Cu")
		(net "ATTN_LED_DR14_AND_R")
	)
	(segment
		(start 23.172674 -63.940436)
		(end 22.733 -64.38011)
		(width 0.17145)
		(layer "F.Cu")
		(net "ATTN_LED_DR14_AND")
	)
	(segment
		(start 21.844 -64.38011)
		(end 20.5105 -64.38011)
		(width 0.17145)
		(layer "F.Cu")
		(net "ATTN_LED_DR14_AND")
	)
	(segment
		(start 23.172674 -62.733682)
		(end 23.172674 -63.940436)
		(width 0.17145)
		(layer "F.Cu")
		(net "ATTN_LED_DR14_AND")
	)
	(segment
		(start 22.733 -64.38011)
		(end 21.844 -64.38011)
		(width 0.17145)
		(layer "F.Cu")
		(net "ATTN_LED_DR14_AND")
	)
	(via
		(at 21.844 -64.38011)
		(size 0.7112)
		(drill 0.3556)
		(layers "F.Cu" "B.Cu")
		(net "ATTN_LED_DR14_AND")
	)
	(segment
		(start 16.442436 -158.282386)
		(end 16.442436 -158.885128)
		(width 0.17145)
		(layer "F.Cu")
		(net "ATTN_LED_DR13_MOS_N")
	)
	(segment
		(start 16.442436 -158.885128)
		(end 17.123156 -159.565848)
		(width 0.17145)
		(layer "F.Cu")
		(net "ATTN_LED_DR13_MOS_N")
	)
	(segment
		(start 16.442436 -158.18485)
		(end 17.76984 -156.857446)
		(width 0.17145)
		(layer "F.Cu")
		(net "ATTN_LED_DR13_MOS_N")
	)
	(segment
		(start 17.76984 -156.857446)
		(end 17.76984 -156.30652)
		(width 0.17145)
		(layer "F.Cu")
		(net "ATTN_LED_DR13_MOS_N")
	)
	(segment
		(start 17.123156 -159.565848)
		(end 18.031968 -159.565848)
		(width 0.17145)
		(layer "F.Cu")
		(net "ATTN_LED_DR13_MOS_N")
	)
	(segment
		(start 16.442436 -158.282386)
		(end 16.442436 -158.18485)
		(width 0.17145)
		(layer "F.Cu")
		(net "ATTN_LED_DR13_MOS_N")
	)
	(segment
		(start 18.031968 -159.565848)
		(end 18.594832 -159.002984)
		(width 0.17145)
		(layer "F.Cu")
		(net "ATTN_LED_DR13_MOS_N")
	)
	(via
		(at 16.442436 -158.282386)
		(size 0.7112)
		(drill 0.3556)
		(layers "F.Cu" "B.Cu")
		(net "ATTN_LED_DR13_MOS_N")
	)
	(segment
		(start 15.3924 -166.897558)
		(end 15.875 -167.380158)
		(width 0.17145)
		(layer "F.Cu")
		(net "ATTN_LED_DR13_AND_R")
	)
	(segment
		(start 15.875 -167.380158)
		(end 18.288 -167.380158)
		(width 0.17145)
		(layer "F.Cu")
		(net "ATTN_LED_DR13_AND_R")
	)
	(segment
		(start 15.3924 -163.627308)
		(end 15.3924 -166.897558)
		(width 0.17145)
		(layer "F.Cu")
		(net "ATTN_LED_DR13_AND_R")
	)
	(segment
		(start 15.14475 -163.379658)
		(end 15.3924 -163.627308)
		(width 0.17145)
		(layer "F.Cu")
		(net "ATTN_LED_DR13_AND_R")
	)
	(segment
		(start 19.6215 -167.380158)
		(end 18.288 -167.380158)
		(width 0.17145)
		(layer "F.Cu")
		(net "ATTN_LED_DR13_AND_R")
	)
	(via
		(at 18.288 -167.380158)
		(size 0.7112)
		(drill 0.3556)
		(layers "F.Cu" "B.Cu")
		(net "ATTN_LED_DR13_AND_R")
	)
	(segment
		(start 23.172674 -166.940484)
		(end 22.733 -167.380158)
		(width 0.17145)
		(layer "F.Cu")
		(net "ATTN_LED_DR13_AND")
	)
	(segment
		(start 23.172674 -165.73373)
		(end 23.172674 -166.940484)
		(width 0.17145)
		(layer "F.Cu")
		(net "ATTN_LED_DR13_AND")
	)
	(segment
		(start 21.844 -167.380158)
		(end 20.5105 -167.380158)
		(width 0.17145)
		(layer "F.Cu")
		(net "ATTN_LED_DR13_AND")
	)
	(segment
		(start 22.733 -167.380158)
		(end 21.844 -167.380158)
		(width 0.17145)
		(layer "F.Cu")
		(net "ATTN_LED_DR13_AND")
	)
	(via
		(at 21.844 -167.380158)
		(size 0.7112)
		(drill 0.3556)
		(layers "F.Cu" "B.Cu")
		(net "ATTN_LED_DR13_AND")
	)
	(segment
		(start 16.269716 -261.10946)
		(end 16.442436 -261.28218)
		(width 0.17145)
		(layer "F.Cu")
		(net "ATTN_LED_DR12_MOS_N")
	)
	(segment
		(start 17.76984 -259.306314)
		(end 17.76984 -259.63753)
		(width 0.17145)
		(layer "F.Cu")
		(net "ATTN_LED_DR12_MOS_N")
	)
	(segment
		(start 16.2687 -260.77545)
		(end 16.269716 -261.10946)
		(width 0.17145)
		(layer "F.Cu")
		(net "ATTN_LED_DR12_MOS_N")
	)
	(segment
		(start 17.163034 -262.002778)
		(end 16.442436 -261.28218)
		(width 0.17145)
		(layer "F.Cu")
		(net "ATTN_LED_DR12_MOS_N")
	)
	(segment
		(start 17.76984 -259.63753)
		(end 17.385792 -260.021578)
		(width 0.17145)
		(layer "F.Cu")
		(net "ATTN_LED_DR12_MOS_N")
	)
	(segment
		(start 17.385792 -260.021578)
		(end 16.273272 -260.021578)
		(width 0.17145)
		(layer "F.Cu")
		(net "ATTN_LED_DR12_MOS_N")
	)
	(segment
		(start 16.2687 -260.03123)
		(end 16.2687 -260.77545)
		(width 0.17145)
		(layer "F.Cu")
		(net "ATTN_LED_DR12_MOS_N")
	)
	(segment
		(start 16.273272 -260.021578)
		(end 16.26616 -260.02869)
		(width 0.17145)
		(layer "F.Cu")
		(net "ATTN_LED_DR12_MOS_N")
	)
	(segment
		(start 18.594832 -262.002778)
		(end 17.163034 -262.002778)
		(width 0.17145)
		(layer "F.Cu")
		(net "ATTN_LED_DR12_MOS_N")
	)
	(segment
		(start 16.26616 -260.02869)
		(end 16.2687 -260.03123)
		(width 0.17145)
		(layer "F.Cu")
		(net "ATTN_LED_DR12_MOS_N")
	)
	(via
		(at 16.442436 -261.28218)
		(size 0.7112)
		(drill 0.3556)
		(layers "F.Cu" "B.Cu")
		(net "ATTN_LED_DR12_MOS_N")
	)
	(segment
		(start 18.288 -270.379952)
		(end 16.887952 -270.379952)
		(width 0.17145)
		(layer "F.Cu")
		(net "ATTN_LED_DR12_AND_R")
	)
	(segment
		(start 16.200628 -269.692628)
		(end 16.200628 -267.057378)
		(width 0.17145)
		(layer "F.Cu")
		(net "ATTN_LED_DR12_AND_R")
	)
	(segment
		(start 16.887952 -270.379952)
		(end 16.200628 -269.692628)
		(width 0.17145)
		(layer "F.Cu")
		(net "ATTN_LED_DR12_AND_R")
	)
	(segment
		(start 16.200628 -267.057378)
		(end 16.03375 -266.8905)
		(width 0.17145)
		(layer "F.Cu")
		(net "ATTN_LED_DR12_AND_R")
	)
	(segment
		(start 19.6215 -270.379952)
		(end 18.288 -270.379952)
		(width 0.17145)
		(layer "F.Cu")
		(net "ATTN_LED_DR12_AND_R")
	)
	(via
		(at 18.288 -270.379952)
		(size 0.7112)
		(drill 0.3556)
		(layers "F.Cu" "B.Cu")
		(net "ATTN_LED_DR12_AND_R")
	)
	(segment
		(start 21.844 -270.379952)
		(end 22.761448 -270.379952)
		(width 0.17145)
		(layer "F.Cu")
		(net "ATTN_LED_DR12_AND")
	)
	(segment
		(start 23.172674 -269.968726)
		(end 23.172674 -268.733524)
		(width 0.17145)
		(layer "F.Cu")
		(net "ATTN_LED_DR12_AND")
	)
	(segment
		(start 22.761448 -270.379952)
		(end 23.172674 -269.968726)
		(width 0.17145)
		(layer "F.Cu")
		(net "ATTN_LED_DR12_AND")
	)
	(segment
		(start 21.844 -270.379952)
		(end 20.5105 -270.379952)
		(width 0.17145)
		(layer "F.Cu")
		(net "ATTN_LED_DR12_AND")
	)
	(via
		(at 21.844 -270.379952)
		(size 0.7112)
		(drill 0.3556)
		(layers "F.Cu" "B.Cu")
		(net "ATTN_LED_DR12_AND")
	)
	(segment
		(start 16.442436 -364.282228)
		(end 16.0528 -363.892592)
		(width 0.17145)
		(layer "F.Cu")
		(net "ATTN_LED_DR11_MOS_N")
	)
	(segment
		(start 16.997426 -365.002826)
		(end 16.442436 -364.447836)
		(width 0.17145)
		(layer "F.Cu")
		(net "ATTN_LED_DR11_MOS_N")
	)
	(segment
		(start 16.830802 -363.026452)
		(end 17.550892 -362.306362)
		(width 0.17145)
		(layer "F.Cu")
		(net "ATTN_LED_DR11_MOS_N")
	)
	(segment
		(start 16.0528 -363.17809)
		(end 16.204438 -363.026452)
		(width 0.17145)
		(layer "F.Cu")
		(net "ATTN_LED_DR11_MOS_N")
	)
	(segment
		(start 16.442436 -364.447836)
		(end 16.442436 -364.282228)
		(width 0.17145)
		(layer "F.Cu")
		(net "ATTN_LED_DR11_MOS_N")
	)
	(segment
		(start 16.0528 -363.892592)
		(end 16.0528 -363.17809)
		(width 0.17145)
		(layer "F.Cu")
		(net "ATTN_LED_DR11_MOS_N")
	)
	(segment
		(start 16.204438 -363.026452)
		(end 16.830802 -363.026452)
		(width 0.17145)
		(layer "F.Cu")
		(net "ATTN_LED_DR11_MOS_N")
	)
	(segment
		(start 17.550892 -362.306362)
		(end 17.76984 -362.306362)
		(width 0.17145)
		(layer "F.Cu")
		(net "ATTN_LED_DR11_MOS_N")
	)
	(segment
		(start 18.594832 -365.002826)
		(end 16.997426 -365.002826)
		(width 0.17145)
		(layer "F.Cu")
		(net "ATTN_LED_DR11_MOS_N")
	)
	(via
		(at 16.442436 -364.282228)
		(size 0.7112)
		(drill 0.3556)
		(layers "F.Cu" "B.Cu")
		(net "ATTN_LED_DR11_MOS_N")
	)
	(segment
		(start 19.6215 -373.38)
		(end 18.288 -373.38)
		(width 0.17145)
		(layer "F.Cu")
		(net "ATTN_LED_DR11_AND_R")
	)
	(segment
		(start 15.2908 -372.7958)
		(end 15.875 -373.38)
		(width 0.17145)
		(layer "F.Cu")
		(net "ATTN_LED_DR11_AND_R")
	)
	(segment
		(start 15.14475 -369.3795)
		(end 15.2908 -369.52555)
		(width 0.17145)
		(layer "F.Cu")
		(net "ATTN_LED_DR11_AND_R")
	)
	(segment
		(start 15.2908 -369.52555)
		(end 15.2908 -372.7958)
		(width 0.17145)
		(layer "F.Cu")
		(net "ATTN_LED_DR11_AND_R")
	)
	(segment
		(start 15.875 -373.38)
		(end 18.288 -373.38)
		(width 0.17145)
		(layer "F.Cu")
		(net "ATTN_LED_DR11_AND_R")
	)
	(via
		(at 18.288 -373.38)
		(size 0.7112)
		(drill 0.3556)
		(layers "F.Cu" "B.Cu")
		(net "ATTN_LED_DR11_AND_R")
	)
	(segment
		(start 23.172674 -372.864126)
		(end 23.172674 -371.733572)
		(width 0.17145)
		(layer "F.Cu")
		(net "ATTN_LED_DR11_AND")
	)
	(segment
		(start 21.844 -373.38)
		(end 20.5105 -373.38)
		(width 0.17145)
		(layer "F.Cu")
		(net "ATTN_LED_DR11_AND")
	)
	(segment
		(start 21.844 -373.38)
		(end 22.6568 -373.38)
		(width 0.17145)
		(layer "F.Cu")
		(net "ATTN_LED_DR11_AND")
	)
	(segment
		(start 22.6568 -373.38)
		(end 23.172674 -372.864126)
		(width 0.17145)
		(layer "F.Cu")
		(net "ATTN_LED_DR11_AND")
	)
	(via
		(at 21.844 -373.38)
		(size 0.7112)
		(drill 0.3556)
		(layers "F.Cu" "B.Cu")
		(net "ATTN_LED_DR11_AND")
	)
	(segment
		(start 17.79524 -466.66658)
		(end 17.79524 -465.33181)
		(width 0.17145)
		(layer "F.Cu")
		(net "ATTN_LED_DR10_MOS_N")
	)
	(segment
		(start 17.79524 -466.66658)
		(end 17.763744 -466.698076)
		(width 0.17145)
		(layer "F.Cu")
		(net "ATTN_LED_DR10_MOS_N")
	)
	(segment
		(start 17.763744 -466.698076)
		(end 16.714724 -466.698076)
		(width 0.17145)
		(layer "F.Cu")
		(net "ATTN_LED_DR10_MOS_N")
	)
	(segment
		(start 16.5354 -467.9061)
		(end 17.1704 -468.5411)
		(width 0.17145)
		(layer "F.Cu")
		(net "ATTN_LED_DR10_MOS_N")
	)
	(segment
		(start 16.5354 -466.8774)
		(end 16.5354 -467.9061)
		(width 0.17145)
		(layer "F.Cu")
		(net "ATTN_LED_DR10_MOS_N")
	)
	(segment
		(start 16.714724 -466.698076)
		(end 16.5354 -466.8774)
		(width 0.17145)
		(layer "F.Cu")
		(net "ATTN_LED_DR10_MOS_N")
	)
	(segment
		(start 17.79524 -465.33181)
		(end 17.76984 -465.30641)
		(width 0.17145)
		(layer "F.Cu")
		(net "ATTN_LED_DR10_MOS_N")
	)
	(via
		(at 16.5354 -466.8774)
		(size 0.7112)
		(drill 0.3556)
		(layers "F.Cu" "B.Cu")
		(net "ATTN_LED_DR10_MOS_N")
	)
	(segment
		(start 23.6728 -474.3196)
		(end 24.74595 -473.24645)
		(width 0.17145)
		(layer "F.Cu")
		(net "ATTN_LED_DR10_AND_R")
	)
	(segment
		(start 24.74595 -473.24645)
		(end 24.74595 -470.7001)
		(width 0.17145)
		(layer "F.Cu")
		(net "ATTN_LED_DR10_AND_R")
	)
	(segment
		(start 23.6728 -474.3196)
		(end 22.4409 -474.3196)
		(width 0.17145)
		(layer "F.Cu")
		(net "ATTN_LED_DR10_AND_R")
	)
	(via
		(at 23.6728 -474.3196)
		(size 0.7112)
		(drill 0.3556)
		(layers "F.Cu" "B.Cu")
		(net "ATTN_LED_DR10_AND_R")
	)
	(segment
		(start 23.050246 -472.518994)
		(end 23.05304 -472.518994)
		(width 0.17145)
		(layer "F.Cu")
		(net "ATTN_LED_DR10_AND")
	)
	(segment
		(start 23.05304 -472.518994)
		(end 23.05304 -470.8271)
		(width 0.17145)
		(layer "F.Cu")
		(net "ATTN_LED_DR10_AND")
	)
	(segment
		(start 22.4409 -473.4306)
		(end 21.5519 -474.3196)
		(width 0.17145)
		(layer "F.Cu")
		(net "ATTN_LED_DR10_AND")
	)
	(segment
		(start 22.7584 -473.4306)
		(end 22.4409 -473.4306)
		(width 0.17145)
		(layer "F.Cu")
		(net "ATTN_LED_DR10_AND")
	)
	(segment
		(start 23.05304 -472.518994)
		(end 23.05304 -473.13596)
		(width 0.17145)
		(layer "F.Cu")
		(net "ATTN_LED_DR10_AND")
	)
	(segment
		(start 23.05304 -473.13596)
		(end 22.7584 -473.4306)
		(width 0.17145)
		(layer "F.Cu")
		(net "ATTN_LED_DR10_AND")
	)
	(via
		(at 23.050246 -472.518994)
		(size 0.7112)
		(drill 0.3556)
		(layers "F.Cu" "B.Cu")
		(net "ATTN_LED_DR10_AND")
	)
	(segment
		(start 222.123 -349.881952)
		(end 222.123 -349.056452)
		(width 0.17145)
		(layer "F.Cu")
		(net "ATTN_LED_DR1_MOS_N")
	)
	(segment
		(start 223.5454 -350.5454)
		(end 223.584516 -350.506284)
		(width 0.17145)
		(layer "F.Cu")
		(net "ATTN_LED_DR1_MOS_N")
	)
	(segment
		(start 222.747332 -350.506284)
		(end 222.123 -349.881952)
		(width 0.17145)
		(layer "F.Cu")
		(net "ATTN_LED_DR1_MOS_N")
	)
	(segment
		(start 223.5454 -350.5454)
		(end 223.506284 -350.506284)
		(width 0.17145)
		(layer "F.Cu")
		(net "ATTN_LED_DR1_MOS_N")
	)
	(segment
		(start 223.584516 -350.506284)
		(end 226.114102 -350.506284)
		(width 0.17145)
		(layer "F.Cu")
		(net "ATTN_LED_DR1_MOS_N")
	)
	(segment
		(start 226.114102 -350.506284)
		(end 227.769674 -350.506284)
		(width 0.17145)
		(layer "F.Cu")
		(net "ATTN_LED_DR1_MOS_N")
	)
	(segment
		(start 223.506284 -350.506284)
		(end 222.747332 -350.506284)
		(width 0.17145)
		(layer "F.Cu")
		(net "ATTN_LED_DR1_MOS_N")
	)
	(via
		(at 223.5454 -350.5454)
		(size 0.7112)
		(drill 0.3556)
		(layers "F.Cu" "B.Cu")
		(net "ATTN_LED_DR1_MOS_N")
	)
	(segment
		(start 236.0295 -345.754452)
		(end 234.79125 -345.754452)
		(width 0.17145)
		(layer "F.Cu")
		(net "ATTN_LED_DR1_AND_R")
	)
	(segment
		(start 236.601 -343.023952)
		(end 236.601 -344.420952)
		(width 0.17145)
		(layer "F.Cu")
		(net "ATTN_LED_DR1_AND_R")
	)
	(segment
		(start 236.601 -345.182952)
		(end 236.0295 -345.754452)
		(width 0.17145)
		(layer "F.Cu")
		(net "ATTN_LED_DR1_AND_R")
	)
	(segment
		(start 234.5055 -342.007952)
		(end 235.585 -342.007952)
		(width 0.17145)
		(layer "F.Cu")
		(net "ATTN_LED_DR1_AND_R")
	)
	(segment
		(start 235.585 -342.007952)
		(end 236.601 -343.023952)
		(width 0.17145)
		(layer "F.Cu")
		(net "ATTN_LED_DR1_AND_R")
	)
	(segment
		(start 236.601 -344.420952)
		(end 236.601 -345.182952)
		(width 0.17145)
		(layer "F.Cu")
		(net "ATTN_LED_DR1_AND_R")
	)
	(via
		(at 236.601 -344.420952)
		(size 0.7112)
		(drill 0.3556)
		(layers "F.Cu" "B.Cu")
		(net "ATTN_LED_DR1_AND_R")
	)
	(segment
		(start 230.76662 -342.508332)
		(end 231.938068 -342.508332)
		(width 0.17145)
		(layer "F.Cu")
		(net "ATTN_LED_DR1_AND")
	)
	(segment
		(start 228.745288 -343.262712)
		(end 228.0285 -343.262712)
		(width 0.17145)
		(layer "F.Cu")
		(net "ATTN_LED_DR1_AND")
	)
	(segment
		(start 230.76662 -342.508332)
		(end 229.499668 -342.508332)
		(width 0.17145)
		(layer "F.Cu")
		(net "ATTN_LED_DR1_AND")
	)
	(segment
		(start 232.438448 -342.007952)
		(end 233.6165 -342.007952)
		(width 0.17145)
		(layer "F.Cu")
		(net "ATTN_LED_DR1_AND")
	)
	(segment
		(start 229.499668 -342.508332)
		(end 228.745288 -343.262712)
		(width 0.17145)
		(layer "F.Cu")
		(net "ATTN_LED_DR1_AND")
	)
	(segment
		(start 231.938068 -342.508332)
		(end 232.438448 -342.007952)
		(width 0.17145)
		(layer "F.Cu")
		(net "ATTN_LED_DR1_AND")
	)
	(via
		(at 230.76662 -342.508332)
		(size 0.7112)
		(drill 0.3556)
		(layers "F.Cu" "B.Cu")
		(net "ATTN_LED_DR1_AND")
	)
	(segment
		(start 225.31578 -453.506332)
		(end 225.258122 -453.506332)
		(width 0.17145)
		(layer "F.Cu")
		(net "ATTN_LED_DR0_MOS_N")
	)
	(segment
		(start 227.769674 -453.506332)
		(end 227.769674 -454.539858)
		(width 0.17145)
		(layer "F.Cu")
		(net "ATTN_LED_DR0_MOS_N")
	)
	(segment
		(start 227.769674 -454.539858)
		(end 227.442268 -454.867264)
		(width 0.17145)
		(layer "F.Cu")
		(net "ATTN_LED_DR0_MOS_N")
	)
	(segment
		(start 227.442268 -454.867264)
		(end 226.676712 -454.867264)
		(width 0.17145)
		(layer "F.Cu")
		(net "ATTN_LED_DR0_MOS_N")
	)
	(segment
		(start 225.258122 -453.506332)
		(end 222.747332 -453.506332)
		(width 0.17145)
		(layer "F.Cu")
		(net "ATTN_LED_DR0_MOS_N")
	)
	(segment
		(start 226.676712 -454.867264)
		(end 225.31578 -453.506332)
		(width 0.17145)
		(layer "F.Cu")
		(net "ATTN_LED_DR0_MOS_N")
	)
	(segment
		(start 222.123 -452.882)
		(end 222.123 -452.0565)
		(width 0.17145)
		(layer "F.Cu")
		(net "ATTN_LED_DR0_MOS_N")
	)
	(segment
		(start 222.747332 -453.506332)
		(end 222.123 -452.882)
		(width 0.17145)
		(layer "F.Cu")
		(net "ATTN_LED_DR0_MOS_N")
	)
	(via
		(at 225.258122 -453.506332)
		(size 0.7112)
		(drill 0.3556)
		(layers "F.Cu" "B.Cu")
		(net "ATTN_LED_DR0_MOS_N")
	)
	(segment
		(start 236.0295 -448.7545)
		(end 236.601 -448.183)
		(width 0.17145)
		(layer "F.Cu")
		(net "ATTN_LED_DR0_AND_R")
	)
	(segment
		(start 235.585 -445.008)
		(end 236.601 -446.024)
		(width 0.17145)
		(layer "F.Cu")
		(net "ATTN_LED_DR0_AND_R")
	)
	(segment
		(start 236.601 -448.183)
		(end 236.601 -447.421)
		(width 0.17145)
		(layer "F.Cu")
		(net "ATTN_LED_DR0_AND_R")
	)
	(segment
		(start 234.79125 -448.7545)
		(end 236.0295 -448.7545)
		(width 0.17145)
		(layer "F.Cu")
		(net "ATTN_LED_DR0_AND_R")
	)
	(segment
		(start 234.5055 -445.008)
		(end 235.585 -445.008)
		(width 0.17145)
		(layer "F.Cu")
		(net "ATTN_LED_DR0_AND_R")
	)
	(segment
		(start 236.601 -446.024)
		(end 236.601 -447.421)
		(width 0.17145)
		(layer "F.Cu")
		(net "ATTN_LED_DR0_AND_R")
	)
	(via
		(at 236.601 -447.421)
		(size 0.7112)
		(drill 0.3556)
		(layers "F.Cu" "B.Cu")
		(net "ATTN_LED_DR0_AND_R")
	)
	(segment
		(start 228.0285 -446.26276)
		(end 228.937566 -446.26276)
		(width 0.17145)
		(layer "F.Cu")
		(net "ATTN_LED_DR0_AND")
	)
	(segment
		(start 232.136442 -445.008)
		(end 233.6165 -445.008)
		(width 0.17145)
		(layer "F.Cu")
		(net "ATTN_LED_DR0_AND")
	)
	(segment
		(start 230.192326 -445.008)
		(end 232.136442 -445.008)
		(width 0.17145)
		(layer "F.Cu")
		(net "ATTN_LED_DR0_AND")
	)
	(segment
		(start 228.937566 -446.26276)
		(end 230.192326 -445.008)
		(width 0.17145)
		(layer "F.Cu")
		(net "ATTN_LED_DR0_AND")
	)
	(via
		(at 232.136442 -445.008)
		(size 0.7112)
		(drill 0.3556)
		(layers "F.Cu" "B.Cu")
		(net "ATTN_LED_DR0_AND")
	)
	(segment
		(start 39.243 -136.144)
		(end 40.284146 -136.144)
		(width 0.17145)
		(layer "F.Cu")
		(net "I2C_B_TMP1_ALERT")
	)
	(segment
		(start 40.64 -136.499854)
		(end 40.64 -137.414)
		(width 0.17145)
		(layer "F.Cu")
		(net "I2C_B_TMP1_ALERT")
	)
	(segment
		(start 40.284146 -136.144)
		(end 40.64 -136.499854)
		(width 0.17145)
		(layer "F.Cu")
		(net "I2C_B_TMP1_ALERT")
	)
	(segment
		(start 40.900858 -137.674858)
		(end 41.945052 -137.674858)
		(width 0.17145)
		(layer "F.Cu")
		(net "I2C_B_TMP1_ALERT")
	)
	(segment
		(start 40.64 -137.414)
		(end 40.900858 -137.674858)
		(width 0.17145)
		(layer "F.Cu")
		(net "I2C_B_TMP1_ALERT")
	)
	(segment
		(start 50.546 -134.0485)
		(end 51.562 -134.0485)
		(width 0.17145)
		(layer "F.Cu")
		(net "I2C_B_TMP1_A2")
	)
	(segment
		(start 48.768 -134.5565)
		(end 49.276 -134.0485)
		(width 0.17145)
		(layer "F.Cu")
		(net "I2C_B_TMP1_A2")
	)
	(segment
		(start 46.871382 -137.024618)
		(end 48.768 -135.128)
		(width 0.17145)
		(layer "F.Cu")
		(net "I2C_B_TMP1_A2")
	)
	(segment
		(start 50.546 -134.0485)
		(end 49.276 -134.0485)
		(width 0.17145)
		(layer "F.Cu")
		(net "I2C_B_TMP1_A2")
	)
	(segment
		(start 46.054772 -137.024618)
		(end 46.871382 -137.024618)
		(width 0.17145)
		(layer "F.Cu")
		(net "I2C_B_TMP1_A2")
	)
	(segment
		(start 48.768 -135.128)
		(end 48.768 -134.5565)
		(width 0.17145)
		(layer "F.Cu")
		(net "I2C_B_TMP1_A2")
	)
	(via
		(at 49.276 -134.0485)
		(size 0.7112)
		(drill 0.3556)
		(layers "F.Cu" "B.Cu")
		(net "I2C_B_TMP1_A2")
	)
	(segment
		(start 50.546 -135.9535)
		(end 49.2125 -135.9535)
		(width 0.17145)
		(layer "F.Cu")
		(net "I2C_B_TMP1_A1")
	)
	(segment
		(start 47.491142 -137.674858)
		(end 46.054772 -137.674858)
		(width 0.17145)
		(layer "F.Cu")
		(net "I2C_B_TMP1_A1")
	)
	(segment
		(start 49.2125 -135.9535)
		(end 47.491142 -137.674858)
		(width 0.17145)
		(layer "F.Cu")
		(net "I2C_B_TMP1_A1")
	)
	(segment
		(start 50.546 -135.9535)
		(end 51.562 -135.9535)
		(width 0.17145)
		(layer "F.Cu")
		(net "I2C_B_TMP1_A1")
	)
	(via
		(at 49.2125 -135.9535)
		(size 0.7112)
		(drill 0.3556)
		(layers "F.Cu" "B.Cu")
		(net "I2C_B_TMP1_A1")
	)
	(segment
		(start 90.652346 -94.589346)
		(end 90.652346 -93.763846)
		(width 0.174752)
		(layer "F.Cu")
		(net "PE_CLK_100M_DR9_1_R_P")
	)
	(segment
		(start 90.652346 -93.763846)
		(end 90.297 -93.4085)
		(width 0.174752)
		(layer "F.Cu")
		(net "PE_CLK_100M_DR9_1_R_P")
	)
	(segment
		(start 92.22994 -97.17659)
		(end 92.22994 -96.52)
		(width 0.174752)
		(layer "F.Cu")
		(net "PE_CLK_100M_DR9_1_R_P")
	)
	(segment
		(start 92.22994 -96.52)
		(end 92.326968 -96.422972)
		(width 0.174752)
		(layer "F.Cu")
		(net "PE_CLK_100M_DR9_1_R_P")
	)
	(segment
		(start 92.326968 -96.422972)
		(end 92.326968 -96.263968)
		(width 0.174752)
		(layer "F.Cu")
		(net "PE_CLK_100M_DR9_1_R_P")
	)
	(segment
		(start 92.326968 -96.263968)
		(end 90.652346 -94.589346)
		(width 0.174752)
		(layer "F.Cu")
		(net "PE_CLK_100M_DR9_1_R_P")
	)
	(segment
		(start 32.9819 -82.3976)
		(end 34.065718 -82.3976)
		(width 0.17145)
		(layer "F.Cu")
		(net "SDA_DR9_R")
	)
	(segment
		(start 35.407092 -82.41665)
		(end 37.921692 -82.41665)
		(width 0.17145)
		(layer "F.Cu")
		(net "SDA_DR9_R")
	)
	(segment
		(start 34.74593 -83.077812)
		(end 35.407092 -82.41665)
		(width 0.17145)
		(layer "F.Cu")
		(net "SDA_DR9_R")
	)
	(segment
		(start 34.065718 -82.3976)
		(end 34.74593 -83.077812)
		(width 0.17145)
		(layer "F.Cu")
		(net "SDA_DR9_R")
	)
	(segment
		(start 32.5755 -82.804)
		(end 32.9819 -82.3976)
		(width 0.17145)
		(layer "F.Cu")
		(net "SDA_DR9_R")
	)
	(segment
		(start 37.921692 -82.41665)
		(end 38.09492 -82.589878)
		(width 0.17145)
		(layer "F.Cu")
		(net "SDA_DR9_R")
	)
	(segment
		(start 38.09492 -82.589878)
		(end 39.200074 -82.589878)
		(width 0.17145)
		(layer "F.Cu")
		(net "SDA_DR9_R")
	)
	(via
		(at 34.74593 -83.077812)
		(size 0.7112)
		(drill 0.3556)
		(layers "F.Cu" "B.Cu")
		(net "SDA_DR9_R")
	)
	(segment
		(start 38.1 -185.589926)
		(end 39.200074 -185.589926)
		(width 0.17145)
		(layer "F.Cu")
		(net "SDA_DR8_R")
	)
	(segment
		(start 32.91205 -185.46445)
		(end 34.03092 -185.46445)
		(width 0.17145)
		(layer "F.Cu")
		(net "SDA_DR8_R")
	)
	(segment
		(start 37.930074 -185.42)
		(end 38.1 -185.589926)
		(width 0.17145)
		(layer "F.Cu")
		(net "SDA_DR8_R")
	)
	(segment
		(start 34.64433 -186.07786)
		(end 35.30219 -185.42)
		(width 0.17145)
		(layer "F.Cu")
		(net "SDA_DR8_R")
	)
	(segment
		(start 32.5755 -185.801)
		(end 32.91205 -185.46445)
		(width 0.17145)
		(layer "F.Cu")
		(net "SDA_DR8_R")
	)
	(segment
		(start 34.03092 -185.46445)
		(end 34.64433 -186.07786)
		(width 0.17145)
		(layer "F.Cu")
		(net "SDA_DR8_R")
	)
	(segment
		(start 35.30219 -185.42)
		(end 37.930074 -185.42)
		(width 0.17145)
		(layer "F.Cu")
		(net "SDA_DR8_R")
	)
	(via
		(at 34.64433 -186.07786)
		(size 0.7112)
		(drill 0.3556)
		(layers "F.Cu" "B.Cu")
		(net "SDA_DR8_R")
	)
	(segment
		(start 33.875472 -288.43605)
		(end 34.51733 -289.077908)
		(width 0.17145)
		(layer "F.Cu")
		(net "SDA_DR7_R")
	)
	(segment
		(start 38.1 -288.589974)
		(end 39.200074 -288.589974)
		(width 0.17145)
		(layer "F.Cu")
		(net "SDA_DR7_R")
	)
	(segment
		(start 32.5755 -288.798)
		(end 32.93745 -288.43605)
		(width 0.17145)
		(layer "F.Cu")
		(net "SDA_DR7_R")
	)
	(segment
		(start 37.977826 -288.4678)
		(end 38.1 -288.589974)
		(width 0.17145)
		(layer "F.Cu")
		(net "SDA_DR7_R")
	)
	(segment
		(start 34.51733 -289.077908)
		(end 35.127438 -288.4678)
		(width 0.17145)
		(layer "F.Cu")
		(net "SDA_DR7_R")
	)
	(segment
		(start 35.127438 -288.4678)
		(end 37.977826 -288.4678)
		(width 0.17145)
		(layer "F.Cu")
		(net "SDA_DR7_R")
	)
	(segment
		(start 32.93745 -288.43605)
		(end 33.875472 -288.43605)
		(width 0.17145)
		(layer "F.Cu")
		(net "SDA_DR7_R")
	)
	(via
		(at 34.51733 -289.077908)
		(size 0.7112)
		(drill 0.3556)
		(layers "F.Cu" "B.Cu")
		(net "SDA_DR7_R")
	)
	(segment
		(start 32.93745 -391.43305)
		(end 33.821624 -391.43305)
		(width 0.17145)
		(layer "F.Cu")
		(net "SDA_DR6_R")
	)
	(segment
		(start 32.5755 -391.795)
		(end 32.93745 -391.43305)
		(width 0.17145)
		(layer "F.Cu")
		(net "SDA_DR6_R")
	)
	(segment
		(start 37.993828 -391.48385)
		(end 38.1 -391.590022)
		(width 0.17145)
		(layer "F.Cu")
		(net "SDA_DR6_R")
	)
	(segment
		(start 34.46653 -392.077956)
		(end 35.060636 -391.48385)
		(width 0.17145)
		(layer "F.Cu")
		(net "SDA_DR6_R")
	)
	(segment
		(start 38.1 -391.590022)
		(end 39.200074 -391.590022)
		(width 0.17145)
		(layer "F.Cu")
		(net "SDA_DR6_R")
	)
	(segment
		(start 35.060636 -391.48385)
		(end 37.993828 -391.48385)
		(width 0.17145)
		(layer "F.Cu")
		(net "SDA_DR6_R")
	)
	(segment
		(start 33.821624 -391.43305)
		(end 34.46653 -392.077956)
		(width 0.17145)
		(layer "F.Cu")
		(net "SDA_DR6_R")
	)
	(via
		(at 34.46653 -392.077956)
		(size 0.7112)
		(drill 0.3556)
		(layers "F.Cu" "B.Cu")
		(net "SDA_DR6_R")
	)
	(segment
		(start 37.96792 -494.59007)
		(end 39.200074 -494.59007)
		(width 0.17145)
		(layer "F.Cu")
		(net "SDA_DR5_R")
	)
	(segment
		(start 34.53765 -492.14405)
		(end 36.82365 -494.43005)
		(width 0.17145)
		(layer "F.Cu")
		(net "SDA_DR5_R")
	)
	(segment
		(start 36.82365 -494.43005)
		(end 37.8079 -494.43005)
		(width 0.17145)
		(layer "F.Cu")
		(net "SDA_DR5_R")
	)
	(segment
		(start 33.47593 -492.842804)
		(end 34.174684 -492.14405)
		(width 0.17145)
		(layer "F.Cu")
		(net "SDA_DR5_R")
	)
	(segment
		(start 37.8079 -494.43005)
		(end 37.96792 -494.59007)
		(width 0.17145)
		(layer "F.Cu")
		(net "SDA_DR5_R")
	)
	(segment
		(start 32.783526 -492.1504)
		(end 33.47593 -492.842804)
		(width 0.17145)
		(layer "F.Cu")
		(net "SDA_DR5_R")
	)
	(segment
		(start 34.174684 -492.14405)
		(end 34.53765 -492.14405)
		(width 0.17145)
		(layer "F.Cu")
		(net "SDA_DR5_R")
	)
	(segment
		(start 32.5247 -492.1504)
		(end 32.783526 -492.1504)
		(width 0.17145)
		(layer "F.Cu")
		(net "SDA_DR5_R")
	)
	(segment
		(start 32.1437 -492.5314)
		(end 32.5247 -492.1504)
		(width 0.17145)
		(layer "F.Cu")
		(net "SDA_DR5_R")
	)
	(via
		(at 33.47593 -492.842804)
		(size 0.7112)
		(drill 0.3556)
		(layers "F.Cu" "B.Cu")
		(net "SDA_DR5_R")
	)
	(segment
		(start 217.846402 -82.445098)
		(end 218.8083 -82.445098)
		(width 0.17145)
		(layer "F.Cu")
		(net "SDA_DR4_R")
	)
	(segment
		(start 222.862648 -82.46618)
		(end 222.986346 -82.589878)
		(width 0.17145)
		(layer "F.Cu")
		(net "SDA_DR4_R")
	)
	(segment
		(start 222.986346 -82.589878)
		(end 224.199958 -82.589878)
		(width 0.17145)
		(layer "F.Cu")
		(net "SDA_DR4_R")
	)
	(segment
		(start 217.4875 -82.804)
		(end 217.846402 -82.445098)
		(width 0.17145)
		(layer "F.Cu")
		(net "SDA_DR4_R")
	)
	(segment
		(start 220.052646 -82.46618)
		(end 222.862648 -82.46618)
		(width 0.17145)
		(layer "F.Cu")
		(net "SDA_DR4_R")
	)
	(segment
		(start 219.441014 -83.077812)
		(end 220.052646 -82.46618)
		(width 0.17145)
		(layer "F.Cu")
		(net "SDA_DR4_R")
	)
	(segment
		(start 218.8083 -82.445098)
		(end 219.441014 -83.077812)
		(width 0.17145)
		(layer "F.Cu")
		(net "SDA_DR4_R")
	)
	(via
		(at 219.441014 -83.077812)
		(size 0.7112)
		(drill 0.3556)
		(layers "F.Cu" "B.Cu")
		(net "SDA_DR4_R")
	)
	(segment
		(start 222.862648 -185.466228)
		(end 222.986346 -185.589926)
		(width 0.17145)
		(layer "F.Cu")
		(net "SDA_DR3_R")
	)
	(segment
		(start 222.986346 -185.589926)
		(end 224.199958 -185.589926)
		(width 0.17145)
		(layer "F.Cu")
		(net "SDA_DR3_R")
	)
	(segment
		(start 217.846402 -185.442098)
		(end 218.779852 -185.442098)
		(width 0.17145)
		(layer "F.Cu")
		(net "SDA_DR3_R")
	)
	(segment
		(start 219.415614 -186.07786)
		(end 220.027246 -185.466228)
		(width 0.17145)
		(layer "F.Cu")
		(net "SDA_DR3_R")
	)
	(segment
		(start 218.779852 -185.442098)
		(end 219.415614 -186.07786)
		(width 0.17145)
		(layer "F.Cu")
		(net "SDA_DR3_R")
	)
	(segment
		(start 220.027246 -185.466228)
		(end 222.862648 -185.466228)
		(width 0.17145)
		(layer "F.Cu")
		(net "SDA_DR3_R")
	)
	(segment
		(start 217.4875 -185.801)
		(end 217.846402 -185.442098)
		(width 0.17145)
		(layer "F.Cu")
		(net "SDA_DR3_R")
	)
	(via
		(at 219.415614 -186.07786)
		(size 0.7112)
		(drill 0.3556)
		(layers "F.Cu" "B.Cu")
		(net "SDA_DR3_R")
	)
	(segment
		(start 220.128846 -288.466276)
		(end 222.862648 -288.466276)
		(width 0.17145)
		(layer "F.Cu")
		(net "SDA_DR2_R")
	)
	(segment
		(start 217.4875 -288.798)
		(end 217.883994 -288.401506)
		(width 0.17145)
		(layer "F.Cu")
		(net "SDA_DR2_R")
	)
	(segment
		(start 219.517214 -289.077908)
		(end 220.128846 -288.466276)
		(width 0.17145)
		(layer "F.Cu")
		(net "SDA_DR2_R")
	)
	(segment
		(start 222.862648 -288.466276)
		(end 222.986346 -288.589974)
		(width 0.17145)
		(layer "F.Cu")
		(net "SDA_DR2_R")
	)
	(segment
		(start 222.986346 -288.589974)
		(end 224.199958 -288.589974)
		(width 0.17145)
		(layer "F.Cu")
		(net "SDA_DR2_R")
	)
	(segment
		(start 217.883994 -288.401506)
		(end 218.840812 -288.401506)
		(width 0.17145)
		(layer "F.Cu")
		(net "SDA_DR2_R")
	)
	(segment
		(start 218.840812 -288.401506)
		(end 219.517214 -289.077908)
		(width 0.17145)
		(layer "F.Cu")
		(net "SDA_DR2_R")
	)
	(via
		(at 219.517214 -289.077908)
		(size 0.7112)
		(drill 0.3556)
		(layers "F.Cu" "B.Cu")
		(net "SDA_DR2_R")
	)
	(segment
		(start 23.855934 -11.409934)
		(end 22.800056 -11.409934)
		(width 0.17145)
		(layer "F.Cu")
		(net "SDA_DR14_R")
	)
	(segment
		(start 29.9974 -15.8877)
		(end 29.9974 -16.3957)
		(width 0.17145)
		(layer "F.Cu")
		(net "SDA_DR14_R")
	)
	(segment
		(start 29.9974 -13.874496)
		(end 29.464254 -13.34135)
		(width 0.17145)
		(layer "F.Cu")
		(net "SDA_DR14_R")
	)
	(segment
		(start 29.9974 -14.5669)
		(end 29.9974 -13.874496)
		(width 0.17145)
		(layer "F.Cu")
		(net "SDA_DR14_R")
	)
	(segment
		(start 26.416 -12.1158)
		(end 25.075896 -12.1158)
		(width 0.17145)
		(layer "F.Cu")
		(net "SDA_DR14_R")
	)
	(segment
		(start 27.64155 -13.34135)
		(end 26.416 -12.1158)
		(width 0.17145)
		(layer "F.Cu")
		(net "SDA_DR14_R")
	)
	(segment
		(start 29.9974 -16.3957)
		(end 30.3022 -16.7005)
		(width 0.17145)
		(layer "F.Cu")
		(net "SDA_DR14_R")
	)
	(segment
		(start 30.6578 -15.2273)
		(end 29.9974 -15.8877)
		(width 0.17145)
		(layer "F.Cu")
		(net "SDA_DR14_R")
	)
	(segment
		(start 30.6578 -15.2273)
		(end 29.9974 -14.5669)
		(width 0.17145)
		(layer "F.Cu")
		(net "SDA_DR14_R")
	)
	(segment
		(start 24.523446 -11.56335)
		(end 24.00935 -11.56335)
		(width 0.17145)
		(layer "F.Cu")
		(net "SDA_DR14_R")
	)
	(segment
		(start 24.00935 -11.56335)
		(end 23.855934 -11.409934)
		(width 0.17145)
		(layer "F.Cu")
		(net "SDA_DR14_R")
	)
	(segment
		(start 25.075896 -12.1158)
		(end 24.523446 -11.56335)
		(width 0.17145)
		(layer "F.Cu")
		(net "SDA_DR14_R")
	)
	(segment
		(start 29.464254 -13.34135)
		(end 27.64155 -13.34135)
		(width 0.17145)
		(layer "F.Cu")
		(net "SDA_DR14_R")
	)
	(via
		(at 30.6578 -15.2273)
		(size 0.7112)
		(drill 0.3556)
		(layers "F.Cu" "B.Cu")
		(net "SDA_DR14_R")
	)
	(segment
		(start 26.819098 -114.53495)
		(end 24.006048 -114.53495)
		(width 0.17145)
		(layer "F.Cu")
		(net "SDA_DR13_R")
	)
	(segment
		(start 24.006048 -114.53495)
		(end 23.88108 -114.409982)
		(width 0.17145)
		(layer "F.Cu")
		(net "SDA_DR13_R")
	)
	(segment
		(start 29.089604 -114.483896)
		(end 27.993848 -114.483896)
		(width 0.17145)
		(layer "F.Cu")
		(net "SDA_DR13_R")
	)
	(segment
		(start 29.4005 -114.173)
		(end 29.089604 -114.483896)
		(width 0.17145)
		(layer "F.Cu")
		(net "SDA_DR13_R")
	)
	(segment
		(start 27.432 -113.922048)
		(end 26.819098 -114.53495)
		(width 0.17145)
		(layer "F.Cu")
		(net "SDA_DR13_R")
	)
	(segment
		(start 27.993848 -114.483896)
		(end 27.432 -113.922048)
		(width 0.17145)
		(layer "F.Cu")
		(net "SDA_DR13_R")
	)
	(segment
		(start 23.88108 -114.409982)
		(end 22.800056 -114.409982)
		(width 0.17145)
		(layer "F.Cu")
		(net "SDA_DR13_R")
	)
	(via
		(at 27.432 -113.922048)
		(size 0.7112)
		(drill 0.3556)
		(layers "F.Cu" "B.Cu")
		(net "SDA_DR13_R")
	)
	(segment
		(start 28.086304 -217.5764)
		(end 29.000196 -217.5764)
		(width 0.17145)
		(layer "F.Cu")
		(net "SDA_DR12_R")
	)
	(segment
		(start 29.4005 -217.176096)
		(end 29.4005 -217.17)
		(width 0.17145)
		(layer "F.Cu")
		(net "SDA_DR12_R")
	)
	(segment
		(start 27.432 -216.922096)
		(end 26.822146 -217.53195)
		(width 0.17145)
		(layer "F.Cu")
		(net "SDA_DR12_R")
	)
	(segment
		(start 29.000196 -217.5764)
		(end 29.4005 -217.176096)
		(width 0.17145)
		(layer "F.Cu")
		(net "SDA_DR12_R")
	)
	(segment
		(start 26.822146 -217.53195)
		(end 23.99792 -217.53195)
		(width 0.17145)
		(layer "F.Cu")
		(net "SDA_DR12_R")
	)
	(segment
		(start 23.99792 -217.53195)
		(end 23.876 -217.41003)
		(width 0.17145)
		(layer "F.Cu")
		(net "SDA_DR12_R")
	)
	(segment
		(start 27.432 -216.922096)
		(end 28.086304 -217.5764)
		(width 0.17145)
		(layer "F.Cu")
		(net "SDA_DR12_R")
	)
	(segment
		(start 23.876 -217.41003)
		(end 22.800056 -217.41003)
		(width 0.17145)
		(layer "F.Cu")
		(net "SDA_DR12_R")
	)
	(via
		(at 27.432 -216.922096)
		(size 0.7112)
		(drill 0.3556)
		(layers "F.Cu" "B.Cu")
		(net "SDA_DR12_R")
	)
	(segment
		(start 26.831544 -320.5226)
		(end 23.993602 -320.5226)
		(width 0.17145)
		(layer "F.Cu")
		(net "SDA_DR11_R")
	)
	(segment
		(start 23.993602 -320.5226)
		(end 23.88108 -320.410078)
		(width 0.17145)
		(layer "F.Cu")
		(net "SDA_DR11_R")
	)
	(segment
		(start 27.432 -319.922144)
		(end 26.831544 -320.5226)
		(width 0.17145)
		(layer "F.Cu")
		(net "SDA_DR11_R")
	)
	(segment
		(start 27.432 -319.922144)
		(end 28.038806 -320.52895)
		(width 0.17145)
		(layer "F.Cu")
		(net "SDA_DR11_R")
	)
	(segment
		(start 23.88108 -320.410078)
		(end 22.800056 -320.410078)
		(width 0.17145)
		(layer "F.Cu")
		(net "SDA_DR11_R")
	)
	(segment
		(start 29.03855 -320.52895)
		(end 29.4005 -320.167)
		(width 0.17145)
		(layer "F.Cu")
		(net "SDA_DR11_R")
	)
	(segment
		(start 28.038806 -320.52895)
		(end 29.03855 -320.52895)
		(width 0.17145)
		(layer "F.Cu")
		(net "SDA_DR11_R")
	)
	(via
		(at 27.432 -319.922144)
		(size 0.7112)
		(drill 0.3556)
		(layers "F.Cu" "B.Cu")
		(net "SDA_DR11_R")
	)
	(segment
		(start 28.054808 -423.545)
		(end 29.0195 -423.545)
		(width 0.17145)
		(layer "F.Cu")
		(net "SDA_DR10_R")
	)
	(segment
		(start 24.00808 -423.410126)
		(end 22.800056 -423.410126)
		(width 0.17145)
		(layer "F.Cu")
		(net "SDA_DR10_R")
	)
	(segment
		(start 27.432 -422.922192)
		(end 28.054808 -423.545)
		(width 0.17145)
		(layer "F.Cu")
		(net "SDA_DR10_R")
	)
	(segment
		(start 26.809192 -423.545)
		(end 24.142954 -423.545)
		(width 0.17145)
		(layer "F.Cu")
		(net "SDA_DR10_R")
	)
	(segment
		(start 27.432 -422.922192)
		(end 26.809192 -423.545)
		(width 0.17145)
		(layer "F.Cu")
		(net "SDA_DR10_R")
	)
	(segment
		(start 29.0195 -423.545)
		(end 29.4005 -423.164)
		(width 0.17145)
		(layer "F.Cu")
		(net "SDA_DR10_R")
	)
	(segment
		(start 24.142954 -423.545)
		(end 24.00808 -423.410126)
		(width 0.17145)
		(layer "F.Cu")
		(net "SDA_DR10_R")
	)
	(via
		(at 27.432 -422.922192)
		(size 0.7112)
		(drill 0.3556)
		(layers "F.Cu" "B.Cu")
		(net "SDA_DR10_R")
	)
	(segment
		(start 217.846402 -391.436098)
		(end 218.926156 -391.436098)
		(width 0.17145)
		(layer "F.Cu")
		(net "SDA_DR1_R")
	)
	(segment
		(start 222.862648 -391.466324)
		(end 222.986346 -391.590022)
		(width 0.17145)
		(layer "F.Cu")
		(net "SDA_DR1_R")
	)
	(segment
		(start 219.568014 -392.077956)
		(end 220.179646 -391.466324)
		(width 0.17145)
		(layer "F.Cu")
		(net "SDA_DR1_R")
	)
	(segment
		(start 217.4875 -391.795)
		(end 217.846402 -391.436098)
		(width 0.17145)
		(layer "F.Cu")
		(net "SDA_DR1_R")
	)
	(segment
		(start 220.179646 -391.466324)
		(end 222.862648 -391.466324)
		(width 0.17145)
		(layer "F.Cu")
		(net "SDA_DR1_R")
	)
	(segment
		(start 222.986346 -391.590022)
		(end 224.199958 -391.590022)
		(width 0.17145)
		(layer "F.Cu")
		(net "SDA_DR1_R")
	)
	(segment
		(start 218.926156 -391.436098)
		(end 219.568014 -392.077956)
		(width 0.17145)
		(layer "F.Cu")
		(net "SDA_DR1_R")
	)
	(via
		(at 219.568014 -392.077956)
		(size 0.7112)
		(drill 0.3556)
		(layers "F.Cu" "B.Cu")
		(net "SDA_DR1_R")
	)
	(segment
		(start 219.009214 -492.714788)
		(end 219.009214 -493.223804)
		(width 0.17145)
		(layer "F.Cu")
		(net "SDA_DR0_R")
	)
	(segment
		(start 217.592402 -492.604298)
		(end 217.2335 -492.9632)
		(width 0.17145)
		(layer "F.Cu")
		(net "SDA_DR0_R")
	)
	(segment
		(start 224.199958 -494.59007)
		(end 222.986346 -494.59007)
		(width 0.17145)
		(layer "F.Cu")
		(net "SDA_DR0_R")
	)
	(segment
		(start 219.1766 -492.547402)
		(end 219.009214 -492.714788)
		(width 0.17145)
		(layer "F.Cu")
		(net "SDA_DR0_R")
	)
	(segment
		(start 219.009214 -493.223804)
		(end 218.389708 -492.604298)
		(width 0.17145)
		(layer "F.Cu")
		(net "SDA_DR0_R")
	)
	(segment
		(start 221.828868 -494.466372)
		(end 219.909898 -492.547402)
		(width 0.17145)
		(layer "F.Cu")
		(net "SDA_DR0_R")
	)
	(segment
		(start 222.862648 -494.466372)
		(end 221.828868 -494.466372)
		(width 0.17145)
		(layer "F.Cu")
		(net "SDA_DR0_R")
	)
	(segment
		(start 219.909898 -492.547402)
		(end 219.1766 -492.547402)
		(width 0.17145)
		(layer "F.Cu")
		(net "SDA_DR0_R")
	)
	(segment
		(start 218.389708 -492.604298)
		(end 217.592402 -492.604298)
		(width 0.17145)
		(layer "F.Cu")
		(net "SDA_DR0_R")
	)
	(segment
		(start 222.986346 -494.59007)
		(end 222.862648 -494.466372)
		(width 0.17145)
		(layer "F.Cu")
		(net "SDA_DR0_R")
	)
	(via
		(at 219.009214 -493.223804)
		(size 0.7112)
		(drill 0.3556)
		(layers "F.Cu" "B.Cu")
		(net "SDA_DR0_R")
	)
	(segment
		(start 32.5755 -81.534)
		(end 32.88665 -81.84515)
		(width 0.17145)
		(layer "F.Cu")
		(net "SCL_DR9_R")
	)
	(segment
		(start 32.88665 -81.84515)
		(end 34.073592 -81.84515)
		(width 0.17145)
		(layer "F.Cu")
		(net "SCL_DR9_R")
	)
	(segment
		(start 38.088062 -81.801716)
		(end 38.1 -81.790032)
		(width 0.17145)
		(layer "F.Cu")
		(net "SCL_DR9_R")
	)
	(segment
		(start 38.1 -81.790032)
		(end 39.200074 -81.790032)
		(width 0.17145)
		(layer "F.Cu")
		(net "SCL_DR9_R")
	)
	(segment
		(start 35.437318 -81.8642)
		(end 38.025578 -81.8642)
		(width 0.17145)
		(layer "F.Cu")
		(net "SCL_DR9_R")
	)
	(segment
		(start 34.74593 -81.172812)
		(end 35.437318 -81.8642)
		(width 0.17145)
		(layer "F.Cu")
		(net "SCL_DR9_R")
	)
	(segment
		(start 34.073592 -81.84515)
		(end 34.74593 -81.172812)
		(width 0.17145)
		(layer "F.Cu")
		(net "SCL_DR9_R")
	)
	(segment
		(start 38.025578 -81.8642)
		(end 38.088062 -81.801716)
		(width 0.17145)
		(layer "F.Cu")
		(net "SCL_DR9_R")
	)
	(via
		(at 34.74593 -81.172812)
		(size 0.7112)
		(drill 0.3556)
		(layers "F.Cu" "B.Cu")
		(net "SCL_DR9_R")
	)
	(segment
		(start 35.33902 -184.86755)
		(end 38.02253 -184.86755)
		(width 0.17145)
		(layer "F.Cu")
		(net "SCL_DR8_R")
	)
	(segment
		(start 32.9565 -184.912)
		(end 33.90519 -184.912)
		(width 0.17145)
		(layer "F.Cu")
		(net "SCL_DR8_R")
	)
	(segment
		(start 34.64433 -184.17286)
		(end 35.33902 -184.86755)
		(width 0.17145)
		(layer "F.Cu")
		(net "SCL_DR8_R")
	)
	(segment
		(start 33.90519 -184.912)
		(end 34.64433 -184.17286)
		(width 0.17145)
		(layer "F.Cu")
		(net "SCL_DR8_R")
	)
	(segment
		(start 32.5755 -184.531)
		(end 32.9565 -184.912)
		(width 0.17145)
		(layer "F.Cu")
		(net "SCL_DR8_R")
	)
	(segment
		(start 38.02253 -184.86755)
		(end 38.1 -184.79008)
		(width 0.17145)
		(layer "F.Cu")
		(net "SCL_DR8_R")
	)
	(segment
		(start 38.1 -184.79008)
		(end 39.200074 -184.79008)
		(width 0.17145)
		(layer "F.Cu")
		(net "SCL_DR8_R")
	)
	(via
		(at 34.64433 -184.17286)
		(size 0.7112)
		(drill 0.3556)
		(layers "F.Cu" "B.Cu")
		(net "SCL_DR8_R")
	)
	(segment
		(start 35.259772 -287.91535)
		(end 37.974778 -287.91535)
		(width 0.17145)
		(layer "F.Cu")
		(net "SCL_DR7_R")
	)
	(segment
		(start 32.9311 -287.8836)
		(end 33.806638 -287.8836)
		(width 0.17145)
		(layer "F.Cu")
		(net "SCL_DR7_R")
	)
	(segment
		(start 32.5755 -287.528)
		(end 32.9311 -287.8836)
		(width 0.17145)
		(layer "F.Cu")
		(net "SCL_DR7_R")
	)
	(segment
		(start 34.51733 -287.172908)
		(end 35.259772 -287.91535)
		(width 0.17145)
		(layer "F.Cu")
		(net "SCL_DR7_R")
	)
	(segment
		(start 33.806638 -287.8836)
		(end 34.51733 -287.172908)
		(width 0.17145)
		(layer "F.Cu")
		(net "SCL_DR7_R")
	)
	(segment
		(start 38.1 -287.790128)
		(end 39.200074 -287.790128)
		(width 0.17145)
		(layer "F.Cu")
		(net "SCL_DR7_R")
	)
	(segment
		(start 37.974778 -287.91535)
		(end 38.1 -287.790128)
		(width 0.17145)
		(layer "F.Cu")
		(net "SCL_DR7_R")
	)
	(via
		(at 34.51733 -287.172908)
		(size 0.7112)
		(drill 0.3556)
		(layers "F.Cu" "B.Cu")
		(net "SCL_DR7_R")
	)
	(segment
		(start 33.758886 -390.8806)
		(end 34.46653 -390.172956)
		(width 0.17145)
		(layer "F.Cu")
		(net "SCL_DR6_R")
	)
	(segment
		(start 32.9311 -390.8806)
		(end 33.758886 -390.8806)
		(width 0.17145)
		(layer "F.Cu")
		(net "SCL_DR6_R")
	)
	(segment
		(start 32.5755 -390.525)
		(end 32.9311 -390.8806)
		(width 0.17145)
		(layer "F.Cu")
		(net "SCL_DR6_R")
	)
	(segment
		(start 38.1 -390.790176)
		(end 39.200074 -390.790176)
		(width 0.17145)
		(layer "F.Cu")
		(net "SCL_DR6_R")
	)
	(segment
		(start 35.224974 -390.9314)
		(end 37.958776 -390.9314)
		(width 0.17145)
		(layer "F.Cu")
		(net "SCL_DR6_R")
	)
	(segment
		(start 37.958776 -390.9314)
		(end 38.1 -390.790176)
		(width 0.17145)
		(layer "F.Cu")
		(net "SCL_DR6_R")
	)
	(segment
		(start 34.46653 -390.172956)
		(end 35.224974 -390.9314)
		(width 0.17145)
		(layer "F.Cu")
		(net "SCL_DR6_R")
	)
	(via
		(at 34.46653 -390.172956)
		(size 0.7112)
		(drill 0.3556)
		(layers "F.Cu" "B.Cu")
		(net "SCL_DR6_R")
	)
	(segment
		(start 37.973 -493.790224)
		(end 39.200074 -493.790224)
		(width 0.17145)
		(layer "F.Cu")
		(net "SCL_DR5_R")
	)
	(segment
		(start 34.766504 -491.5916)
		(end 37.052504 -493.8776)
		(width 0.17145)
		(layer "F.Cu")
		(net "SCL_DR5_R")
	)
	(segment
		(start 32.1437 -491.2614)
		(end 32.48025 -491.59795)
		(width 0.17145)
		(layer "F.Cu")
		(net "SCL_DR5_R")
	)
	(segment
		(start 37.885624 -493.8776)
		(end 37.973 -493.790224)
		(width 0.17145)
		(layer "F.Cu")
		(net "SCL_DR5_R")
	)
	(segment
		(start 37.052504 -493.8776)
		(end 37.885624 -493.8776)
		(width 0.17145)
		(layer "F.Cu")
		(net "SCL_DR5_R")
	)
	(segment
		(start 32.815784 -491.59795)
		(end 33.47593 -490.937804)
		(width 0.17145)
		(layer "F.Cu")
		(net "SCL_DR5_R")
	)
	(segment
		(start 34.129726 -491.5916)
		(end 34.766504 -491.5916)
		(width 0.17145)
		(layer "F.Cu")
		(net "SCL_DR5_R")
	)
	(segment
		(start 33.47593 -490.937804)
		(end 34.129726 -491.5916)
		(width 0.17145)
		(layer "F.Cu")
		(net "SCL_DR5_R")
	)
	(segment
		(start 32.48025 -491.59795)
		(end 32.815784 -491.59795)
		(width 0.17145)
		(layer "F.Cu")
		(net "SCL_DR5_R")
	)
	(via
		(at 33.47593 -490.937804)
		(size 0.7112)
		(drill 0.3556)
		(layers "F.Cu" "B.Cu")
		(net "SCL_DR5_R")
	)
	(segment
		(start 217.846148 -81.892648)
		(end 218.721178 -81.892648)
		(width 0.17145)
		(layer "F.Cu")
		(net "SCL_DR4_R")
	)
	(segment
		(start 222.862648 -81.91373)
		(end 222.986346 -81.790032)
		(width 0.17145)
		(layer "F.Cu")
		(net "SCL_DR4_R")
	)
	(segment
		(start 218.721178 -81.892648)
		(end 219.441014 -81.172812)
		(width 0.17145)
		(layer "F.Cu")
		(net "SCL_DR4_R")
	)
	(segment
		(start 219.441014 -81.172812)
		(end 220.181932 -81.91373)
		(width 0.17145)
		(layer "F.Cu")
		(net "SCL_DR4_R")
	)
	(segment
		(start 217.4875 -81.534)
		(end 217.846148 -81.892648)
		(width 0.17145)
		(layer "F.Cu")
		(net "SCL_DR4_R")
	)
	(segment
		(start 220.181932 -81.91373)
		(end 222.862648 -81.91373)
		(width 0.17145)
		(layer "F.Cu")
		(net "SCL_DR4_R")
	)
	(segment
		(start 222.986346 -81.790032)
		(end 224.199958 -81.790032)
		(width 0.17145)
		(layer "F.Cu")
		(net "SCL_DR4_R")
	)
	(via
		(at 219.441014 -81.172812)
		(size 0.7112)
		(drill 0.3556)
		(layers "F.Cu" "B.Cu")
		(net "SCL_DR4_R")
	)
	(segment
		(start 218.698826 -184.889648)
		(end 219.415614 -184.17286)
		(width 0.17145)
		(layer "F.Cu")
		(net "SCL_DR3_R")
	)
	(segment
		(start 219.415614 -184.17286)
		(end 220.156532 -184.913778)
		(width 0.17145)
		(layer "F.Cu")
		(net "SCL_DR3_R")
	)
	(segment
		(start 222.986346 -184.79008)
		(end 224.199958 -184.79008)
		(width 0.17145)
		(layer "F.Cu")
		(net "SCL_DR3_R")
	)
	(segment
		(start 220.156532 -184.913778)
		(end 222.862648 -184.913778)
		(width 0.17145)
		(layer "F.Cu")
		(net "SCL_DR3_R")
	)
	(segment
		(start 222.862648 -184.913778)
		(end 222.986346 -184.79008)
		(width 0.17145)
		(layer "F.Cu")
		(net "SCL_DR3_R")
	)
	(segment
		(start 217.846148 -184.889648)
		(end 218.698826 -184.889648)
		(width 0.17145)
		(layer "F.Cu")
		(net "SCL_DR3_R")
	)
	(segment
		(start 217.4875 -184.531)
		(end 217.846148 -184.889648)
		(width 0.17145)
		(layer "F.Cu")
		(net "SCL_DR3_R")
	)
	(via
		(at 219.415614 -184.17286)
		(size 0.7112)
		(drill 0.3556)
		(layers "F.Cu" "B.Cu")
		(net "SCL_DR3_R")
	)
	(segment
		(start 217.808556 -287.849056)
		(end 218.841066 -287.849056)
		(width 0.17145)
		(layer "F.Cu")
		(net "SCL_DR2_R")
	)
	(segment
		(start 219.517214 -287.172908)
		(end 220.258132 -287.913826)
		(width 0.17145)
		(layer "F.Cu")
		(net "SCL_DR2_R")
	)
	(segment
		(start 222.986346 -287.790128)
		(end 224.199958 -287.790128)
		(width 0.17145)
		(layer "F.Cu")
		(net "SCL_DR2_R")
	)
	(segment
		(start 217.4875 -287.528)
		(end 217.808556 -287.849056)
		(width 0.17145)
		(layer "F.Cu")
		(net "SCL_DR2_R")
	)
	(segment
		(start 218.841066 -287.849056)
		(end 219.517214 -287.172908)
		(width 0.17145)
		(layer "F.Cu")
		(net "SCL_DR2_R")
	)
	(segment
		(start 222.862648 -287.913826)
		(end 222.986346 -287.790128)
		(width 0.17145)
		(layer "F.Cu")
		(net "SCL_DR2_R")
	)
	(segment
		(start 220.258132 -287.913826)
		(end 222.862648 -287.913826)
		(width 0.17145)
		(layer "F.Cu")
		(net "SCL_DR2_R")
	)
	(via
		(at 219.517214 -287.172908)
		(size 0.7112)
		(drill 0.3556)
		(layers "F.Cu" "B.Cu")
		(net "SCL_DR2_R")
	)
	(segment
		(start 29.2354 -13.8938)
		(end 27.412696 -13.8938)
		(width 0.17145)
		(layer "F.Cu")
		(net "SCL_DR14_R")
	)
	(segment
		(start 28.7528 -15.2273)
		(end 29.44495 -15.91945)
		(width 0.17145)
		(layer "F.Cu")
		(net "SCL_DR14_R")
	)
	(segment
		(start 24.294592 -12.1158)
		(end 23.974806 -12.1158)
		(width 0.17145)
		(layer "F.Cu")
		(net "SCL_DR14_R")
	)
	(segment
		(start 27.412696 -13.8938)
		(end 26.1874 -12.668504)
		(width 0.17145)
		(layer "F.Cu")
		(net "SCL_DR14_R")
	)
	(segment
		(start 29.44495 -14.10335)
		(end 29.2354 -13.8938)
		(width 0.17145)
		(layer "F.Cu")
		(net "SCL_DR14_R")
	)
	(segment
		(start 29.44495 -15.91945)
		(end 29.44495 -16.28775)
		(width 0.17145)
		(layer "F.Cu")
		(net "SCL_DR14_R")
	)
	(segment
		(start 23.974806 -12.1158)
		(end 23.880826 -12.20978)
		(width 0.17145)
		(layer "F.Cu")
		(net "SCL_DR14_R")
	)
	(segment
		(start 29.44495 -14.53515)
		(end 29.44495 -14.10335)
		(width 0.17145)
		(layer "F.Cu")
		(net "SCL_DR14_R")
	)
	(segment
		(start 29.44495 -16.28775)
		(end 29.0322 -16.7005)
		(width 0.17145)
		(layer "F.Cu")
		(net "SCL_DR14_R")
	)
	(segment
		(start 26.1874 -12.668504)
		(end 24.847296 -12.668504)
		(width 0.17145)
		(layer "F.Cu")
		(net "SCL_DR14_R")
	)
	(segment
		(start 23.880826 -12.20978)
		(end 22.800056 -12.20978)
		(width 0.17145)
		(layer "F.Cu")
		(net "SCL_DR14_R")
	)
	(segment
		(start 28.7528 -15.2273)
		(end 29.44495 -14.53515)
		(width 0.17145)
		(layer "F.Cu")
		(net "SCL_DR14_R")
	)
	(segment
		(start 24.847296 -12.668504)
		(end 24.294592 -12.1158)
		(width 0.17145)
		(layer "F.Cu")
		(net "SCL_DR14_R")
	)
	(via
		(at 28.7528 -15.2273)
		(size 0.7112)
		(drill 0.3556)
		(layers "F.Cu" "B.Cu")
		(net "SCL_DR14_R")
	)
	(segment
		(start 24.003254 -115.0874)
		(end 23.880826 -115.209828)
		(width 0.17145)
		(layer "F.Cu")
		(net "SCL_DR13_R")
	)
	(segment
		(start 27.432 -115.827048)
		(end 28.222702 -115.036346)
		(width 0.17145)
		(layer "F.Cu")
		(net "SCL_DR13_R")
	)
	(segment
		(start 28.222702 -115.036346)
		(end 28.993846 -115.036346)
		(width 0.17145)
		(layer "F.Cu")
		(net "SCL_DR13_R")
	)
	(segment
		(start 27.432 -115.827048)
		(end 26.692352 -115.0874)
		(width 0.17145)
		(layer "F.Cu")
		(net "SCL_DR13_R")
	)
	(segment
		(start 23.880826 -115.209828)
		(end 22.800056 -115.209828)
		(width 0.17145)
		(layer "F.Cu")
		(net "SCL_DR13_R")
	)
	(segment
		(start 28.993846 -115.036346)
		(end 29.4005 -115.443)
		(width 0.17145)
		(layer "F.Cu")
		(net "SCL_DR13_R")
	)
	(segment
		(start 26.692352 -115.0874)
		(end 24.003254 -115.0874)
		(width 0.17145)
		(layer "F.Cu")
		(net "SCL_DR13_R")
	)
	(via
		(at 27.432 -115.827048)
		(size 0.7112)
		(drill 0.3556)
		(layers "F.Cu" "B.Cu")
		(net "SCL_DR13_R")
	)
	(segment
		(start 27.432 -218.827096)
		(end 28.130246 -218.12885)
		(width 0.17145)
		(layer "F.Cu")
		(net "SCL_DR12_R")
	)
	(segment
		(start 23.880826 -218.209876)
		(end 22.800056 -218.209876)
		(width 0.17145)
		(layer "F.Cu")
		(net "SCL_DR12_R")
	)
	(segment
		(start 28.130246 -218.12885)
		(end 29.08935 -218.12885)
		(width 0.17145)
		(layer "F.Cu")
		(net "SCL_DR12_R")
	)
	(segment
		(start 29.08935 -218.12885)
		(end 29.4005 -218.44)
		(width 0.17145)
		(layer "F.Cu")
		(net "SCL_DR12_R")
	)
	(segment
		(start 24.006302 -218.0844)
		(end 23.880826 -218.209876)
		(width 0.17145)
		(layer "F.Cu")
		(net "SCL_DR12_R")
	)
	(segment
		(start 26.689304 -218.0844)
		(end 24.006302 -218.0844)
		(width 0.17145)
		(layer "F.Cu")
		(net "SCL_DR12_R")
	)
	(segment
		(start 27.432 -218.827096)
		(end 26.689304 -218.0844)
		(width 0.17145)
		(layer "F.Cu")
		(net "SCL_DR12_R")
	)
	(via
		(at 27.432 -218.827096)
		(size 0.7112)
		(drill 0.3556)
		(layers "F.Cu" "B.Cu")
		(net "SCL_DR12_R")
	)
	(segment
		(start 27.432 -321.827144)
		(end 26.679906 -321.07505)
		(width 0.17145)
		(layer "F.Cu")
		(net "SCL_DR11_R")
	)
	(segment
		(start 29.0449 -321.0814)
		(end 29.4005 -321.437)
		(width 0.17145)
		(layer "F.Cu")
		(net "SCL_DR11_R")
	)
	(segment
		(start 24.0157 -321.07505)
		(end 23.880826 -321.209924)
		(width 0.17145)
		(layer "F.Cu")
		(net "SCL_DR11_R")
	)
	(segment
		(start 28.177744 -321.0814)
		(end 29.0449 -321.0814)
		(width 0.17145)
		(layer "F.Cu")
		(net "SCL_DR11_R")
	)
	(segment
		(start 23.880826 -321.209924)
		(end 22.800056 -321.209924)
		(width 0.17145)
		(layer "F.Cu")
		(net "SCL_DR11_R")
	)
	(segment
		(start 26.679906 -321.07505)
		(end 24.0157 -321.07505)
		(width 0.17145)
		(layer "F.Cu")
		(net "SCL_DR11_R")
	)
	(segment
		(start 27.432 -321.827144)
		(end 28.177744 -321.0814)
		(width 0.17145)
		(layer "F.Cu")
		(net "SCL_DR11_R")
	)
	(via
		(at 27.432 -321.827144)
		(size 0.7112)
		(drill 0.3556)
		(layers "F.Cu" "B.Cu")
		(net "SCL_DR11_R")
	)
	(segment
		(start 27.432 -424.827192)
		(end 28.161742 -424.09745)
		(width 0.17145)
		(layer "F.Cu")
		(net "SCL_DR10_R")
	)
	(segment
		(start 28.161742 -424.09745)
		(end 29.06395 -424.09745)
		(width 0.17145)
		(layer "F.Cu")
		(net "SCL_DR10_R")
	)
	(segment
		(start 24.007826 -424.209972)
		(end 22.800056 -424.209972)
		(width 0.17145)
		(layer "F.Cu")
		(net "SCL_DR10_R")
	)
	(segment
		(start 27.432 -424.827192)
		(end 26.702258 -424.09745)
		(width 0.17145)
		(layer "F.Cu")
		(net "SCL_DR10_R")
	)
	(segment
		(start 29.06395 -424.09745)
		(end 29.4005 -424.434)
		(width 0.17145)
		(layer "F.Cu")
		(net "SCL_DR10_R")
	)
	(segment
		(start 26.702258 -424.09745)
		(end 24.120348 -424.09745)
		(width 0.17145)
		(layer "F.Cu")
		(net "SCL_DR10_R")
	)
	(segment
		(start 24.120348 -424.09745)
		(end 24.007826 -424.209972)
		(width 0.17145)
		(layer "F.Cu")
		(net "SCL_DR10_R")
	)
	(via
		(at 27.432 -424.827192)
		(size 0.7112)
		(drill 0.3556)
		(layers "F.Cu" "B.Cu")
		(net "SCL_DR10_R")
	)
	(segment
		(start 222.986346 -390.790176)
		(end 222.862648 -390.913874)
		(width 0.17145)
		(layer "F.Cu")
		(net "SCL_DR1_R")
	)
	(segment
		(start 219.568014 -390.172956)
		(end 218.857322 -390.883648)
		(width 0.17145)
		(layer "F.Cu")
		(net "SCL_DR1_R")
	)
	(segment
		(start 220.308932 -390.913874)
		(end 219.568014 -390.172956)
		(width 0.17145)
		(layer "F.Cu")
		(net "SCL_DR1_R")
	)
	(segment
		(start 222.862648 -390.913874)
		(end 220.308932 -390.913874)
		(width 0.17145)
		(layer "F.Cu")
		(net "SCL_DR1_R")
	)
	(segment
		(start 224.199958 -390.790176)
		(end 222.986346 -390.790176)
		(width 0.17145)
		(layer "F.Cu")
		(net "SCL_DR1_R")
	)
	(segment
		(start 218.857322 -390.883648)
		(end 217.846148 -390.883648)
		(width 0.17145)
		(layer "F.Cu")
		(net "SCL_DR1_R")
	)
	(segment
		(start 217.846148 -390.883648)
		(end 217.4875 -390.525)
		(width 0.17145)
		(layer "F.Cu")
		(net "SCL_DR1_R")
	)
	(via
		(at 219.568014 -390.172956)
		(size 0.7112)
		(drill 0.3556)
		(layers "F.Cu" "B.Cu")
		(net "SCL_DR1_R")
	)
	(segment
		(start 224.199958 -493.790224)
		(end 222.986346 -493.790224)
		(width 0.17145)
		(layer "F.Cu")
		(net "SCL_DR0_R")
	)
	(segment
		(start 222.057722 -493.913922)
		(end 220.138752 -491.994952)
		(width 0.17145)
		(layer "F.Cu")
		(net "SCL_DR0_R")
	)
	(segment
		(start 219.009214 -491.802166)
		(end 219.009214 -491.318804)
		(width 0.17145)
		(layer "F.Cu")
		(net "SCL_DR0_R")
	)
	(segment
		(start 217.592148 -492.051848)
		(end 217.2335 -491.6932)
		(width 0.17145)
		(layer "F.Cu")
		(net "SCL_DR0_R")
	)
	(segment
		(start 222.862648 -493.913922)
		(end 222.057722 -493.913922)
		(width 0.17145)
		(layer "F.Cu")
		(net "SCL_DR0_R")
	)
	(segment
		(start 220.138752 -491.994952)
		(end 219.202 -491.994952)
		(width 0.17145)
		(layer "F.Cu")
		(net "SCL_DR0_R")
	)
	(segment
		(start 222.986346 -493.790224)
		(end 222.862648 -493.913922)
		(width 0.17145)
		(layer "F.Cu")
		(net "SCL_DR0_R")
	)
	(segment
		(start 219.202 -491.994952)
		(end 219.009214 -491.802166)
		(width 0.17145)
		(layer "F.Cu")
		(net "SCL_DR0_R")
	)
	(segment
		(start 218.27617 -492.051848)
		(end 217.592148 -492.051848)
		(width 0.17145)
		(layer "F.Cu")
		(net "SCL_DR0_R")
	)
	(segment
		(start 219.009214 -491.318804)
		(end 218.27617 -492.051848)
		(width 0.17145)
		(layer "F.Cu")
		(net "SCL_DR0_R")
	)
	(via
		(at 219.009214 -491.318804)
		(size 0.7112)
		(drill 0.3556)
		(layers "F.Cu" "B.Cu")
		(net "SCL_DR0_R")
	)
	(segment
		(start 75.449938 -359.0798)
		(end 75.449938 -358.380538)
		(width 0.17145)
		(layer "F.Cu")
		(net "I2C8_SDA_R_SW_EU17")
	)
	(segment
		(start 75.449938 -358.380538)
		(end 74.4728 -357.4034)
		(width 0.17145)
		(layer "F.Cu")
		(net "I2C8_SDA_R_SW_EU17")
	)
	(segment
		(start 73.914 -356.0826)
		(end 73.914 -355.4095)
		(width 0.17145)
		(layer "F.Cu")
		(net "I2C8_SDA_R_SW_EU17")
	)
	(segment
		(start 74.4728 -357.4034)
		(end 74.4728 -357.1494)
		(width 0.17145)
		(layer "F.Cu")
		(net "I2C8_SDA_R_SW_EU17")
	)
	(segment
		(start 74.4728 -356.6414)
		(end 73.914 -356.0826)
		(width 0.17145)
		(layer "F.Cu")
		(net "I2C8_SDA_R_SW_EU17")
	)
	(segment
		(start 74.4728 -357.1494)
		(end 74.4728 -356.6414)
		(width 0.17145)
		(layer "F.Cu")
		(net "I2C8_SDA_R_SW_EU17")
	)
	(via
		(at 74.4728 -357.1494)
		(size 0.7112)
		(drill 0.3556)
		(layers "F.Cu" "B.Cu")
		(net "I2C8_SDA_R_SW_EU17")
	)
	(segment
		(start 80.518 -146.431)
		(end 80.01 -146.939)
		(width 0.17145)
		(layer "F.Cu")
		(net "I2C8_SDA_R_SW_EU16")
	)
	(segment
		(start 79.95158 -146.939)
		(end 80.01 -146.939)
		(width 0.17145)
		(layer "F.Cu")
		(net "I2C8_SDA_R_SW_EU16")
	)
	(segment
		(start 78.923642 -147.966938)
		(end 79.95158 -146.939)
		(width 0.17145)
		(layer "F.Cu")
		(net "I2C8_SDA_R_SW_EU16")
	)
	(segment
		(start 78.1812 -147.966938)
		(end 78.923642 -147.966938)
		(width 0.17145)
		(layer "F.Cu")
		(net "I2C8_SDA_R_SW_EU16")
	)
	(segment
		(start 81.3435 -146.431)
		(end 80.518 -146.431)
		(width 0.17145)
		(layer "F.Cu")
		(net "I2C8_SDA_R_SW_EU16")
	)
	(via
		(at 80.01 -146.939)
		(size 0.7112)
		(drill 0.3556)
		(layers "F.Cu" "B.Cu")
		(net "I2C8_SDA_R_SW_EU16")
	)
	(segment
		(start 74.950066 -358.66197)
		(end 74.950066 -359.0036)
		(width 0.17145)
		(layer "F.Cu")
		(net "I2C8_SCL_R_SW_EU17")
	)
	(segment
		(start 72.5678 -356.8954)
		(end 72.9234 -357.251)
		(width 0.17145)
		(layer "F.Cu")
		(net "I2C8_SCL_R_SW_EU17")
	)
	(segment
		(start 72.5678 -356.6414)
		(end 72.5678 -356.8954)
		(width 0.17145)
		(layer "F.Cu")
		(net "I2C8_SCL_R_SW_EU17")
	)
	(segment
		(start 73.539096 -357.251)
		(end 74.950066 -358.66197)
		(width 0.17145)
		(layer "F.Cu")
		(net "I2C8_SCL_R_SW_EU17")
	)
	(segment
		(start 72.5678 -356.2096)
		(end 72.5678 -356.6414)
		(width 0.17145)
		(layer "F.Cu")
		(net "I2C8_SCL_R_SW_EU17")
	)
	(segment
		(start 72.898 -355.4095)
		(end 72.898 -355.8794)
		(width 0.17145)
		(layer "F.Cu")
		(net "I2C8_SCL_R_SW_EU17")
	)
	(segment
		(start 72.9234 -357.251)
		(end 73.539096 -357.251)
		(width 0.17145)
		(layer "F.Cu")
		(net "I2C8_SCL_R_SW_EU17")
	)
	(segment
		(start 72.898 -355.8794)
		(end 72.5678 -356.2096)
		(width 0.17145)
		(layer "F.Cu")
		(net "I2C8_SCL_R_SW_EU17")
	)
	(via
		(at 72.5678 -356.6414)
		(size 0.7112)
		(drill 0.3556)
		(layers "F.Cu" "B.Cu")
		(net "I2C8_SCL_R_SW_EU17")
	)
	(segment
		(start 78.2574 -147.467066)
		(end 78.64221 -147.467066)
		(width 0.17145)
		(layer "F.Cu")
		(net "I2C8_SCL_R_SW_EU16")
	)
	(segment
		(start 80.391 -145.415)
		(end 80.01 -145.034)
		(width 0.17145)
		(layer "F.Cu")
		(net "I2C8_SCL_R_SW_EU16")
	)
	(segment
		(start 78.64221 -147.467066)
		(end 80.01 -146.099276)
		(width 0.17145)
		(layer "F.Cu")
		(net "I2C8_SCL_R_SW_EU16")
	)
	(segment
		(start 80.01 -146.099276)
		(end 80.01 -145.034)
		(width 0.17145)
		(layer "F.Cu")
		(net "I2C8_SCL_R_SW_EU16")
	)
	(segment
		(start 81.3435 -145.415)
		(end 80.391 -145.415)
		(width 0.17145)
		(layer "F.Cu")
		(net "I2C8_SCL_R_SW_EU16")
	)
	(via
		(at 80.01 -145.034)
		(size 0.7112)
		(drill 0.3556)
		(layers "F.Cu" "B.Cu")
		(net "I2C8_SCL_R_SW_EU16")
	)
	(segment
		(start 89.55659 -303.43094)
		(end 88.90127 -303.43094)
		(width 0.17145)
		(layer "F.Cu")
		(net "I2C_SDA_BUF_9_EU2_R")
	)
	(segment
		(start 88.90127 -303.43094)
		(end 88.8492 -303.48301)
		(width 0.17145)
		(layer "F.Cu")
		(net "I2C_SDA_BUF_9_EU2_R")
	)
	(segment
		(start 86.995 -301.371)
		(end 87.122 -301.498)
		(width 0.17145)
		(layer "F.Cu")
		(net "I2C_SDA_BUF_9_EU2_R")
	)
	(segment
		(start 87.22995 -302.34255)
		(end 87.22995 -301.60595)
		(width 0.17145)
		(layer "F.Cu")
		(net "I2C_SDA_BUF_9_EU2_R")
	)
	(segment
		(start 88.37041 -303.48301)
		(end 87.22995 -302.34255)
		(width 0.17145)
		(layer "F.Cu")
		(net "I2C_SDA_BUF_9_EU2_R")
	)
	(segment
		(start 88.8492 -303.48301)
		(end 88.37041 -303.48301)
		(width 0.17145)
		(layer "F.Cu")
		(net "I2C_SDA_BUF_9_EU2_R")
	)
	(segment
		(start 84.8995 -301.371)
		(end 86.995 -301.371)
		(width 0.17145)
		(layer "F.Cu")
		(net "I2C_SDA_BUF_9_EU2_R")
	)
	(segment
		(start 87.22995 -301.60595)
		(end 87.122 -301.498)
		(width 0.17145)
		(layer "F.Cu")
		(net "I2C_SDA_BUF_9_EU2_R")
	)
	(via
		(at 87.122 -301.498)
		(size 0.7112)
		(drill 0.3556)
		(layers "F.Cu" "B.Cu")
		(net "I2C_SDA_BUF_9_EU2_R")
	)
	(segment
		(start 87.0458 -428.187104)
		(end 86.385146 -427.52645)
		(width 0.17145)
		(layer "F.Cu")
		(net "I2C_SDA_BUF_9_EU1_R")
	)
	(segment
		(start 85.36305 -427.52645)
		(end 84.8995 -427.99)
		(width 0.17145)
		(layer "F.Cu")
		(net "I2C_SDA_BUF_9_EU1_R")
	)
	(segment
		(start 87.0458 -428.5488)
		(end 88.54694 -430.04994)
		(width 0.17145)
		(layer "F.Cu")
		(net "I2C_SDA_BUF_9_EU1_R")
	)
	(segment
		(start 88.54694 -430.04994)
		(end 89.55659 -430.04994)
		(width 0.17145)
		(layer "F.Cu")
		(net "I2C_SDA_BUF_9_EU1_R")
	)
	(segment
		(start 86.385146 -427.52645)
		(end 85.36305 -427.52645)
		(width 0.17145)
		(layer "F.Cu")
		(net "I2C_SDA_BUF_9_EU1_R")
	)
	(segment
		(start 87.0458 -428.2948)
		(end 87.0458 -428.5488)
		(width 0.17145)
		(layer "F.Cu")
		(net "I2C_SDA_BUF_9_EU1_R")
	)
	(segment
		(start 87.0458 -428.2948)
		(end 87.0458 -428.187104)
		(width 0.17145)
		(layer "F.Cu")
		(net "I2C_SDA_BUF_9_EU1_R")
	)
	(via
		(at 87.0458 -428.2948)
		(size 0.7112)
		(drill 0.3556)
		(layers "F.Cu" "B.Cu")
		(net "I2C_SDA_BUF_9_EU1_R")
	)
	(segment
		(start 88.599264 -302.93056)
		(end 89.55659 -302.93056)
		(width 0.17145)
		(layer "F.Cu")
		(net "I2C_SCL_BUF_9_EU2_R")
	)
	(segment
		(start 85.598 -300.355)
		(end 86.106 -299.847)
		(width 0.17145)
		(layer "F.Cu")
		(net "I2C_SCL_BUF_9_EU2_R")
	)
	(segment
		(start 87.33155 -300.81855)
		(end 87.7824 -301.2694)
		(width 0.17145)
		(layer "F.Cu")
		(net "I2C_SCL_BUF_9_EU2_R")
	)
	(segment
		(start 87.07755 -300.81855)
		(end 87.33155 -300.81855)
		(width 0.17145)
		(layer "F.Cu")
		(net "I2C_SCL_BUF_9_EU2_R")
	)
	(segment
		(start 87.7824 -302.113696)
		(end 88.599264 -302.93056)
		(width 0.17145)
		(layer "F.Cu")
		(net "I2C_SCL_BUF_9_EU2_R")
	)
	(segment
		(start 87.7824 -301.2694)
		(end 87.7824 -302.113696)
		(width 0.17145)
		(layer "F.Cu")
		(net "I2C_SCL_BUF_9_EU2_R")
	)
	(segment
		(start 86.106 -299.847)
		(end 87.07755 -300.81855)
		(width 0.17145)
		(layer "F.Cu")
		(net "I2C_SCL_BUF_9_EU2_R")
	)
	(segment
		(start 84.8995 -300.355)
		(end 85.598 -300.355)
		(width 0.17145)
		(layer "F.Cu")
		(net "I2C_SCL_BUF_9_EU2_R")
	)
	(via
		(at 86.106 -299.847)
		(size 0.7112)
		(drill 0.3556)
		(layers "F.Cu" "B.Cu")
		(net "I2C_SCL_BUF_9_EU2_R")
	)
	(segment
		(start 87.66683 -428.388526)
		(end 88.827864 -429.54956)
		(width 0.17145)
		(layer "F.Cu")
		(net "I2C_SCL_BUF_9_EU1_R")
	)
	(segment
		(start 86.2584 -426.6184)
		(end 87.66683 -428.02683)
		(width 0.17145)
		(layer "F.Cu")
		(net "I2C_SCL_BUF_9_EU1_R")
	)
	(segment
		(start 88.827864 -429.54956)
		(end 89.55659 -429.54956)
		(width 0.17145)
		(layer "F.Cu")
		(net "I2C_SCL_BUF_9_EU1_R")
	)
	(segment
		(start 86.1314 -426.6184)
		(end 85.9536 -426.6184)
		(width 0.17145)
		(layer "F.Cu")
		(net "I2C_SCL_BUF_9_EU1_R")
	)
	(segment
		(start 87.66683 -428.02683)
		(end 87.66683 -428.388526)
		(width 0.17145)
		(layer "F.Cu")
		(net "I2C_SCL_BUF_9_EU1_R")
	)
	(segment
		(start 85.9536 -426.6184)
		(end 85.598 -426.974)
		(width 0.17145)
		(layer "F.Cu")
		(net "I2C_SCL_BUF_9_EU1_R")
	)
	(segment
		(start 85.598 -426.974)
		(end 84.8995 -426.974)
		(width 0.17145)
		(layer "F.Cu")
		(net "I2C_SCL_BUF_9_EU1_R")
	)
	(segment
		(start 86.1314 -426.6184)
		(end 86.2584 -426.6184)
		(width 0.17145)
		(layer "F.Cu")
		(net "I2C_SCL_BUF_9_EU1_R")
	)
	(via
		(at 86.1314 -426.6184)
		(size 0.7112)
		(drill 0.3556)
		(layers "F.Cu" "B.Cu")
		(net "I2C_SCL_BUF_9_EU1_R")
	)
	(segment
		(start 102.616 -99.568)
		(end 103.124 -100.076)
		(width 0.17145)
		(layer "F.Cu")
		(net "CLK_BUFFER_EU4_VOE_N")
	)
	(segment
		(start 102.0445 -103.3145)
		(end 101.092 -103.3145)
		(width 0.17145)
		(layer "F.Cu")
		(net "CLK_BUFFER_EU4_VOE_N")
	)
	(segment
		(start 99.568 -103.632)
		(end 99.34956 -103.85044)
		(width 0.17145)
		(layer "F.Cu")
		(net "CLK_BUFFER_EU4_VOE_N")
	)
	(segment
		(start 103.124 -102.235)
		(end 102.0445 -103.3145)
		(width 0.17145)
		(layer "F.Cu")
		(net "CLK_BUFFER_EU4_VOE_N")
	)
	(segment
		(start 99.568 -103.47706)
		(end 99.568 -103.632)
		(width 0.17145)
		(layer "F.Cu")
		(net "CLK_BUFFER_EU4_VOE_N")
	)
	(segment
		(start 99.34956 -103.85044)
		(end 98.40341 -103.85044)
		(width 0.17145)
		(layer "F.Cu")
		(net "CLK_BUFFER_EU4_VOE_N")
	)
	(segment
		(start 101.05644 -103.35006)
		(end 101.092 -103.3145)
		(width 0.17145)
		(layer "F.Cu")
		(net "CLK_BUFFER_EU4_VOE_N")
	)
	(segment
		(start 100.076 -99.568)
		(end 99.79406 -99.84994)
		(width 0.17145)
		(layer "F.Cu")
		(net "CLK_BUFFER_EU4_VOE_N")
	)
	(segment
		(start 98.40341 -99.34956)
		(end 99.85756 -99.34956)
		(width 0.17145)
		(layer "F.Cu")
		(net "CLK_BUFFER_EU4_VOE_N")
	)
	(segment
		(start 103.124 -101.346)
		(end 103.124 -102.235)
		(width 0.17145)
		(layer "F.Cu")
		(net "CLK_BUFFER_EU4_VOE_N")
	)
	(segment
		(start 99.695 -103.35006)
		(end 101.05644 -103.35006)
		(width 0.17145)
		(layer "F.Cu")
		(net "CLK_BUFFER_EU4_VOE_N")
	)
	(segment
		(start 99.79406 -99.84994)
		(end 98.40341 -99.84994)
		(width 0.17145)
		(layer "F.Cu")
		(net "CLK_BUFFER_EU4_VOE_N")
	)
	(segment
		(start 99.695 -103.35006)
		(end 99.568 -103.47706)
		(width 0.17145)
		(layer "F.Cu")
		(net "CLK_BUFFER_EU4_VOE_N")
	)
	(segment
		(start 100.076 -99.568)
		(end 102.616 -99.568)
		(width 0.17145)
		(layer "F.Cu")
		(net "CLK_BUFFER_EU4_VOE_N")
	)
	(segment
		(start 103.124 -100.076)
		(end 103.124 -101.346)
		(width 0.17145)
		(layer "F.Cu")
		(net "CLK_BUFFER_EU4_VOE_N")
	)
	(segment
		(start 98.40341 -103.35006)
		(end 99.695 -103.35006)
		(width 0.17145)
		(layer "F.Cu")
		(net "CLK_BUFFER_EU4_VOE_N")
	)
	(segment
		(start 99.85756 -99.34956)
		(end 100.076 -99.568)
		(width 0.17145)
		(layer "F.Cu")
		(net "CLK_BUFFER_EU4_VOE_N")
	)
	(via
		(at 103.124 -101.346)
		(size 0.7112)
		(drill 0.3556)
		(layers "F.Cu" "B.Cu")
		(net "CLK_BUFFER_EU4_VOE_N")
	)
	(segment
		(start 91.72956 -205.51648)
		(end 91.72956 -206.39659)
		(width 0.17145)
		(layer "F.Cu")
		(net "CLK_BUFFER_EU3_VOE_N")
	)
	(segment
		(start 102.108 -214.376)
		(end 101.854 -214.376)
		(width 0.17145)
		(layer "F.Cu")
		(net "CLK_BUFFER_EU3_VOE_N")
	)
	(segment
		(start 100.9015 -213.487)
		(end 100.203 -213.487)
		(width 0.17145)
		(layer "F.Cu")
		(net "CLK_BUFFER_EU3_VOE_N")
	)
	(segment
		(start 101.854 -214.376)
		(end 100.965 -213.487)
		(width 0.17145)
		(layer "F.Cu")
		(net "CLK_BUFFER_EU3_VOE_N")
	)
	(segment
		(start 91.4654 -205.25232)
		(end 91.72956 -205.51648)
		(width 0.17145)
		(layer "F.Cu")
		(net "CLK_BUFFER_EU3_VOE_N")
	)
	(segment
		(start 99.34956 -213.07044)
		(end 98.40341 -213.07044)
		(width 0.17145)
		(layer "F.Cu")
		(net "CLK_BUFFER_EU3_VOE_N")
	)
	(segment
		(start 91.23045 -206.39659)
		(end 91.23045 -205.48727)
		(width 0.17145)
		(layer "F.Cu")
		(net "CLK_BUFFER_EU3_VOE_N")
	)
	(segment
		(start 99.695 -212.979)
		(end 99.441 -212.979)
		(width 0.17145)
		(layer "F.Cu")
		(net "CLK_BUFFER_EU3_VOE_N")
	)
	(segment
		(start 100.965 -213.487)
		(end 100.9015 -213.487)
		(width 0.17145)
		(layer "F.Cu")
		(net "CLK_BUFFER_EU3_VOE_N")
	)
	(segment
		(start 98.40341 -212.57006)
		(end 99.314 -212.57006)
		(width 0.17145)
		(layer "F.Cu")
		(net "CLK_BUFFER_EU3_VOE_N")
	)
	(segment
		(start 91.23045 -205.48727)
		(end 91.4654 -205.25232)
		(width 0.17145)
		(layer "F.Cu")
		(net "CLK_BUFFER_EU3_VOE_N")
	)
	(segment
		(start 99.441 -212.979)
		(end 99.34956 -213.07044)
		(width 0.17145)
		(layer "F.Cu")
		(net "CLK_BUFFER_EU3_VOE_N")
	)
	(segment
		(start 100.203 -213.487)
		(end 99.695 -212.979)
		(width 0.17145)
		(layer "F.Cu")
		(net "CLK_BUFFER_EU3_VOE_N")
	)
	(segment
		(start 99.441 -212.69706)
		(end 99.441 -212.979)
		(width 0.17145)
		(layer "F.Cu")
		(net "CLK_BUFFER_EU3_VOE_N")
	)
	(segment
		(start 99.314 -212.57006)
		(end 99.441 -212.69706)
		(width 0.17145)
		(layer "F.Cu")
		(net "CLK_BUFFER_EU3_VOE_N")
	)
	(via
		(at 102.108 -214.376)
		(size 0.508)
		(drill 0.254)
		(layers "F.Cu" "B.Cu")
		(net "CLK_BUFFER_EU3_VOE_N")
	)
	(via
		(at 91.4654 -205.25232)
		(size 0.508)
		(drill 0.254)
		(layers "F.Cu" "B.Cu")
		(net "CLK_BUFFER_EU3_VOE_N")
	)
	(via
		(at 99.06 -208.407)
		(size 0.7112)
		(drill 0.3556)
		(layers "F.Cu" "B.Cu")
		(net "CLK_BUFFER_EU3_VOE_N")
	)
	(segment
		(start 95.90532 -205.25232)
		(end 99.06 -208.407)
		(width 0.17145)
		(layer "B.Cu")
		(net "CLK_BUFFER_EU3_VOE_N")
	)
	(segment
		(start 99.06 -208.407)
		(end 101.092 -210.439)
		(width 0.17145)
		(layer "B.Cu")
		(net "CLK_BUFFER_EU3_VOE_N")
	)
	(segment
		(start 101.092 -213.36)
		(end 102.108 -214.376)
		(width 0.17145)
		(layer "B.Cu")
		(net "CLK_BUFFER_EU3_VOE_N")
	)
	(segment
		(start 101.092 -210.439)
		(end 101.092 -213.36)
		(width 0.17145)
		(layer "B.Cu")
		(net "CLK_BUFFER_EU3_VOE_N")
	)
	(segment
		(start 91.4654 -205.25232)
		(end 95.90532 -205.25232)
		(width 0.17145)
		(layer "B.Cu")
		(net "CLK_BUFFER_EU3_VOE_N")
	)
	(segment
		(start 99.47656 -302.93056)
		(end 99.695 -303.149)
		(width 0.17145)
		(layer "F.Cu")
		(net "CLK_BUFFER_EU2_VOE_N")
	)
	(segment
		(start 98.40341 -303.43094)
		(end 99.41306 -303.43094)
		(width 0.17145)
		(layer "F.Cu")
		(net "CLK_BUFFER_EU2_VOE_N")
	)
	(segment
		(start 100.076 -302.768)
		(end 101.2825 -302.768)
		(width 0.17145)
		(layer "F.Cu")
		(net "CLK_BUFFER_EU2_VOE_N")
	)
	(segment
		(start 91.23045 -300.75759)
		(end 91.23045 -299.62856)
		(width 0.17145)
		(layer "F.Cu")
		(net "CLK_BUFFER_EU2_VOE_N")
	)
	(segment
		(start 101.2825 -302.768)
		(end 101.2825 -301.8155)
		(width 0.17145)
		(layer "F.Cu")
		(net "CLK_BUFFER_EU2_VOE_N")
	)
	(segment
		(start 91.72956 -300.12767)
		(end 91.23045 -299.62856)
		(width 0.17145)
		(layer "F.Cu")
		(net "CLK_BUFFER_EU2_VOE_N")
	)
	(segment
		(start 91.72956 -300.75759)
		(end 91.72956 -300.12767)
		(width 0.17145)
		(layer "F.Cu")
		(net "CLK_BUFFER_EU2_VOE_N")
	)
	(segment
		(start 98.40341 -302.93056)
		(end 99.47656 -302.93056)
		(width 0.17145)
		(layer "F.Cu")
		(net "CLK_BUFFER_EU2_VOE_N")
	)
	(segment
		(start 99.41306 -303.43094)
		(end 99.695 -303.149)
		(width 0.17145)
		(layer "F.Cu")
		(net "CLK_BUFFER_EU2_VOE_N")
	)
	(segment
		(start 99.695 -303.149)
		(end 100.076 -302.768)
		(width 0.17145)
		(layer "F.Cu")
		(net "CLK_BUFFER_EU2_VOE_N")
	)
	(via
		(at 101.2825 -301.8155)
		(size 0.508)
		(drill 0.254)
		(layers "F.Cu" "B.Cu")
		(net "CLK_BUFFER_EU2_VOE_N")
	)
	(via
		(at 91.23045 -299.62856)
		(size 0.508)
		(drill 0.254)
		(layers "F.Cu" "B.Cu")
		(net "CLK_BUFFER_EU2_VOE_N")
	)
	(via
		(at 97.31756 -299.62856)
		(size 0.7112)
		(drill 0.3556)
		(layers "F.Cu" "B.Cu")
		(net "CLK_BUFFER_EU2_VOE_N")
	)
	(segment
		(start 101.2825 -301.8155)
		(end 99.09556 -299.62856)
		(width 0.17145)
		(layer "B.Cu")
		(net "CLK_BUFFER_EU2_VOE_N")
	)
	(segment
		(start 99.09556 -299.62856)
		(end 97.31756 -299.62856)
		(width 0.17145)
		(layer "B.Cu")
		(net "CLK_BUFFER_EU2_VOE_N")
	)
	(segment
		(start 97.31756 -299.62856)
		(end 91.23045 -299.62856)
		(width 0.17145)
		(layer "B.Cu")
		(net "CLK_BUFFER_EU2_VOE_N")
	)
	(segment
		(start 100.076 -429.768)
		(end 99.695 -429.768)
		(width 0.17145)
		(layer "F.Cu")
		(net "CLK_BUFFER_EU1_VOE_N")
	)
	(segment
		(start 96.23044 -438.36844)
		(end 96.23044 -436.22341)
		(width 0.17145)
		(layer "F.Cu")
		(net "CLK_BUFFER_EU1_VOE_N")
	)
	(segment
		(start 100.457 -429.387)
		(end 100.076 -429.768)
		(width 0.17145)
		(layer "F.Cu")
		(net "CLK_BUFFER_EU1_VOE_N")
	)
	(segment
		(start 95.73006 -437.86806)
		(end 95.73006 -436.22341)
		(width 0.17145)
		(layer "F.Cu")
		(net "CLK_BUFFER_EU1_VOE_N")
	)
	(segment
		(start 96.23044 -438.36844)
		(end 95.73006 -437.86806)
		(width 0.17145)
		(layer "F.Cu")
		(net "CLK_BUFFER_EU1_VOE_N")
	)
	(segment
		(start 98.40341 -430.04994)
		(end 99.41306 -430.04994)
		(width 0.17145)
		(layer "F.Cu")
		(net "CLK_BUFFER_EU1_VOE_N")
	)
	(segment
		(start 96.23044 -426.71238)
		(end 95.73006 -426.212)
		(width 0.17145)
		(layer "F.Cu")
		(net "CLK_BUFFER_EU1_VOE_N")
	)
	(segment
		(start 96.266 -438.404)
		(end 96.23044 -438.36844)
		(width 0.17145)
		(layer "F.Cu")
		(net "CLK_BUFFER_EU1_VOE_N")
	)
	(segment
		(start 96.266 -438.404)
		(end 96.266 -439.2295)
		(width 0.17145)
		(layer "F.Cu")
		(net "CLK_BUFFER_EU1_VOE_N")
	)
	(segment
		(start 95.73006 -427.37659)
		(end 95.73006 -426.212)
		(width 0.17145)
		(layer "F.Cu")
		(net "CLK_BUFFER_EU1_VOE_N")
	)
	(segment
		(start 99.47656 -429.54956)
		(end 98.40341 -429.54956)
		(width 0.17145)
		(layer "F.Cu")
		(net "CLK_BUFFER_EU1_VOE_N")
	)
	(segment
		(start 96.23044 -427.37659)
		(end 96.23044 -426.71238)
		(width 0.17145)
		(layer "F.Cu")
		(net "CLK_BUFFER_EU1_VOE_N")
	)
	(segment
		(start 99.695 -429.768)
		(end 99.47656 -429.54956)
		(width 0.17145)
		(layer "F.Cu")
		(net "CLK_BUFFER_EU1_VOE_N")
	)
	(segment
		(start 99.41306 -430.04994)
		(end 99.695 -429.768)
		(width 0.17145)
		(layer "F.Cu")
		(net "CLK_BUFFER_EU1_VOE_N")
	)
	(via
		(at 95.73006 -426.212)
		(size 0.508)
		(drill 0.254)
		(layers "F.Cu" "B.Cu")
		(net "CLK_BUFFER_EU1_VOE_N")
	)
	(via
		(at 100.457 -429.387)
		(size 0.508)
		(drill 0.254)
		(layers "F.Cu" "B.Cu")
		(net "CLK_BUFFER_EU1_VOE_N")
	)
	(via
		(at 100.457 -432.562)
		(size 0.7112)
		(drill 0.3556)
		(layers "F.Cu" "B.Cu")
		(net "CLK_BUFFER_EU1_VOE_N")
	)
	(via
		(at 96.266 -438.404)
		(size 0.508)
		(drill 0.254)
		(layers "F.Cu" "B.Cu")
		(net "CLK_BUFFER_EU1_VOE_N")
	)
	(segment
		(start 97.282 -426.212)
		(end 100.457 -429.387)
		(width 0.17145)
		(layer "B.Cu")
		(net "CLK_BUFFER_EU1_VOE_N")
	)
	(segment
		(start 100.457 -434.213)
		(end 100.457 -432.562)
		(width 0.17145)
		(layer "B.Cu")
		(net "CLK_BUFFER_EU1_VOE_N")
	)
	(segment
		(start 95.73006 -426.212)
		(end 97.282 -426.212)
		(width 0.17145)
		(layer "B.Cu")
		(net "CLK_BUFFER_EU1_VOE_N")
	)
	(segment
		(start 96.266 -438.404)
		(end 100.457 -434.213)
		(width 0.17145)
		(layer "B.Cu")
		(net "CLK_BUFFER_EU1_VOE_N")
	)
	(segment
		(start 100.457 -432.562)
		(end 100.457 -429.387)
		(width 0.17145)
		(layer "B.Cu")
		(net "CLK_BUFFER_EU1_VOE_N")
	)
	(segment
		(start 85.3059 -102.2985)
		(end 86.614 -102.2985)
		(width 0.508)
		(layer "F.Cu")
		(net "VDDR_4")
	)
	(segment
		(start 83.6295 -102.4636)
		(end 84.6582 -102.4636)
		(width 0.508)
		(layer "F.Cu")
		(net "VDDR_4")
	)
	(segment
		(start 87.95131 -101.85019)
		(end 87.503 -102.2985)
		(width 0.3048)
		(layer "F.Cu")
		(net "VDDR_4")
	)
	(segment
		(start 84.6582 -102.4636)
		(end 85.1408 -102.4636)
		(width 0.508)
		(layer "F.Cu")
		(net "VDDR_4")
	)
	(segment
		(start 89.55659 -101.85019)
		(end 87.95131 -101.85019)
		(width 0.3048)
		(layer "F.Cu")
		(net "VDDR_4")
	)
	(segment
		(start 85.1408 -102.4636)
		(end 85.3059 -102.2985)
		(width 0.508)
		(layer "F.Cu")
		(net "VDDR_4")
	)
	(segment
		(start 86.614 -102.2985)
		(end 87.503 -102.2985)
		(width 0.508)
		(layer "F.Cu")
		(net "VDDR_4")
	)
	(segment
		(start 83.3755 -102.7176)
		(end 83.6295 -102.4636)
		(width 0.508)
		(layer "F.Cu")
		(net "VDDR_4")
	)
	(via
		(at 84.6582 -102.4636)
		(size 0.7112)
		(drill 0.3556)
		(layers "F.Cu" "B.Cu")
		(net "VDDR_4")
	)
	(segment
		(start 87.503 -211.5185)
		(end 87.95131 -211.07019)
		(width 0.3048)
		(layer "F.Cu")
		(net "VDDR_3")
	)
	(segment
		(start 86.614 -211.5185)
		(end 87.503 -211.5185)
		(width 0.508)
		(layer "F.Cu")
		(net "VDDR_3")
	)
	(segment
		(start 87.95131 -211.07019)
		(end 89.55659 -211.07019)
		(width 0.3048)
		(layer "F.Cu")
		(net "VDDR_3")
	)
	(segment
		(start 83.7311 -211.582)
		(end 83.3755 -211.9376)
		(width 0.508)
		(layer "F.Cu")
		(net "VDDR_3")
	)
	(segment
		(start 84.7852 -211.582)
		(end 83.7311 -211.582)
		(width 0.508)
		(layer "F.Cu")
		(net "VDDR_3")
	)
	(segment
		(start 84.7852 -211.582)
		(end 84.8487 -211.5185)
		(width 0.508)
		(layer "F.Cu")
		(net "VDDR_3")
	)
	(segment
		(start 84.8487 -211.5185)
		(end 86.614 -211.5185)
		(width 0.508)
		(layer "F.Cu")
		(net "VDDR_3")
	)
	(via
		(at 84.7852 -211.582)
		(size 0.7112)
		(drill 0.3556)
		(layers "F.Cu" "B.Cu")
		(net "VDDR_3")
	)
	(segment
		(start 83.7692 -305.8795)
		(end 83.3755 -306.2732)
		(width 0.508)
		(layer "F.Cu")
		(net "VDDR_2")
	)
	(segment
		(start 87.503 -305.8795)
		(end 86.614 -305.8795)
		(width 0.508)
		(layer "F.Cu")
		(net "VDDR_2")
	)
	(segment
		(start 89.55659 -305.43119)
		(end 87.95131 -305.43119)
		(width 0.3048)
		(layer "F.Cu")
		(net "VDDR_2")
	)
	(segment
		(start 87.95131 -305.43119)
		(end 87.503 -305.8795)
		(width 0.3048)
		(layer "F.Cu")
		(net "VDDR_2")
	)
	(segment
		(start 84.963 -305.8795)
		(end 83.7692 -305.8795)
		(width 0.508)
		(layer "F.Cu")
		(net "VDDR_2")
	)
	(segment
		(start 84.963 -305.8795)
		(end 86.614 -305.8795)
		(width 0.508)
		(layer "F.Cu")
		(net "VDDR_2")
	)
	(via
		(at 84.963 -305.8795)
		(size 0.7112)
		(drill 0.3556)
		(layers "F.Cu" "B.Cu")
		(net "VDDR_2")
	)
	(segment
		(start 87.503 -432.4985)
		(end 86.614 -432.4985)
		(width 0.508)
		(layer "F.Cu")
		(net "VDDR_1")
	)
	(segment
		(start 84.9249 -432.4985)
		(end 86.614 -432.4985)
		(width 0.508)
		(layer "F.Cu")
		(net "VDDR_1")
	)
	(segment
		(start 84.7344 -432.689)
		(end 84.9249 -432.4985)
		(width 0.508)
		(layer "F.Cu")
		(net "VDDR_1")
	)
	(segment
		(start 87.95131 -432.05019)
		(end 87.503 -432.4985)
		(width 0.3048)
		(layer "F.Cu")
		(net "VDDR_1")
	)
	(segment
		(start 89.55659 -432.05019)
		(end 87.95131 -432.05019)
		(width 0.3048)
		(layer "F.Cu")
		(net "VDDR_1")
	)
	(segment
		(start 83.3755 -432.8922)
		(end 84.5312 -432.8922)
		(width 0.508)
		(layer "F.Cu")
		(net "VDDR_1")
	)
	(segment
		(start 84.5312 -432.8922)
		(end 84.7344 -432.689)
		(width 0.508)
		(layer "F.Cu")
		(net "VDDR_1")
	)
	(via
		(at 84.7344 -432.689)
		(size 0.7112)
		(drill 0.3556)
		(layers "F.Cu" "B.Cu")
		(net "VDDR_1")
	)
	(segment
		(start 86.487 -107.95)
		(end 83.3755 -107.95)
		(width 0.508)
		(layer "F.Cu")
		(net "VDDA_4")
	)
	(segment
		(start 88.646 -106.299)
		(end 88.646 -105.918)
		(width 0.3048)
		(layer "F.Cu")
		(net "VDDA_4")
	)
	(segment
		(start 89.21369 -105.35031)
		(end 89.429082 -105.35031)
		(width 0.3048)
		(layer "F.Cu")
		(net "VDDA_4")
	)
	(segment
		(start 88.646 -105.918)
		(end 89.21369 -105.35031)
		(width 0.3048)
		(layer "F.Cu")
		(net "VDDA_4")
	)
	(segment
		(start 88.2015 -106.7435)
		(end 88.646 -106.299)
		(width 0.3048)
		(layer "F.Cu")
		(net "VDDA_4")
	)
	(segment
		(start 88.011 -106.7435)
		(end 87.122 -106.7435)
		(width 0.508)
		(layer "F.Cu")
		(net "VDDA_4")
	)
	(segment
		(start 87.122 -107.315)
		(end 86.487 -107.95)
		(width 0.508)
		(layer "F.Cu")
		(net "VDDA_4")
	)
	(segment
		(start 87.122 -106.7435)
		(end 87.122 -107.315)
		(width 0.508)
		(layer "F.Cu")
		(net "VDDA_4")
	)
	(segment
		(start 88.011 -106.7435)
		(end 88.2015 -106.7435)
		(width 0.3048)
		(layer "F.Cu")
		(net "VDDA_4")
	)
	(via
		(at 86.487 -107.95)
		(size 0.7112)
		(drill 0.3556)
		(layers "F.Cu" "B.Cu")
		(net "VDDA_4")
	)
	(segment
		(start 87.122 -216.535)
		(end 87.122 -215.9635)
		(width 0.508)
		(layer "F.Cu")
		(net "VDDA_3")
	)
	(segment
		(start 88.011 -215.9635)
		(end 88.2015 -215.9635)
		(width 0.3048)
		(layer "F.Cu")
		(net "VDDA_3")
	)
	(segment
		(start 86.487 -217.17)
		(end 87.122 -216.535)
		(width 0.508)
		(layer "F.Cu")
		(net "VDDA_3")
	)
	(segment
		(start 88.2015 -215.9635)
		(end 88.646 -215.519)
		(width 0.3048)
		(layer "F.Cu")
		(net "VDDA_3")
	)
	(segment
		(start 88.646 -215.519)
		(end 88.646 -215.138)
		(width 0.3048)
		(layer "F.Cu")
		(net "VDDA_3")
	)
	(segment
		(start 88.646 -215.138)
		(end 89.21369 -214.57031)
		(width 0.3048)
		(layer "F.Cu")
		(net "VDDA_3")
	)
	(segment
		(start 87.122 -215.9635)
		(end 88.011 -215.9635)
		(width 0.508)
		(layer "F.Cu")
		(net "VDDA_3")
	)
	(segment
		(start 83.3755 -217.17)
		(end 86.487 -217.17)
		(width 0.508)
		(layer "F.Cu")
		(net "VDDA_3")
	)
	(segment
		(start 89.21369 -214.57031)
		(end 89.429082 -214.57031)
		(width 0.3048)
		(layer "F.Cu")
		(net "VDDA_3")
	)
	(via
		(at 86.487 -217.17)
		(size 0.7112)
		(drill 0.3556)
		(layers "F.Cu" "B.Cu")
		(net "VDDA_3")
	)
	(segment
		(start 88.646 -309.88)
		(end 88.2015 -310.3245)
		(width 0.3048)
		(layer "F.Cu")
		(net "VDDA_2")
	)
	(segment
		(start 83.3755 -311.531)
		(end 86.487 -311.531)
		(width 0.508)
		(layer "F.Cu")
		(net "VDDA_2")
	)
	(segment
		(start 87.122 -310.3245)
		(end 87.122 -310.896)
		(width 0.508)
		(layer "F.Cu")
		(net "VDDA_2")
	)
	(segment
		(start 88.011 -310.3245)
		(end 87.122 -310.3245)
		(width 0.508)
		(layer "F.Cu")
		(net "VDDA_2")
	)
	(segment
		(start 89.429082 -308.93131)
		(end 89.21369 -308.93131)
		(width 0.3048)
		(layer "F.Cu")
		(net "VDDA_2")
	)
	(segment
		(start 88.2015 -310.3245)
		(end 88.011 -310.3245)
		(width 0.3048)
		(layer "F.Cu")
		(net "VDDA_2")
	)
	(segment
		(start 88.646 -309.499)
		(end 88.646 -309.88)
		(width 0.3048)
		(layer "F.Cu")
		(net "VDDA_2")
	)
	(segment
		(start 89.21369 -308.93131)
		(end 88.646 -309.499)
		(width 0.3048)
		(layer "F.Cu")
		(net "VDDA_2")
	)
	(segment
		(start 87.122 -310.896)
		(end 86.487 -311.531)
		(width 0.508)
		(layer "F.Cu")
		(net "VDDA_2")
	)
	(via
		(at 86.487 -311.531)
		(size 0.7112)
		(drill 0.3556)
		(layers "F.Cu" "B.Cu")
		(net "VDDA_2")
	)
	(segment
		(start 88.646 -436.499)
		(end 88.646 -436.118)
		(width 0.3048)
		(layer "F.Cu")
		(net "VDDA_1")
	)
	(segment
		(start 88.011 -436.9435)
		(end 88.2015 -436.9435)
		(width 0.3048)
		(layer "F.Cu")
		(net "VDDA_1")
	)
	(segment
		(start 86.487 -438.15)
		(end 87.122 -437.515)
		(width 0.508)
		(layer "F.Cu")
		(net "VDDA_1")
	)
	(segment
		(start 83.3755 -438.15)
		(end 86.487 -438.15)
		(width 0.508)
		(layer "F.Cu")
		(net "VDDA_1")
	)
	(segment
		(start 89.21369 -435.55031)
		(end 89.429082 -435.55031)
		(width 0.3048)
		(layer "F.Cu")
		(net "VDDA_1")
	)
	(segment
		(start 88.2015 -436.9435)
		(end 88.646 -436.499)
		(width 0.3048)
		(layer "F.Cu")
		(net "VDDA_1")
	)
	(segment
		(start 87.122 -436.9435)
		(end 88.011 -436.9435)
		(width 0.508)
		(layer "F.Cu")
		(net "VDDA_1")
	)
	(segment
		(start 87.122 -437.515)
		(end 87.122 -436.9435)
		(width 0.508)
		(layer "F.Cu")
		(net "VDDA_1")
	)
	(segment
		(start 88.646 -436.118)
		(end 89.21369 -435.55031)
		(width 0.3048)
		(layer "F.Cu")
		(net "VDDA_1")
	)
	(via
		(at 86.487 -438.15)
		(size 0.7112)
		(drill 0.3556)
		(layers "F.Cu" "B.Cu")
		(net "VDDA_1")
	)
	(segment
		(start 227.699062 -435.890924)
		(end 227.699062 -436.360062)
		(width 0.3048)
		(layer "F.Cu")
		(net "TPS53312_P3V3_PG")
	)
	(segment
		(start 227.699062 -436.360062)
		(end 228.092 -436.753)
		(width 0.3048)
		(layer "F.Cu")
		(net "TPS53312_P3V3_PG")
	)
	(segment
		(start 229.235 -437.896)
		(end 229.235 -438.7215)
		(width 0.508)
		(layer "F.Cu")
		(net "TPS53312_P3V3_PG")
	)
	(segment
		(start 231.267 -438.8485)
		(end 231.267 -438.0738)
		(width 0.508)
		(layer "F.Cu")
		(net "TPS53312_P3V3_PG")
	)
	(segment
		(start 230.251 -438.7215)
		(end 230.632 -438.7215)
		(width 0.508)
		(layer "F.Cu")
		(net "TPS53312_P3V3_PG")
	)
	(segment
		(start 229.235 -438.7215)
		(end 230.251 -438.7215)
		(width 0.508)
		(layer "F.Cu")
		(net "TPS53312_P3V3_PG")
	)
	(segment
		(start 228.092 -436.753)
		(end 229.235 -437.896)
		(width 0.508)
		(layer "F.Cu")
		(net "TPS53312_P3V3_PG")
	)
	(segment
		(start 230.632 -438.7215)
		(end 230.759 -438.8485)
		(width 0.508)
		(layer "F.Cu")
		(net "TPS53312_P3V3_PG")
	)
	(segment
		(start 233.4895 -435.61)
		(end 233.4895 -434.721)
		(width 0.508)
		(layer "F.Cu")
		(net "TPS53312_P3V3_PG")
	)
	(segment
		(start 230.759 -438.8485)
		(end 231.267 -438.8485)
		(width 0.508)
		(layer "F.Cu")
		(net "TPS53312_P3V3_PG")
	)
	(via
		(at 231.267 -438.0738)
		(size 0.508)
		(drill 0.254)
		(layers "F.Cu" "B.Cu")
		(net "TPS53312_P3V3_PG")
	)
	(via
		(at 233.4895 -434.721)
		(size 0.508)
		(drill 0.254)
		(layers "F.Cu" "B.Cu")
		(net "TPS53312_P3V3_PG")
	)
	(via
		(at 231.902 -436.3085)
		(size 0.7112)
		(drill 0.3556)
		(layers "F.Cu" "B.Cu")
		(net "TPS53312_P3V3_PG")
	)
	(segment
		(start 233.4895 -434.721)
		(end 231.902 -436.3085)
		(width 0.508)
		(layer "B.Cu")
		(net "TPS53312_P3V3_PG")
	)
	(segment
		(start 231.267 -436.9435)
		(end 231.267 -438.0738)
		(width 0.508)
		(layer "B.Cu")
		(net "TPS53312_P3V3_PG")
	)
	(segment
		(start 231.902 -436.3085)
		(end 231.267 -436.9435)
		(width 0.508)
		(layer "B.Cu")
		(net "TPS53312_P3V3_PG")
	)
	(segment
		(start 232.7148 -434.0098)
		(end 232.41 -433.705)
		(width 0.508)
		(layer "F.Cu")
		(net "P3V3_VRG5")
	)
	(segment
		(start 232.41 -433.705)
		(end 231.267 -433.705)
		(width 0.508)
		(layer "F.Cu")
		(net "P3V3_VRG5")
	)
	(segment
		(start 230.378 -433.705)
		(end 229.992936 -434.090064)
		(width 0.508)
		(layer "F.Cu")
		(net "P3V3_VRG5")
	)
	(segment
		(start 232.6005 -434.7972)
		(end 232.6005 -435.61)
		(width 0.508)
		(layer "F.Cu")
		(net "P3V3_VRG5")
	)
	(segment
		(start 232.7148 -434.6829)
		(end 232.6005 -434.7972)
		(width 0.508)
		(layer "F.Cu")
		(net "P3V3_VRG5")
	)
	(segment
		(start 231.267 -433.705)
		(end 230.378 -433.705)
		(width 0.508)
		(layer "F.Cu")
		(net "P3V3_VRG5")
	)
	(segment
		(start 229.992936 -434.090064)
		(end 228.487224 -434.090064)
		(width 0.3048)
		(layer "F.Cu")
		(net "P3V3_VRG5")
	)
	(segment
		(start 232.7148 -434.0098)
		(end 232.7148 -434.6829)
		(width 0.508)
		(layer "F.Cu")
		(net "P3V3_VRG5")
	)
	(via
		(at 232.7148 -434.0098)
		(size 0.7112)
		(drill 0.3556)
		(layers "F.Cu" "B.Cu")
		(net "P3V3_VRG5")
	)
	(segment
		(start 230.124 -430.371504)
		(end 230.124 -429.5775)
		(width 0.254)
		(layer "F.Cu")
		(net "P3V3_VO")
	)
	(segment
		(start 229.140004 -431.3555)
		(end 228.5873 -431.3555)
		(width 0.254)
		(layer "F.Cu")
		(net "P3V3_VO")
	)
	(segment
		(start 227.699062 -432.243738)
		(end 227.699062 -432.789076)
		(width 0.254)
		(layer "F.Cu")
		(net "P3V3_VO")
	)
	(segment
		(start 228.5873 -431.3555)
		(end 227.699062 -432.243738)
		(width 0.254)
		(layer "F.Cu")
		(net "P3V3_VO")
	)
	(segment
		(start 229.686104 -430.8094)
		(end 229.140004 -431.3555)
		(width 0.254)
		(layer "F.Cu")
		(net "P3V3_VO")
	)
	(segment
		(start 229.686104 -430.8094)
		(end 230.124 -430.371504)
		(width 0.254)
		(layer "F.Cu")
		(net "P3V3_VO")
	)
	(via
		(at 229.686104 -430.8094)
		(size 0.7112)
		(drill 0.3556)
		(layers "F.Cu" "B.Cu")
		(net "P3V3_VO")
	)
	(via
		(at 225.9584 -429.7426)
		(size 0.7112)
		(drill 0.3556)
		(layers "F.Cu" "B.Cu")
		(net "P3V3_VIN")
	)
	(segment
		(start 218.313 -430.784)
		(end 217.297 -430.784)
		(width 0.254)
		(layer "F.Cu")
		(net "P3V3_VFB_R")
	)
	(segment
		(start 218.313 -431.6095)
		(end 218.313 -430.784)
		(width 0.254)
		(layer "F.Cu")
		(net "P3V3_VFB_R")
	)
	(segment
		(start 232.4735 -429.514)
		(end 232.4735 -428.625)
		(width 0.254)
		(layer "F.Cu")
		(net "P3V3_VFB_R")
	)
	(segment
		(start 217.297 -430.784)
		(end 217.17 -430.911)
		(width 0.254)
		(layer "F.Cu")
		(net "P3V3_VFB_R")
	)
	(via
		(at 232.4735 -428.625)
		(size 0.508)
		(drill 0.254)
		(layers "F.Cu" "B.Cu")
		(net "P3V3_VFB_R")
	)
	(via
		(at 218.313 -430.784)
		(size 0.508)
		(drill 0.254)
		(layers "F.Cu" "B.Cu")
		(net "P3V3_VFB_R")
	)
	(segment
		(start 220.20022 -421.78478)
		(end 229.76078 -421.78478)
		(width 0.254)
		(layer "B.Cu")
		(net "P3V3_VFB_R")
	)
	(segment
		(start 232.4735 -424.4975)
		(end 232.4735 -428.625)
		(width 0.254)
		(layer "B.Cu")
		(net "P3V3_VFB_R")
	)
	(segment
		(start 229.76078 -421.78478)
		(end 232.4735 -424.4975)
		(width 0.254)
		(layer "B.Cu")
		(net "P3V3_VFB_R")
	)
	(segment
		(start 218.313 -430.784)
		(end 218.313 -423.672)
		(width 0.254)
		(layer "B.Cu")
		(net "P3V3_VFB_R")
	)
	(segment
		(start 218.313 -423.672)
		(end 220.20022 -421.78478)
		(width 0.254)
		(layer "B.Cu")
		(net "P3V3_VFB_R")
	)
	(segment
		(start 229.197662 -433.589938)
		(end 228.499924 -433.589938)
		(width 0.254)
		(layer "F.Cu")
		(net "P3V3_VFB")
	)
	(segment
		(start 231.5845 -431.546)
		(end 231.5845 -430.53)
		(width 0.254)
		(layer "F.Cu")
		(net "P3V3_VFB")
	)
	(segment
		(start 230.2256 -432.562)
		(end 230.124 -432.6636)
		(width 0.254)
		(layer "F.Cu")
		(net "P3V3_VFB")
	)
	(segment
		(start 231.5845 -432.562)
		(end 230.2256 -432.562)
		(width 0.254)
		(layer "F.Cu")
		(net "P3V3_VFB")
	)
	(segment
		(start 231.5845 -430.53)
		(end 231.5845 -429.514)
		(width 0.254)
		(layer "F.Cu")
		(net "P3V3_VFB")
	)
	(segment
		(start 231.5845 -432.562)
		(end 231.5845 -431.546)
		(width 0.254)
		(layer "F.Cu")
		(net "P3V3_VFB")
	)
	(segment
		(start 230.124 -432.6636)
		(end 229.197662 -433.589938)
		(width 0.254)
		(layer "F.Cu")
		(net "P3V3_VFB")
	)
	(via
		(at 230.124 -432.6636)
		(size 0.7112)
		(drill 0.3556)
		(layers "F.Cu" "B.Cu")
		(net "P3V3_VFB")
	)
	(segment
		(start 227.198936 -432.058064)
		(end 227.198936 -432.801776)
		(width 0.3048)
		(layer "F.Cu")
		(net "P3V3_VCC")
	)
	(segment
		(start 227.711 -430.8602)
		(end 227.711 -429.514)
		(width 0.508)
		(layer "F.Cu")
		(net "P3V3_VCC")
	)
	(segment
		(start 228.981 -429.514)
		(end 227.711 -429.514)
		(width 0.508)
		(layer "F.Cu")
		(net "P3V3_VCC")
	)
	(segment
		(start 227.711 -430.8602)
		(end 227.711 -431.546)
		(width 0.3048)
		(layer "F.Cu")
		(net "P3V3_VCC")
	)
	(segment
		(start 227.711 -431.546)
		(end 227.198936 -432.058064)
		(width 0.3048)
		(layer "F.Cu")
		(net "P3V3_VCC")
	)
	(via
		(at 227.711 -430.8602)
		(size 0.7112)
		(drill 0.3556)
		(layers "F.Cu" "B.Cu")
		(net "P3V3_VCC")
	)
	(segment
		(start 223.5835 -430.53)
		(end 222.758 -430.53)
		(width 0.508)
		(layer "F.Cu")
		(net "P3V3_VBST_RR")
	)
	(segment
		(start 223.901 -430.8475)
		(end 223.5835 -430.53)
		(width 0.508)
		(layer "F.Cu")
		(net "P3V3_VBST_RR")
	)
	(segment
		(start 223.901 -431.7365)
		(end 223.901 -432.435)
		(width 0.508)
		(layer "F.Cu")
		(net "P3V3_VBST")
	)
	(segment
		(start 224.592642 -433.126642)
		(end 225.055938 -433.589938)
		(width 0.3048)
		(layer "F.Cu")
		(net "P3V3_VBST")
	)
	(segment
		(start 225.055938 -433.589938)
		(end 225.398076 -433.589938)
		(width 0.3048)
		(layer "F.Cu")
		(net "P3V3_VBST")
	)
	(segment
		(start 223.901 -432.435)
		(end 224.592642 -433.126642)
		(width 0.508)
		(layer "F.Cu")
		(net "P3V3_VBST")
	)
	(segment
		(start 225.410776 -434.090064)
		(end 223.447864 -434.090064)
		(width 0.254)
		(layer "F.Cu")
		(net "P3V3_SW")
	)
	(segment
		(start 222.758 -433.4002)
		(end 222.758 -432.054)
		(width 0.254)
		(layer "F.Cu")
		(net "P3V3_SW")
	)
	(segment
		(start 218.313 -436.372)
		(end 218.313 -432.4985)
		(width 0.254)
		(layer "F.Cu")
		(net "P3V3_SW")
	)
	(segment
		(start 220.584522 -436.88)
		(end 218.821 -436.88)
		(width 0.254)
		(layer "F.Cu")
		(net "P3V3_SW")
	)
	(segment
		(start 223.447864 -434.090064)
		(end 222.758 -433.4002)
		(width 0.254)
		(layer "F.Cu")
		(net "P3V3_SW")
	)
	(segment
		(start 218.821 -436.88)
		(end 218.313 -436.372)
		(width 0.254)
		(layer "F.Cu")
		(net "P3V3_SW")
	)
	(via
		(at 223.2914 -435.6354)
		(size 0.7112)
		(drill 0.3556)
		(layers "F.Cu" "B.Cu")
		(net "P3V3_SW")
	)
	(segment
		(start 228.976936 -434.589936)
		(end 229.489 -435.102)
		(width 0.254)
		(layer "F.Cu")
		(net "P3V3_SS")
	)
	(segment
		(start 230.378 -436.626)
		(end 231.0638 -436.626)
		(width 0.254)
		(layer "F.Cu")
		(net "P3V3_SS")
	)
	(segment
		(start 229.489 -435.737)
		(end 230.378 -436.626)
		(width 0.254)
		(layer "F.Cu")
		(net "P3V3_SS")
	)
	(segment
		(start 229.489 -435.102)
		(end 229.489 -435.737)
		(width 0.254)
		(layer "F.Cu")
		(net "P3V3_SS")
	)
	(segment
		(start 228.487224 -434.589936)
		(end 228.976936 -434.589936)
		(width 0.254)
		(layer "F.Cu")
		(net "P3V3_SS")
	)
	(segment
		(start 231.0638 -436.626)
		(end 232.3465 -436.626)
		(width 0.254)
		(layer "F.Cu")
		(net "P3V3_SS")
	)
	(via
		(at 231.0638 -436.626)
		(size 0.7112)
		(drill 0.3556)
		(layers "F.Cu" "B.Cu")
		(net "P3V3_SS")
	)
	(segment
		(start 223.4692 -439.6232)
		(end 223.012 -439.166)
		(width 0.508)
		(layer "F.Cu")
		(net "P3V3_SNB")
	)
	(segment
		(start 224.663 -439.6232)
		(end 223.4692 -439.6232)
		(width 0.508)
		(layer "F.Cu")
		(net "P3V3_SNB")
	)
	(segment
		(start 89.55659 -212.06968)
		(end 88.92032 -212.06968)
		(width 0.254)
		(layer "F.Cu")
		(net "P3V3_PG")
	)
	(segment
		(start 88.92032 -102.84968)
		(end 87.884 -103.886)
		(width 0.254)
		(layer "F.Cu")
		(net "P3V3_PG")
	)
	(segment
		(start 88.92032 -306.43068)
		(end 87.884 -307.467)
		(width 0.254)
		(layer "F.Cu")
		(net "P3V3_PG")
	)
	(segment
		(start 89.55659 -102.84968)
		(end 88.92032 -102.84968)
		(width 0.254)
		(layer "F.Cu")
		(net "P3V3_PG")
	)
	(segment
		(start 84.2772 -213.106)
		(end 84.1502 -212.979)
		(width 0.254)
		(layer "F.Cu")
		(net "P3V3_PG")
	)
	(segment
		(start 89.55659 -433.04968)
		(end 88.92032 -433.04968)
		(width 0.254)
		(layer "F.Cu")
		(net "P3V3_PG")
	)
	(segment
		(start 229.235 -439.6105)
		(end 229.235 -440.436)
		(width 0.254)
		(layer "F.Cu")
		(net "P3V3_PG")
	)
	(segment
		(start 84.201 -433.959)
		(end 83.3755 -433.959)
		(width 0.254)
		(layer "F.Cu")
		(net "P3V3_PG")
	)
	(segment
		(start 83.3755 -307.34)
		(end 84.1502 -307.34)
		(width 0.254)
		(layer "F.Cu")
		(net "P3V3_PG")
	)
	(segment
		(start 87.884 -103.886)
		(end 84.2772 -103.886)
		(width 0.254)
		(layer "F.Cu")
		(net "P3V3_PG")
	)
	(segment
		(start 88.92032 -433.04968)
		(end 87.884 -434.086)
		(width 0.254)
		(layer "F.Cu")
		(net "P3V3_PG")
	)
	(segment
		(start 87.884 -307.467)
		(end 84.2772 -307.467)
		(width 0.254)
		(layer "F.Cu")
		(net "P3V3_PG")
	)
	(segment
		(start 89.55659 -306.43068)
		(end 88.92032 -306.43068)
		(width 0.254)
		(layer "F.Cu")
		(net "P3V3_PG")
	)
	(segment
		(start 87.884 -213.106)
		(end 84.2772 -213.106)
		(width 0.254)
		(layer "F.Cu")
		(net "P3V3_PG")
	)
	(segment
		(start 83.3755 -212.979)
		(end 84.1502 -212.979)
		(width 0.254)
		(layer "F.Cu")
		(net "P3V3_PG")
	)
	(segment
		(start 84.2772 -103.886)
		(end 84.1502 -103.759)
		(width 0.254)
		(layer "F.Cu")
		(net "P3V3_PG")
	)
	(segment
		(start 88.92032 -212.06968)
		(end 87.884 -213.106)
		(width 0.254)
		(layer "F.Cu")
		(net "P3V3_PG")
	)
	(segment
		(start 84.328 -434.086)
		(end 84.201 -433.959)
		(width 0.254)
		(layer "F.Cu")
		(net "P3V3_PG")
	)
	(segment
		(start 84.2772 -307.467)
		(end 84.1502 -307.34)
		(width 0.254)
		(layer "F.Cu")
		(net "P3V3_PG")
	)
	(segment
		(start 83.3755 -103.759)
		(end 84.1502 -103.759)
		(width 0.254)
		(layer "F.Cu")
		(net "P3V3_PG")
	)
	(segment
		(start 87.884 -434.086)
		(end 84.328 -434.086)
		(width 0.254)
		(layer "F.Cu")
		(net "P3V3_PG")
	)
	(via
		(at 84.1502 -307.34)
		(size 0.508)
		(drill 0.254)
		(layers "F.Cu" "B.Cu")
		(net "P3V3_PG")
	)
	(via
		(at 84.1502 -103.759)
		(size 0.508)
		(drill 0.254)
		(layers "F.Cu" "B.Cu")
		(net "P3V3_PG")
	)
	(via
		(at 84.1502 -212.979)
		(size 0.508)
		(drill 0.254)
		(layers "F.Cu" "B.Cu")
		(net "P3V3_PG")
	)
	(via
		(at 85.09635 -432.23815)
		(size 0.7112)
		(drill 0.3556)
		(layers "F.Cu" "B.Cu")
		(net "P3V3_PG")
	)
	(via
		(at 84.201 -433.959)
		(size 0.508)
		(drill 0.254)
		(layers "F.Cu" "B.Cu")
		(net "P3V3_PG")
	)
	(via
		(at 83.3755 -112.1156)
		(size 0.7112)
		(drill 0.3556)
		(layers "F.Cu" "B.Cu")
		(net "P3V3_PG")
	)
	(via
		(at 80.9752 -209.2198)
		(size 0.7112)
		(drill 0.3556)
		(layers "F.Cu" "B.Cu")
		(net "P3V3_PG")
	)
	(via
		(at 83.3755 -313.182)
		(size 0.7112)
		(drill 0.3556)
		(layers "F.Cu" "B.Cu")
		(net "P3V3_PG")
	)
	(via
		(at 229.235 -440.436)
		(size 0.508)
		(drill 0.254)
		(layers "F.Cu" "B.Cu")
		(net "P3V3_PG")
	)
	(segment
		(start 77.724 -205.9686)
		(end 80.9752 -209.2198)
		(width 0.254)
		(layer "B.Cu")
		(net "P3V3_PG")
	)
	(segment
		(start 85.09 -306.4002)
		(end 85.09 -294.132)
		(width 0.254)
		(layer "B.Cu")
		(net "P3V3_PG")
	)
	(segment
		(start 77.724 -165.4302)
		(end 77.724 -205.9686)
		(width 0.254)
		(layer "B.Cu")
		(net "P3V3_PG")
	)
	(segment
		(start 81.915 -380.9746)
		(end 81.915 -345.390978)
		(width 0.254)
		(layer "B.Cu")
		(net "P3V3_PG")
	)
	(segment
		(start 76.454 -155.956)
		(end 75.057 -157.353)
		(width 0.254)
		(layer "B.Cu")
		(net "P3V3_PG")
	)
	(segment
		(start 76.892912 -154.374088)
		(end 76.454 -154.813)
		(width 0.254)
		(layer "B.Cu")
		(net "P3V3_PG")
	)
	(segment
		(start 85.09635 -433.06365)
		(end 84.201 -433.959)
		(width 0.254)
		(layer "B.Cu")
		(net "P3V3_PG")
	)
	(segment
		(start 85.09635 -432.23815)
		(end 85.09635 -433.06365)
		(width 0.254)
		(layer "B.Cu")
		(net "P3V3_PG")
	)
	(segment
		(start 75.057 -162.7632)
		(end 77.724 -165.4302)
		(width 0.254)
		(layer "B.Cu")
		(net "P3V3_PG")
	)
	(segment
		(start 85.09635 -432.23815)
		(end 85.09635 -427.24705)
		(width 0.254)
		(layer "B.Cu")
		(net "P3V3_PG")
	)
	(segment
		(start 83.3755 -308.1147)
		(end 84.1502 -307.34)
		(width 0.254)
		(layer "B.Cu")
		(net "P3V3_PG")
	)
	(segment
		(start 84.855812 -154.374088)
		(end 76.892912 -154.374088)
		(width 0.254)
		(layer "B.Cu")
		(net "P3V3_PG")
	)
	(segment
		(start 92.456 -134.3406)
		(end 92.456 -144.68602)
		(width 0.254)
		(layer "B.Cu")
		(net "P3V3_PG")
	)
	(segment
		(start 83.3755 -343.930478)
		(end 83.3755 -313.182)
		(width 0.254)
		(layer "B.Cu")
		(net "P3V3_PG")
	)
	(segment
		(start 85.09635 -427.24705)
		(end 85.6234 -426.72)
		(width 0.254)
		(layer "B.Cu")
		(net "P3V3_PG")
	)
	(segment
		(start 84.1502 -111.3409)
		(end 84.1502 -103.759)
		(width 0.254)
		(layer "B.Cu")
		(net "P3V3_PG")
	)
	(segment
		(start 92.456 -144.68602)
		(end 85.390482 -151.751538)
		(width 0.254)
		(layer "B.Cu")
		(net "P3V3_PG")
	)
	(segment
		(start 83.3755 -112.1156)
		(end 83.3755 -125.2601)
		(width 0.254)
		(layer "B.Cu")
		(net "P3V3_PG")
	)
	(segment
		(start 75.057 -157.353)
		(end 75.057 -162.7632)
		(width 0.254)
		(layer "B.Cu")
		(net "P3V3_PG")
	)
	(segment
		(start 83.3755 -112.1156)
		(end 84.1502 -111.3409)
		(width 0.254)
		(layer "B.Cu")
		(net "P3V3_PG")
	)
	(segment
		(start 81.915 -345.390978)
		(end 83.3755 -343.930478)
		(width 0.254)
		(layer "B.Cu")
		(net "P3V3_PG")
	)
	(segment
		(start 83.3755 -313.182)
		(end 83.3755 -308.1147)
		(width 0.254)
		(layer "B.Cu")
		(net "P3V3_PG")
	)
	(segment
		(start 83.3755 -125.2601)
		(end 92.456 -134.3406)
		(width 0.254)
		(layer "B.Cu")
		(net "P3V3_PG")
	)
	(segment
		(start 76.454 -154.813)
		(end 76.454 -155.956)
		(width 0.254)
		(layer "B.Cu")
		(net "P3V3_PG")
	)
	(segment
		(start 80.9752 -209.2198)
		(end 84.1502 -212.3948)
		(width 0.254)
		(layer "B.Cu")
		(net "P3V3_PG")
	)
	(segment
		(start 85.6234 -426.72)
		(end 85.6234 -384.683)
		(width 0.254)
		(layer "B.Cu")
		(net "P3V3_PG")
	)
	(segment
		(start 85.6234 -384.683)
		(end 81.915 -380.9746)
		(width 0.254)
		(layer "B.Cu")
		(net "P3V3_PG")
	)
	(segment
		(start 84.1502 -212.3948)
		(end 84.1502 -212.979)
		(width 0.254)
		(layer "B.Cu")
		(net "P3V3_PG")
	)
	(segment
		(start 84.1502 -307.34)
		(end 85.09 -306.4002)
		(width 0.254)
		(layer "B.Cu")
		(net "P3V3_PG")
	)
	(segment
		(start 85.390482 -153.839418)
		(end 84.855812 -154.374088)
		(width 0.254)
		(layer "B.Cu")
		(net "P3V3_PG")
	)
	(segment
		(start 84.1502 -293.1922)
		(end 84.1502 -212.979)
		(width 0.254)
		(layer "B.Cu")
		(net "P3V3_PG")
	)
	(segment
		(start 85.09 -294.132)
		(end 84.1502 -293.1922)
		(width 0.254)
		(layer "B.Cu")
		(net "P3V3_PG")
	)
	(segment
		(start 85.390482 -151.751538)
		(end 85.390482 -153.839418)
		(width 0.254)
		(layer "B.Cu")
		(net "P3V3_PG")
	)
	(segment
		(start 172.5676 -428.752)
		(end 186.9694 -443.1538)
		(width 0.254)
		(layer "In5.Cu")
		(net "P3V3_PG")
	)
	(segment
		(start 219.2274 -445.8208)
		(end 223.8502 -445.8208)
		(width 0.254)
		(layer "In5.Cu")
		(net "P3V3_PG")
	)
	(segment
		(start 223.8502 -445.8208)
		(end 229.235 -440.436)
		(width 0.254)
		(layer "In5.Cu")
		(net "P3V3_PG")
	)
	(segment
		(start 84.201 -441.0202)
		(end 85.644228 -442.463428)
		(width 0.254)
		(layer "In5.Cu")
		(net "P3V3_PG")
	)
	(segment
		(start 85.644228 -442.463428)
		(end 106.557572 -442.463428)
		(width 0.254)
		(layer "In5.Cu")
		(net "P3V3_PG")
	)
	(segment
		(start 84.201 -433.959)
		(end 84.201 -441.0202)
		(width 0.254)
		(layer "In5.Cu")
		(net "P3V3_PG")
	)
	(segment
		(start 216.5604 -443.1538)
		(end 219.2274 -445.8208)
		(width 0.254)
		(layer "In5.Cu")
		(net "P3V3_PG")
	)
	(segment
		(start 106.557572 -442.463428)
		(end 120.269 -428.752)
		(width 0.254)
		(layer "In5.Cu")
		(net "P3V3_PG")
	)
	(segment
		(start 120.269 -428.752)
		(end 172.5676 -428.752)
		(width 0.254)
		(layer "In5.Cu")
		(net "P3V3_PG")
	)
	(segment
		(start 186.9694 -443.1538)
		(end 216.5604 -443.1538)
		(width 0.254)
		(layer "In5.Cu")
		(net "P3V3_PG")
	)
	(segment
		(start 216.789 -436.88)
		(end 217.17 -436.499)
		(width 0.254)
		(layer "F.Cu")
		(net "P3V3_OUT")
	)
	(segment
		(start 208.28 -437.769)
		(end 208.915 -438.404)
		(width 0.254)
		(layer "F.Cu")
		(net "P3V3_OUT")
	)
	(segment
		(start 208.915 -438.404)
		(end 208.915 -439.3565)
		(width 0.254)
		(layer "F.Cu")
		(net "P3V3_OUT")
	)
	(segment
		(start 215.025478 -436.88)
		(end 216.789 -436.88)
		(width 0.254)
		(layer "F.Cu")
		(net "P3V3_OUT")
	)
	(segment
		(start 217.17 -436.499)
		(end 217.17 -432.435)
		(width 0.254)
		(layer "F.Cu")
		(net "P3V3_OUT")
	)
	(via
		(at 212.315552 -435.991)
		(size 0.7112)
		(drill 0.3556)
		(layers "F.Cu" "B.Cu")
		(net "P3V3_OUT")
	)
	(via
		(at 210.791552 -437.134)
		(size 0.7112)
		(drill 0.3556)
		(layers "F.Cu" "B.Cu")
		(net "P3V3_OUT")
	)
	(via
		(at 210.029552 -435.356)
		(size 0.7112)
		(drill 0.3556)
		(layers "F.Cu" "B.Cu")
		(net "P3V3_OUT")
	)
	(segment
		(start 227.1903 -438.7215)
		(end 227.203 -438.7088)
		(width 0.254)
		(layer "F.Cu")
		(net "P3V3_EN_R")
	)
	(segment
		(start 227.203 -438.15)
		(end 227.203 -438.7088)
		(width 0.254)
		(layer "F.Cu")
		(net "P3V3_EN_R")
	)
	(segment
		(start 227.198936 -435.878224)
		(end 227.198936 -437.4388)
		(width 0.254)
		(layer "F.Cu")
		(net "P3V3_EN_R")
	)
	(segment
		(start 227.2157 -438.7215)
		(end 227.203 -438.7088)
		(width 0.254)
		(layer "F.Cu")
		(net "P3V3_EN_R")
	)
	(segment
		(start 226.187 -438.7215)
		(end 227.1903 -438.7215)
		(width 0.254)
		(layer "F.Cu")
		(net "P3V3_EN_R")
	)
	(segment
		(start 228.219 -438.7215)
		(end 227.2157 -438.7215)
		(width 0.254)
		(layer "F.Cu")
		(net "P3V3_EN_R")
	)
	(segment
		(start 227.198936 -438.145936)
		(end 227.203 -438.15)
		(width 0.254)
		(layer "F.Cu")
		(net "P3V3_EN_R")
	)
	(segment
		(start 227.198936 -437.4388)
		(end 227.198936 -438.145936)
		(width 0.254)
		(layer "F.Cu")
		(net "P3V3_EN_R")
	)
	(via
		(at 227.198936 -437.4388)
		(size 0.7112)
		(drill 0.3556)
		(layers "F.Cu" "B.Cu")
		(net "P3V3_EN_R")
	)
	(segment
		(start 233.553 -430.53)
		(end 233.553 -428.371)
		(width 0.254)
		(layer "F.Cu")
		(net "P3V3_CC_R")
	)
	(segment
		(start 233.553 -428.371)
		(end 232.918 -427.736)
		(width 0.254)
		(layer "F.Cu")
		(net "P3V3_CC_R")
	)
	(segment
		(start 231.0765 -427.736)
		(end 230.124 -428.6885)
		(width 0.254)
		(layer "F.Cu")
		(net "P3V3_CC_R")
	)
	(segment
		(start 232.918 -427.736)
		(end 231.5972 -427.736)
		(width 0.254)
		(layer "F.Cu")
		(net "P3V3_CC_R")
	)
	(segment
		(start 232.4735 -430.53)
		(end 232.4735 -431.546)
		(width 0.254)
		(layer "F.Cu")
		(net "P3V3_CC_R")
	)
	(segment
		(start 233.553 -430.53)
		(end 232.4735 -430.53)
		(width 0.254)
		(layer "F.Cu")
		(net "P3V3_CC_R")
	)
	(segment
		(start 231.5972 -427.736)
		(end 231.0765 -427.736)
		(width 0.254)
		(layer "F.Cu")
		(net "P3V3_CC_R")
	)
	(via
		(at 231.5972 -427.736)
		(size 0.7112)
		(drill 0.3556)
		(layers "F.Cu" "B.Cu")
		(net "P3V3_CC_R")
	)
	(segment
		(start 209.996024 -443.295024)
		(end 208.915 -442.214)
		(width 0.254)
		(layer "F.Cu")
		(net "P3V3_CC")
	)
	(segment
		(start 235.077 -430.53)
		(end 235.585 -431.038)
		(width 0.254)
		(layer "F.Cu")
		(net "P3V3_CC")
	)
	(segment
		(start 208.915 -442.214)
		(end 208.915 -439.4835)
		(width 0.254)
		(layer "F.Cu")
		(net "P3V3_CC")
	)
	(segment
		(start 228.114606 -443.295024)
		(end 209.996024 -443.295024)
		(width 0.254)
		(layer "F.Cu")
		(net "P3V3_CC")
	)
	(segment
		(start 235.585 -431.038)
		(end 235.585 -439.350912)
		(width 0.254)
		(layer "F.Cu")
		(net "P3V3_CC")
	)
	(segment
		(start 235.585 -439.350912)
		(end 231.640888 -443.295024)
		(width 0.254)
		(layer "F.Cu")
		(net "P3V3_CC")
	)
	(segment
		(start 231.640888 -443.295024)
		(end 228.114606 -443.295024)
		(width 0.254)
		(layer "F.Cu")
		(net "P3V3_CC")
	)
	(via
		(at 228.114606 -443.295024)
		(size 0.7112)
		(drill 0.3556)
		(layers "F.Cu" "B.Cu")
		(net "P3V3_CC")
	)
	(segment
		(start 227.965 -441.198)
		(end 227.203 -440.436)
		(width 0.254)
		(layer "F.Cu")
		(net "AGND_P3V3")
	)
	(segment
		(start 232.791 -437.261)
		(end 232.791 -437.4896)
		(width 0.254)
		(layer "F.Cu")
		(net "AGND_P3V3")
	)
	(segment
		(start 232.4735 -432.562)
		(end 233.426 -432.562)
		(width 0.254)
		(layer "F.Cu")
		(net "AGND_P3V3")
	)
	(segment
		(start 234.1626 -439.5724)
		(end 232.537 -441.198)
		(width 0.254)
		(layer "F.Cu")
		(net "AGND_P3V3")
	)
	(segment
		(start 227.1903 -439.6105)
		(end 227.203 -439.6232)
		(width 0.254)
		(layer "F.Cu")
		(net "AGND_P3V3")
	)
	(segment
		(start 230.3526 -437.4896)
		(end 228.499924 -435.636924)
		(width 0.254)
		(layer "F.Cu")
		(net "AGND_P3V3")
	)
	(segment
		(start 234.95 -434.086)
		(end 234.95 -436.7022)
		(width 0.254)
		(layer "F.Cu")
		(net "AGND_P3V3")
	)
	(segment
		(start 232.537 -441.198)
		(end 227.965 -441.198)
		(width 0.254)
		(layer "F.Cu")
		(net "AGND_P3V3")
	)
	(segment
		(start 228.499924 -435.636924)
		(end 228.499924 -435.090062)
		(width 0.254)
		(layer "F.Cu")
		(net "AGND_P3V3")
	)
	(segment
		(start 233.426 -432.562)
		(end 234.95 -434.086)
		(width 0.254)
		(layer "F.Cu")
		(net "AGND_P3V3")
	)
	(segment
		(start 234.1626 -437.4896)
		(end 234.1626 -439.5724)
		(width 0.254)
		(layer "F.Cu")
		(net "AGND_P3V3")
	)
	(segment
		(start 227.203 -440.436)
		(end 227.203 -439.6232)
		(width 0.254)
		(layer "F.Cu")
		(net "AGND_P3V3")
	)
	(segment
		(start 233.2355 -436.626)
		(end 233.2355 -436.8165)
		(width 0.254)
		(layer "F.Cu")
		(net "AGND_P3V3")
	)
	(segment
		(start 227.711 -427.99)
		(end 227.711 -426.974)
		(width 0.254)
		(layer "F.Cu")
		(net "AGND_P3V3")
	)
	(segment
		(start 232.791 -437.4896)
		(end 234.1626 -437.4896)
		(width 0.254)
		(layer "F.Cu")
		(net "AGND_P3V3")
	)
	(segment
		(start 233.2355 -436.8165)
		(end 232.791 -437.261)
		(width 0.254)
		(layer "F.Cu")
		(net "AGND_P3V3")
	)
	(segment
		(start 232.791 -437.4896)
		(end 230.3526 -437.4896)
		(width 0.254)
		(layer "F.Cu")
		(net "AGND_P3V3")
	)
	(segment
		(start 226.187 -439.6105)
		(end 227.1903 -439.6105)
		(width 0.254)
		(layer "F.Cu")
		(net "AGND_P3V3")
	)
	(segment
		(start 234.95 -436.7022)
		(end 234.1626 -437.4896)
		(width 0.254)
		(layer "F.Cu")
		(net "AGND_P3V3")
	)
	(via
		(at 227.711 -426.974)
		(size 0.508)
		(drill 0.254)
		(layers "F.Cu" "B.Cu")
		(net "AGND_P3V3")
	)
	(via
		(at 234.1626 -437.4896)
		(size 0.508)
		(drill 0.254)
		(layers "F.Cu" "B.Cu")
		(net "AGND_P3V3")
	)
	(segment
		(start 227.711 -426.974)
		(end 228.346 -426.339)
		(width 0.254)
		(layer "In5.Cu")
		(net "AGND_P3V3")
	)
	(segment
		(start 228.346 -426.339)
		(end 231.14 -426.339)
		(width 0.254)
		(layer "In5.Cu")
		(net "AGND_P3V3")
	)
	(segment
		(start 231.14 -426.339)
		(end 234.1626 -429.3616)
		(width 0.254)
		(layer "In5.Cu")
		(net "AGND_P3V3")
	)
	(segment
		(start 234.1626 -429.3616)
		(end 234.1626 -437.4896)
		(width 0.254)
		(layer "In5.Cu")
		(net "AGND_P3V3")
	)
	(segment
		(start 43.815 -138.176)
		(end 43.815 -135.325104)
		(width 0.17145)
		(layer "F.Cu")
		(net "TMP1_SDA")
	)
	(segment
		(start 44.870878 -134.6962)
		(end 45.9867 -134.6962)
		(width 0.17145)
		(layer "F.Cu")
		(net "TMP1_SDA")
	)
	(segment
		(start 43.815 -135.325104)
		(end 44.443904 -134.6962)
		(width 0.17145)
		(layer "F.Cu")
		(net "TMP1_SDA")
	)
	(segment
		(start 41.945052 -138.975338)
		(end 43.015662 -138.975338)
		(width 0.17145)
		(layer "F.Cu")
		(net "TMP1_SDA")
	)
	(segment
		(start 43.015662 -138.975338)
		(end 43.815 -138.176)
		(width 0.17145)
		(layer "F.Cu")
		(net "TMP1_SDA")
	)
	(segment
		(start 44.443904 -134.6962)
		(end 44.870878 -134.6962)
		(width 0.17145)
		(layer "F.Cu")
		(net "TMP1_SDA")
	)
	(segment
		(start 45.9867 -134.6962)
		(end 46.1645 -134.874)
		(width 0.17145)
		(layer "F.Cu")
		(net "TMP1_SDA")
	)
	(segment
		(start 44.870878 -135.03275)
		(end 44.870878 -134.6962)
		(width 0.17145)
		(layer "F.Cu")
		(net "TMP1_SDA")
	)
	(via
		(at 44.870878 -135.03275)
		(size 0.7112)
		(drill 0.3556)
		(layers "F.Cu" "B.Cu")
		(net "TMP1_SDA")
	)
	(segment
		(start 43.26255 -135.509)
		(end 43.26255 -135.09625)
		(width 0.17145)
		(layer "F.Cu")
		(net "TMP1_SCL")
	)
	(segment
		(start 44.21505 -134.14375)
		(end 45.87875 -134.14375)
		(width 0.17145)
		(layer "F.Cu")
		(net "TMP1_SCL")
	)
	(segment
		(start 42.926 -135.509)
		(end 43.26255 -135.509)
		(width 0.17145)
		(layer "F.Cu")
		(net "TMP1_SCL")
	)
	(segment
		(start 42.884598 -138.325098)
		(end 43.26255 -137.947146)
		(width 0.17145)
		(layer "F.Cu")
		(net "TMP1_SCL")
	)
	(segment
		(start 41.945052 -138.325098)
		(end 42.884598 -138.325098)
		(width 0.17145)
		(layer "F.Cu")
		(net "TMP1_SCL")
	)
	(segment
		(start 43.26255 -137.947146)
		(end 43.26255 -135.509)
		(width 0.17145)
		(layer "F.Cu")
		(net "TMP1_SCL")
	)
	(segment
		(start 43.26255 -135.09625)
		(end 44.21505 -134.14375)
		(width 0.17145)
		(layer "F.Cu")
		(net "TMP1_SCL")
	)
	(segment
		(start 45.87875 -134.14375)
		(end 46.1645 -133.858)
		(width 0.17145)
		(layer "F.Cu")
		(net "TMP1_SCL")
	)
	(via
		(at 42.926 -135.509)
		(size 0.7112)
		(drill 0.3556)
		(layers "F.Cu" "B.Cu")
		(net "TMP1_SCL")
	)
	(segment
		(start 9.780524 -164.403278)
		(end 7.642352 -166.54145)
		(width 0.17145)
		(layer "F.Cu")
		(net "SSD9_CLK0_OE_R_N")
	)
	(segment
		(start 89.143078 -93.588078)
		(end 91.72956 -96.17456)
		(width 0.17145)
		(layer "F.Cu")
		(net "SSD9_CLK0_OE_R_N")
	)
	(segment
		(start 5.588 -166.54145)
		(end 5.41655 -166.37)
		(width 0.17145)
		(layer "F.Cu")
		(net "SSD9_CLK0_OE_R_N")
	)
	(segment
		(start 7.642352 -166.54145)
		(end 5.588 -166.54145)
		(width 0.17145)
		(layer "F.Cu")
		(net "SSD9_CLK0_OE_R_N")
	)
	(segment
		(start 89.5985 -89.535)
		(end 89.5985 -90.9955)
		(width 0.17145)
		(layer "F.Cu")
		(net "SSD9_CLK0_OE_R_N")
	)
	(segment
		(start 9.780524 -99.33178)
		(end 9.780524 -164.403278)
		(width 0.17145)
		(layer "F.Cu")
		(net "SSD9_CLK0_OE_R_N")
	)
	(segment
		(start 5.41655 -166.37)
		(end 3.911854 -166.37)
		(width 0.17145)
		(layer "F.Cu")
		(net "SSD9_CLK0_OE_R_N")
	)
	(segment
		(start 88.89746 -88.5825)
		(end 89.662 -88.5825)
		(width 0.17145)
		(layer "F.Cu")
		(net "SSD9_CLK0_OE_R_N")
	)
	(segment
		(start 29.4894 -64.897)
		(end 28.304744 -66.081656)
		(width 0.17145)
		(layer "F.Cu")
		(net "SSD9_CLK0_OE_R_N")
	)
	(segment
		(start 3.41884 -167.14216)
		(end 2.249932 -167.14216)
		(width 0.17145)
		(layer "F.Cu")
		(net "SSD9_CLK0_OE_R_N")
	)
	(segment
		(start 15.528036 -93.584268)
		(end 9.780524 -99.33178)
		(width 0.17145)
		(layer "F.Cu")
		(net "SSD9_CLK0_OE_R_N")
	)
	(segment
		(start 89.662 -89.4715)
		(end 89.5985 -89.535)
		(width 0.17145)
		(layer "F.Cu")
		(net "SSD9_CLK0_OE_R_N")
	)
	(segment
		(start 3.724148 -166.836852)
		(end 3.41884 -167.14216)
		(width 0.17145)
		(layer "F.Cu")
		(net "SSD9_CLK0_OE_R_N")
	)
	(segment
		(start 91.72956 -96.17456)
		(end 91.72956 -97.17659)
		(width 0.17145)
		(layer "F.Cu")
		(net "SSD9_CLK0_OE_R_N")
	)
	(segment
		(start 88.86698 -88.61298)
		(end 88.89746 -88.5825)
		(width 0.17145)
		(layer "F.Cu")
		(net "SSD9_CLK0_OE_R_N")
	)
	(segment
		(start 3.724148 -166.557706)
		(end 3.724148 -166.836852)
		(width 0.17145)
		(layer "F.Cu")
		(net "SSD9_CLK0_OE_R_N")
	)
	(segment
		(start 15.528036 -75.529186)
		(end 15.528036 -93.584268)
		(width 0.17145)
		(layer "F.Cu")
		(net "SSD9_CLK0_OE_R_N")
	)
	(segment
		(start 28.304744 -66.081656)
		(end 19.80438 -74.58202)
		(width 0.17145)
		(layer "F.Cu")
		(net "SSD9_CLK0_OE_R_N")
	)
	(segment
		(start 89.662 -88.5825)
		(end 89.662 -89.4715)
		(width 0.17145)
		(layer "F.Cu")
		(net "SSD9_CLK0_OE_R_N")
	)
	(segment
		(start 32.766 -64.897)
		(end 29.4894 -64.897)
		(width 0.17145)
		(layer "F.Cu")
		(net "SSD9_CLK0_OE_R_N")
	)
	(segment
		(start 19.80438 -74.58202)
		(end 16.475202 -74.58202)
		(width 0.17145)
		(layer "F.Cu")
		(net "SSD9_CLK0_OE_R_N")
	)
	(segment
		(start 89.5985 -90.9955)
		(end 89.143078 -91.450922)
		(width 0.17145)
		(layer "F.Cu")
		(net "SSD9_CLK0_OE_R_N")
	)
	(segment
		(start 89.143078 -91.450922)
		(end 89.143078 -93.588078)
		(width 0.17145)
		(layer "F.Cu")
		(net "SSD9_CLK0_OE_R_N")
	)
	(segment
		(start 39.33825 -39.6875)
		(end 39.33825 -40.767)
		(width 0.17145)
		(layer "F.Cu")
		(net "SSD9_CLK0_OE_R_N")
	)
	(segment
		(start 16.475202 -74.58202)
		(end 15.528036 -75.529186)
		(width 0.17145)
		(layer "F.Cu")
		(net "SSD9_CLK0_OE_R_N")
	)
	(segment
		(start 3.911854 -166.37)
		(end 3.724148 -166.557706)
		(width 0.17145)
		(layer "F.Cu")
		(net "SSD9_CLK0_OE_R_N")
	)
	(via
		(at 39.33825 -40.767)
		(size 0.508)
		(drill 0.254)
		(layers "F.Cu" "B.Cu")
		(net "SSD9_CLK0_OE_R_N")
	)
	(via
		(at 88.86698 -88.61298)
		(size 0.508)
		(drill 0.254)
		(layers "F.Cu" "B.Cu")
		(net "SSD9_CLK0_OE_R_N")
	)
	(via
		(at 32.766 -64.897)
		(size 0.508)
		(drill 0.254)
		(layers "F.Cu" "B.Cu")
		(net "SSD9_CLK0_OE_R_N")
	)
	(via
		(at 28.304744 -66.081656)
		(size 0.7112)
		(drill 0.3556)
		(layers "F.Cu" "B.Cu")
		(net "SSD9_CLK0_OE_R_N")
	)
	(segment
		(start 33.5026 -65.6336)
		(end 47.9806 -65.6336)
		(width 0.1524)
		(layer "In2.Cu")
		(net "SSD9_CLK0_OE_R_N")
	)
	(segment
		(start 57.112154 -74.765154)
		(end 63.009272 -74.765154)
		(width 0.1524)
		(layer "In2.Cu")
		(net "SSD9_CLK0_OE_R_N")
	)
	(segment
		(start 47.9806 -65.6336)
		(end 57.112154 -74.765154)
		(width 0.1524)
		(layer "In2.Cu")
		(net "SSD9_CLK0_OE_R_N")
	)
	(segment
		(start 86.931754 -82.893154)
		(end 86.931754 -86.677754)
		(width 0.1524)
		(layer "In2.Cu")
		(net "SSD9_CLK0_OE_R_N")
	)
	(segment
		(start 81.58988 -77.55128)
		(end 86.931754 -82.893154)
		(width 0.1524)
		(layer "In2.Cu")
		(net "SSD9_CLK0_OE_R_N")
	)
	(segment
		(start 86.931754 -86.677754)
		(end 88.86698 -88.61298)
		(width 0.1524)
		(layer "In2.Cu")
		(net "SSD9_CLK0_OE_R_N")
	)
	(segment
		(start 65.795398 -77.55128)
		(end 81.58988 -77.55128)
		(width 0.1524)
		(layer "In2.Cu")
		(net "SSD9_CLK0_OE_R_N")
	)
	(segment
		(start 63.009272 -74.765154)
		(end 65.795398 -77.55128)
		(width 0.1524)
		(layer "In2.Cu")
		(net "SSD9_CLK0_OE_R_N")
	)
	(segment
		(start 32.766 -64.897)
		(end 33.5026 -65.6336)
		(width 0.1524)
		(layer "In2.Cu")
		(net "SSD9_CLK0_OE_R_N")
	)
	(segment
		(start 36.2966 -43.80865)
		(end 39.33825 -40.767)
		(width 0.1524)
		(layer "In5.Cu")
		(net "SSD9_CLK0_OE_R_N")
	)
	(segment
		(start 36.2966 -55.9562)
		(end 36.2966 -43.80865)
		(width 0.1524)
		(layer "In5.Cu")
		(net "SSD9_CLK0_OE_R_N")
	)
	(segment
		(start 34.2646 -63.3984)
		(end 34.2646 -57.9882)
		(width 0.1524)
		(layer "In5.Cu")
		(net "SSD9_CLK0_OE_R_N")
	)
	(segment
		(start 32.766 -64.897)
		(end 34.2646 -63.3984)
		(width 0.1524)
		(layer "In5.Cu")
		(net "SSD9_CLK0_OE_R_N")
	)
	(segment
		(start 34.2646 -57.9882)
		(end 36.2966 -55.9562)
		(width 0.1524)
		(layer "In5.Cu")
		(net "SSD9_CLK0_OE_R_N")
	)
	(segment
		(start 97.2185 -113.665)
		(end 97.155 -113.7285)
		(width 0.17145)
		(layer "F.Cu")
		(net "SSD8_CLK0_OE_R_N")
	)
	(segment
		(start 97.2185 -113.665)
		(end 97.2185 -112.1791)
		(width 0.17145)
		(layer "F.Cu")
		(net "SSD8_CLK0_OE_R_N")
	)
	(segment
		(start 97.2185 -112.1791)
		(end 97.673922 -111.723678)
		(width 0.17145)
		(layer "F.Cu")
		(net "SSD8_CLK0_OE_R_N")
	)
	(segment
		(start 97.155 -113.7285)
		(end 97.155 -114.6175)
		(width 0.17145)
		(layer "F.Cu")
		(net "SSD8_CLK0_OE_R_N")
	)
	(segment
		(start 95.73006 -107.28706)
		(end 95.73006 -106.02341)
		(width 0.17145)
		(layer "F.Cu")
		(net "SSD8_CLK0_OE_R_N")
	)
	(segment
		(start 97.673922 -109.230922)
		(end 95.73006 -107.28706)
		(width 0.17145)
		(layer "F.Cu")
		(net "SSD8_CLK0_OE_R_N")
	)
	(segment
		(start 36.54425 -143.1925)
		(end 36.54425 -144.11325)
		(width 0.17145)
		(layer "F.Cu")
		(net "SSD8_CLK0_OE_R_N")
	)
	(segment
		(start 97.673922 -111.723678)
		(end 97.673922 -109.230922)
		(width 0.17145)
		(layer "F.Cu")
		(net "SSD8_CLK0_OE_R_N")
	)
	(segment
		(start 97.939606 -114.6175)
		(end 97.944178 -114.612928)
		(width 0.17145)
		(layer "F.Cu")
		(net "SSD8_CLK0_OE_R_N")
	)
	(segment
		(start 36.54425 -144.11325)
		(end 38.3159 -145.8849)
		(width 0.17145)
		(layer "F.Cu")
		(net "SSD8_CLK0_OE_R_N")
	)
	(segment
		(start 97.155 -114.6175)
		(end 97.939606 -114.6175)
		(width 0.17145)
		(layer "F.Cu")
		(net "SSD8_CLK0_OE_R_N")
	)
	(via
		(at 38.3159 -145.8849)
		(size 0.508)
		(drill 0.254)
		(layers "F.Cu" "B.Cu")
		(net "SSD8_CLK0_OE_R_N")
	)
	(via
		(at 10.182098 -200.2536)
		(size 0.7112)
		(drill 0.3556)
		(layers "F.Cu" "B.Cu")
		(net "SSD8_CLK0_OE_R_N")
	)
	(via
		(at 97.944178 -114.612928)
		(size 0.508)
		(drill 0.254)
		(layers "F.Cu" "B.Cu")
		(net "SSD8_CLK0_OE_R_N")
	)
	(segment
		(start 41.293796 -170.8277)
		(end 41.293796 -181.083204)
		(width 0.17145)
		(layer "B.Cu")
		(net "SSD8_CLK0_OE_R_N")
	)
	(segment
		(start 10.182098 -199.240394)
		(end 10.182098 -200.2536)
		(width 0.17145)
		(layer "B.Cu")
		(net "SSD8_CLK0_OE_R_N")
	)
	(segment
		(start 10.182098 -220.195902)
		(end 7.62 -222.758)
		(width 0.17145)
		(layer "B.Cu")
		(net "SSD8_CLK0_OE_R_N")
	)
	(segment
		(start 37.719 -184.658)
		(end 21.844 -184.658)
		(width 0.17145)
		(layer "B.Cu")
		(net "SSD8_CLK0_OE_R_N")
	)
	(segment
		(start 38.3159 -145.8849)
		(end 38.3159 -147.55495)
		(width 0.17145)
		(layer "B.Cu")
		(net "SSD8_CLK0_OE_R_N")
	)
	(segment
		(start 7.62 -222.758)
		(end 6.197854 -222.758)
		(width 0.17145)
		(layer "B.Cu")
		(net "SSD8_CLK0_OE_R_N")
	)
	(segment
		(start 38.3159 -147.55495)
		(end 35.94735 -149.9235)
		(width 0.17145)
		(layer "B.Cu")
		(net "SSD8_CLK0_OE_R_N")
	)
	(segment
		(start 21.844 -184.658)
		(end 11.038078 -195.463922)
		(width 0.17145)
		(layer "B.Cu")
		(net "SSD8_CLK0_OE_R_N")
	)
	(segment
		(start 33.782 -156.61005)
		(end 33.782 -163.315904)
		(width 0.17145)
		(layer "B.Cu")
		(net "SSD8_CLK0_OE_R_N")
	)
	(segment
		(start 6.197854 -222.758)
		(end 5.6642 -223.291654)
		(width 0.17145)
		(layer "B.Cu")
		(net "SSD8_CLK0_OE_R_N")
	)
	(segment
		(start 35.94735 -154.4447)
		(end 33.782 -156.61005)
		(width 0.17145)
		(layer "B.Cu")
		(net "SSD8_CLK0_OE_R_N")
	)
	(segment
		(start 10.182098 -200.2536)
		(end 10.182098 -220.195902)
		(width 0.17145)
		(layer "B.Cu")
		(net "SSD8_CLK0_OE_R_N")
	)
	(segment
		(start 41.293796 -181.083204)
		(end 37.719 -184.658)
		(width 0.17145)
		(layer "B.Cu")
		(net "SSD8_CLK0_OE_R_N")
	)
	(segment
		(start 11.038078 -198.384414)
		(end 10.182098 -199.240394)
		(width 0.17145)
		(layer "B.Cu")
		(net "SSD8_CLK0_OE_R_N")
	)
	(segment
		(start 5.6642 -223.4184)
		(end 4.340606 -224.741994)
		(width 0.17145)
		(layer "B.Cu")
		(net "SSD8_CLK0_OE_R_N")
	)
	(segment
		(start 11.038078 -195.463922)
		(end 11.038078 -198.384414)
		(width 0.17145)
		(layer "B.Cu")
		(net "SSD8_CLK0_OE_R_N")
	)
	(segment
		(start 35.94735 -149.9235)
		(end 35.94735 -154.4447)
		(width 0.17145)
		(layer "B.Cu")
		(net "SSD8_CLK0_OE_R_N")
	)
	(segment
		(start 4.340606 -224.741994)
		(end 1.868932 -224.741994)
		(width 0.17145)
		(layer "B.Cu")
		(net "SSD8_CLK0_OE_R_N")
	)
	(segment
		(start 33.782 -163.315904)
		(end 41.293796 -170.8277)
		(width 0.17145)
		(layer "B.Cu")
		(net "SSD8_CLK0_OE_R_N")
	)
	(segment
		(start 5.6642 -223.291654)
		(end 5.6642 -223.4184)
		(width 0.17145)
		(layer "B.Cu")
		(net "SSD8_CLK0_OE_R_N")
	)
	(segment
		(start 60.2615 -119.3419)
		(end 90.3605 -119.3419)
		(width 0.1524)
		(layer "In5.Cu")
		(net "SSD8_CLK0_OE_R_N")
	)
	(segment
		(start 43.9928 -135.6106)
		(end 60.2615 -119.3419)
		(width 0.1524)
		(layer "In5.Cu")
		(net "SSD8_CLK0_OE_R_N")
	)
	(segment
		(start 43.9928 -136.8298)
		(end 43.9928 -135.6106)
		(width 0.1524)
		(layer "In5.Cu")
		(net "SSD8_CLK0_OE_R_N")
	)
	(segment
		(start 38.3159 -145.8849)
		(end 39.9542 -144.2466)
		(width 0.1524)
		(layer "In5.Cu")
		(net "SSD8_CLK0_OE_R_N")
	)
	(segment
		(start 90.3605 -119.3419)
		(end 94.63786 -115.06454)
		(width 0.1524)
		(layer "In5.Cu")
		(net "SSD8_CLK0_OE_R_N")
	)
	(segment
		(start 39.9542 -144.2466)
		(end 39.9542 -140.8684)
		(width 0.1524)
		(layer "In5.Cu")
		(net "SSD8_CLK0_OE_R_N")
	)
	(segment
		(start 39.9542 -140.8684)
		(end 43.9928 -136.8298)
		(width 0.1524)
		(layer "In5.Cu")
		(net "SSD8_CLK0_OE_R_N")
	)
	(segment
		(start 97.492566 -115.06454)
		(end 97.944178 -114.612928)
		(width 0.1524)
		(layer "In5.Cu")
		(net "SSD8_CLK0_OE_R_N")
	)
	(segment
		(start 94.63786 -115.06454)
		(end 97.492566 -115.06454)
		(width 0.1524)
		(layer "In5.Cu")
		(net "SSD8_CLK0_OE_R_N")
	)
	(segment
		(start 7.395718 -316.454282)
		(end 9.144 -314.706)
		(width 0.17145)
		(layer "F.Cu")
		(net "SSD7_CLK0_OE_R_N")
	)
	(segment
		(start 95.73006 -215.24341)
		(end 95.73006 -216.50706)
		(width 0.17145)
		(layer "F.Cu")
		(net "SSD7_CLK0_OE_R_N")
	)
	(segment
		(start 96.360488 -223.704912)
		(end 96.493076 -223.8375)
		(width 0.17145)
		(layer "F.Cu")
		(net "SSD7_CLK0_OE_R_N")
	)
	(segment
		(start 97.2185 -221.4245)
		(end 97.2185 -222.885)
		(width 0.17145)
		(layer "F.Cu")
		(net "SSD7_CLK0_OE_R_N")
	)
	(segment
		(start 3.278886 -317.142114)
		(end 3.966718 -316.454282)
		(width 0.17145)
		(layer "F.Cu")
		(net "SSD7_CLK0_OE_R_N")
	)
	(segment
		(start 53.05425 -241.992658)
		(end 53.05425 -243.1288)
		(width 0.17145)
		(layer "F.Cu")
		(net "SSD7_CLK0_OE_R_N")
	)
	(segment
		(start 97.155 -223.8375)
		(end 97.2185 -223.774)
		(width 0.17145)
		(layer "F.Cu")
		(net "SSD7_CLK0_OE_R_N")
	)
	(segment
		(start 95.73006 -216.50706)
		(end 97.663 -218.44)
		(width 0.17145)
		(layer "F.Cu")
		(net "SSD7_CLK0_OE_R_N")
	)
	(segment
		(start 3.966718 -316.454282)
		(end 7.395718 -316.454282)
		(width 0.17145)
		(layer "F.Cu")
		(net "SSD7_CLK0_OE_R_N")
	)
	(segment
		(start 97.663 -218.44)
		(end 97.663 -220.98)
		(width 0.17145)
		(layer "F.Cu")
		(net "SSD7_CLK0_OE_R_N")
	)
	(segment
		(start 97.2185 -223.774)
		(end 97.2185 -222.885)
		(width 0.17145)
		(layer "F.Cu")
		(net "SSD7_CLK0_OE_R_N")
	)
	(segment
		(start 97.663 -220.98)
		(end 97.2185 -221.4245)
		(width 0.17145)
		(layer "F.Cu")
		(net "SSD7_CLK0_OE_R_N")
	)
	(segment
		(start 9.144 -314.706)
		(end 9.144 -313.944)
		(width 0.17145)
		(layer "F.Cu")
		(net "SSD7_CLK0_OE_R_N")
	)
	(segment
		(start 2.249932 -317.142114)
		(end 3.278886 -317.142114)
		(width 0.17145)
		(layer "F.Cu")
		(net "SSD7_CLK0_OE_R_N")
	)
	(segment
		(start 96.493076 -223.8375)
		(end 97.155 -223.8375)
		(width 0.17145)
		(layer "F.Cu")
		(net "SSD7_CLK0_OE_R_N")
	)
	(via
		(at 28.6258 -274.2184)
		(size 0.7112)
		(drill 0.3556)
		(layers "F.Cu" "B.Cu")
		(net "SSD7_CLK0_OE_R_N")
	)
	(via
		(at 53.05425 -243.1288)
		(size 0.508)
		(drill 0.254)
		(layers "F.Cu" "B.Cu")
		(net "SSD7_CLK0_OE_R_N")
	)
	(via
		(at 49.784 -271.8562)
		(size 0.508)
		(drill 0.254)
		(layers "F.Cu" "B.Cu")
		(net "SSD7_CLK0_OE_R_N")
	)
	(via
		(at 9.144 -313.944)
		(size 0.508)
		(drill 0.254)
		(layers "F.Cu" "B.Cu")
		(net "SSD7_CLK0_OE_R_N")
	)
	(via
		(at 96.360488 -223.704912)
		(size 0.508)
		(drill 0.254)
		(layers "F.Cu" "B.Cu")
		(net "SSD7_CLK0_OE_R_N")
	)
	(via
		(at 35.3822 -271.018)
		(size 0.508)
		(drill 0.254)
		(layers "F.Cu" "B.Cu")
		(net "SSD7_CLK0_OE_R_N")
	)
	(segment
		(start 31.8262 -271.018)
		(end 35.3822 -271.018)
		(width 0.17145)
		(layer "B.Cu")
		(net "SSD7_CLK0_OE_R_N")
	)
	(segment
		(start 53.331872 -268.308328)
		(end 49.784 -271.8562)
		(width 0.17145)
		(layer "B.Cu")
		(net "SSD7_CLK0_OE_R_N")
	)
	(segment
		(start 9.144 -313.944)
		(end 9.8044 -313.2836)
		(width 0.17145)
		(layer "B.Cu")
		(net "SSD7_CLK0_OE_R_N")
	)
	(segment
		(start 28.6258 -274.2184)
		(end 31.8262 -271.018)
		(width 0.17145)
		(layer "B.Cu")
		(net "SSD7_CLK0_OE_R_N")
	)
	(segment
		(start 53.05425 -243.1288)
		(end 53.05425 -243.93398)
		(width 0.17145)
		(layer "B.Cu")
		(net "SSD7_CLK0_OE_R_N")
	)
	(segment
		(start 53.05425 -243.93398)
		(end 53.331872 -244.211602)
		(width 0.17145)
		(layer "B.Cu")
		(net "SSD7_CLK0_OE_R_N")
	)
	(segment
		(start 9.8044 -293.0398)
		(end 28.6258 -274.2184)
		(width 0.17145)
		(layer "B.Cu")
		(net "SSD7_CLK0_OE_R_N")
	)
	(segment
		(start 9.8044 -313.2836)
		(end 9.8044 -293.0398)
		(width 0.17145)
		(layer "B.Cu")
		(net "SSD7_CLK0_OE_R_N")
	)
	(segment
		(start 53.331872 -244.211602)
		(end 53.331872 -268.308328)
		(width 0.17145)
		(layer "B.Cu")
		(net "SSD7_CLK0_OE_R_N")
	)
	(segment
		(start 49.784 -271.8562)
		(end 36.2204 -271.8562)
		(width 0.1524)
		(layer "In2.Cu")
		(net "SSD7_CLK0_OE_R_N")
	)
	(segment
		(start 96.360488 -223.704912)
		(end 95.400114 -224.665286)
		(width 0.1524)
		(layer "In2.Cu")
		(net "SSD7_CLK0_OE_R_N")
	)
	(segment
		(start 95.400114 -226.798886)
		(end 50.3428 -271.8562)
		(width 0.1524)
		(layer "In2.Cu")
		(net "SSD7_CLK0_OE_R_N")
	)
	(segment
		(start 36.2204 -271.8562)
		(end 35.3822 -271.018)
		(width 0.1524)
		(layer "In2.Cu")
		(net "SSD7_CLK0_OE_R_N")
	)
	(segment
		(start 95.400114 -224.665286)
		(end 95.400114 -226.798886)
		(width 0.1524)
		(layer "In2.Cu")
		(net "SSD7_CLK0_OE_R_N")
	)
	(segment
		(start 50.3428 -271.8562)
		(end 49.784 -271.8562)
		(width 0.1524)
		(layer "In2.Cu")
		(net "SSD7_CLK0_OE_R_N")
	)
	(segment
		(start 95.73006 -310.86806)
		(end 95.73006 -309.60441)
		(width 0.17145)
		(layer "F.Cu")
		(net "SSD6_CLK0_OE_R_N")
	)
	(segment
		(start 3.396234 -358.742234)
		(end 3.724148 -359.070148)
		(width 0.17145)
		(layer "F.Cu")
		(net "SSD6_CLK0_OE_R_N")
	)
	(segment
		(start 8.128 -359.918)
		(end 8.128 -359.9434)
		(width 0.17145)
		(layer "F.Cu")
		(net "SSD6_CLK0_OE_R_N")
	)
	(segment
		(start 8.128 -359.9434)
		(end 8.255 -360.0704)
		(width 0.17145)
		(layer "F.Cu")
		(net "SSD6_CLK0_OE_R_N")
	)
	(segment
		(start 7.767066 -359.557066)
		(end 8.128 -359.918)
		(width 0.17145)
		(layer "F.Cu")
		(net "SSD6_CLK0_OE_R_N")
	)
	(segment
		(start 40.35425 -348.43339)
		(end 40.35425 -349.5294)
		(width 0.17145)
		(layer "F.Cu")
		(net "SSD6_CLK0_OE_R_N")
	)
	(segment
		(start 97.607628 -312.745628)
		(end 95.73006 -310.86806)
		(width 0.17145)
		(layer "F.Cu")
		(net "SSD6_CLK0_OE_R_N")
	)
	(segment
		(start 97.2185 -317.246)
		(end 97.155 -317.3095)
		(width 0.17145)
		(layer "F.Cu")
		(net "SSD6_CLK0_OE_R_N")
	)
	(segment
		(start 3.724148 -359.070148)
		(end 3.724148 -359.283508)
		(width 0.17145)
		(layer "F.Cu")
		(net "SSD6_CLK0_OE_R_N")
	)
	(segment
		(start 2.249932 -358.742234)
		(end 3.396234 -358.742234)
		(width 0.17145)
		(layer "F.Cu")
		(net "SSD6_CLK0_OE_R_N")
	)
	(segment
		(start 97.155 -317.3095)
		(end 97.155 -318.1985)
		(width 0.17145)
		(layer "F.Cu")
		(net "SSD6_CLK0_OE_R_N")
	)
	(segment
		(start 3.997706 -359.557066)
		(end 7.767066 -359.557066)
		(width 0.17145)
		(layer "F.Cu")
		(net "SSD6_CLK0_OE_R_N")
	)
	(segment
		(start 97.2185 -317.246)
		(end 97.2185 -315.8109)
		(width 0.17145)
		(layer "F.Cu")
		(net "SSD6_CLK0_OE_R_N")
	)
	(segment
		(start 97.607628 -315.421772)
		(end 97.607628 -312.745628)
		(width 0.17145)
		(layer "F.Cu")
		(net "SSD6_CLK0_OE_R_N")
	)
	(segment
		(start 3.724148 -359.283508)
		(end 3.997706 -359.557066)
		(width 0.17145)
		(layer "F.Cu")
		(net "SSD6_CLK0_OE_R_N")
	)
	(segment
		(start 97.155 -318.1985)
		(end 96.487234 -318.1985)
		(width 0.17145)
		(layer "F.Cu")
		(net "SSD6_CLK0_OE_R_N")
	)
	(segment
		(start 97.2185 -315.8109)
		(end 97.607628 -315.421772)
		(width 0.17145)
		(layer "F.Cu")
		(net "SSD6_CLK0_OE_R_N")
	)
	(segment
		(start 96.487234 -318.1985)
		(end 96.36633 -318.077596)
		(width 0.17145)
		(layer "F.Cu")
		(net "SSD6_CLK0_OE_R_N")
	)
	(via
		(at 96.36633 -318.077596)
		(size 0.508)
		(drill 0.254)
		(layers "F.Cu" "B.Cu")
		(net "SSD6_CLK0_OE_R_N")
	)
	(via
		(at 24.039068 -369.8494)
		(size 0.7112)
		(drill 0.3556)
		(layers "F.Cu" "B.Cu")
		(net "SSD6_CLK0_OE_R_N")
	)
	(via
		(at 40.35425 -349.5294)
		(size 0.508)
		(drill 0.254)
		(layers "F.Cu" "B.Cu")
		(net "SSD6_CLK0_OE_R_N")
	)
	(via
		(at 8.255 -360.0704)
		(size 0.508)
		(drill 0.254)
		(layers "F.Cu" "B.Cu")
		(net "SSD6_CLK0_OE_R_N")
	)
	(segment
		(start 40.35425 -355.104446)
		(end 40.35425 -349.5294)
		(width 0.17145)
		(layer "B.Cu")
		(net "SSD6_CLK0_OE_R_N")
	)
	(segment
		(start 24.039068 -369.8494)
		(end 21.705824 -369.8494)
		(width 0.17145)
		(layer "B.Cu")
		(net "SSD6_CLK0_OE_R_N")
	)
	(segment
		(start 21.140674 -370.41455)
		(end 18.008854 -370.41455)
		(width 0.17145)
		(layer "B.Cu")
		(net "SSD6_CLK0_OE_R_N")
	)
	(segment
		(start 8.255 -360.660696)
		(end 8.255 -360.0704)
		(width 0.17145)
		(layer "B.Cu")
		(net "SSD6_CLK0_OE_R_N")
	)
	(segment
		(start 18.008854 -370.41455)
		(end 8.255 -360.660696)
		(width 0.17145)
		(layer "B.Cu")
		(net "SSD6_CLK0_OE_R_N")
	)
	(segment
		(start 21.705824 -369.8494)
		(end 21.140674 -370.41455)
		(width 0.17145)
		(layer "B.Cu")
		(net "SSD6_CLK0_OE_R_N")
	)
	(segment
		(start 25.609296 -369.8494)
		(end 40.35425 -355.104446)
		(width 0.17145)
		(layer "B.Cu")
		(net "SSD6_CLK0_OE_R_N")
	)
	(segment
		(start 24.039068 -369.8494)
		(end 25.609296 -369.8494)
		(width 0.17145)
		(layer "B.Cu")
		(net "SSD6_CLK0_OE_R_N")
	)
	(segment
		(start 86.784434 -318.720724)
		(end 85.53831 -317.4746)
		(width 0.1524)
		(layer "In5.Cu")
		(net "SSD6_CLK0_OE_R_N")
	)
	(segment
		(start 59.0042 -317.4746)
		(end 52.1462 -324.3326)
		(width 0.1524)
		(layer "In5.Cu")
		(net "SSD6_CLK0_OE_R_N")
	)
	(segment
		(start 52.1462 -324.3326)
		(end 52.1462 -335.8388)
		(width 0.1524)
		(layer "In5.Cu")
		(net "SSD6_CLK0_OE_R_N")
	)
	(segment
		(start 52.1462 -335.8388)
		(end 40.35425 -347.63075)
		(width 0.1524)
		(layer "In5.Cu")
		(net "SSD6_CLK0_OE_R_N")
	)
	(segment
		(start 85.53831 -317.4746)
		(end 59.0042 -317.4746)
		(width 0.1524)
		(layer "In5.Cu")
		(net "SSD6_CLK0_OE_R_N")
	)
	(segment
		(start 96.36633 -318.077596)
		(end 95.723202 -318.720724)
		(width 0.1524)
		(layer "In5.Cu")
		(net "SSD6_CLK0_OE_R_N")
	)
	(segment
		(start 40.35425 -347.63075)
		(end 40.35425 -349.5294)
		(width 0.1524)
		(layer "In5.Cu")
		(net "SSD6_CLK0_OE_R_N")
	)
	(segment
		(start 95.723202 -318.720724)
		(end 86.784434 -318.720724)
		(width 0.1524)
		(layer "In5.Cu")
		(net "SSD6_CLK0_OE_R_N")
	)
	(segment
		(start 88.60155 -442.533024)
		(end 88.60155 -439.71845)
		(width 0.17145)
		(layer "F.Cu")
		(net "SSD5_CLK0_OE_R_N")
	)
	(segment
		(start 88.2015 -442.933074)
		(end 88.60155 -442.533024)
		(width 0.17145)
		(layer "F.Cu")
		(net "SSD5_CLK0_OE_R_N")
	)
	(segment
		(start 87.291672 -444.688214)
		(end 87.420958 -444.8175)
		(width 0.17145)
		(layer "F.Cu")
		(net "SSD5_CLK0_OE_R_N")
	)
	(segment
		(start 57.11825 -447.9925)
		(end 57.11825 -449.0974)
		(width 0.17145)
		(layer "F.Cu")
		(net "SSD5_CLK0_OE_R_N")
	)
	(segment
		(start 88.2015 -443.865)
		(end 88.2015 -442.933074)
		(width 0.17145)
		(layer "F.Cu")
		(net "SSD5_CLK0_OE_R_N")
	)
	(segment
		(start 91.23045 -437.08955)
		(end 91.23045 -436.22341)
		(width 0.17145)
		(layer "F.Cu")
		(net "SSD5_CLK0_OE_R_N")
	)
	(segment
		(start 88.138 -444.8175)
		(end 88.2015 -444.754)
		(width 0.17145)
		(layer "F.Cu")
		(net "SSD5_CLK0_OE_R_N")
	)
	(segment
		(start 88.60155 -439.71845)
		(end 91.23045 -437.08955)
		(width 0.17145)
		(layer "F.Cu")
		(net "SSD5_CLK0_OE_R_N")
	)
	(segment
		(start 88.2015 -444.754)
		(end 88.2015 -443.865)
		(width 0.17145)
		(layer "F.Cu")
		(net "SSD5_CLK0_OE_R_N")
	)
	(segment
		(start 87.420958 -444.8175)
		(end 88.138 -444.8175)
		(width 0.17145)
		(layer "F.Cu")
		(net "SSD5_CLK0_OE_R_N")
	)
	(via
		(at 37.3888 -437.9976)
		(size 0.508)
		(drill 0.254)
		(layers "F.Cu" "B.Cu")
		(net "SSD5_CLK0_OE_R_N")
	)
	(via
		(at 57.11825 -449.0974)
		(size 0.508)
		(drill 0.254)
		(layers "F.Cu" "B.Cu")
		(net "SSD5_CLK0_OE_R_N")
	)
	(via
		(at 21.2344 -441.0964)
		(size 0.7112)
		(drill 0.3556)
		(layers "F.Cu" "B.Cu")
		(net "SSD5_CLK0_OE_R_N")
	)
	(via
		(at 87.291672 -444.688214)
		(size 0.508)
		(drill 0.254)
		(layers "F.Cu" "B.Cu")
		(net "SSD5_CLK0_OE_R_N")
	)
	(segment
		(start 35.668204 -441.673996)
		(end 37.4142 -439.928)
		(width 0.17145)
		(layer "B.Cu")
		(net "SSD5_CLK0_OE_R_N")
	)
	(segment
		(start 5.842 -433.197)
		(end 4.586986 -431.941986)
		(width 0.17145)
		(layer "B.Cu")
		(net "SSD5_CLK0_OE_R_N")
	)
	(segment
		(start 70.3961 -445.4017)
		(end 59.2328 -445.4017)
		(width 0.17145)
		(layer "B.Cu")
		(net "SSD5_CLK0_OE_R_N")
	)
	(segment
		(start 4.586986 -431.941986)
		(end 1.868932 -431.941986)
		(width 0.17145)
		(layer "B.Cu")
		(net "SSD5_CLK0_OE_R_N")
	)
	(segment
		(start 21.2344 -441.0964)
		(end 19.815048 -439.677048)
		(width 0.17145)
		(layer "B.Cu")
		(net "SSD5_CLK0_OE_R_N")
	)
	(segment
		(start 21.2344 -441.0964)
		(end 21.717 -441.579)
		(width 0.17145)
		(layer "B.Cu")
		(net "SSD5_CLK0_OE_R_N")
	)
	(segment
		(start 37.4142 -439.928)
		(end 37.4142 -438.0484)
		(width 0.17145)
		(layer "B.Cu")
		(net "SSD5_CLK0_OE_R_N")
	)
	(segment
		(start 37.4142 -438.0484)
		(end 37.3888 -438.023)
		(width 0.17145)
		(layer "B.Cu")
		(net "SSD5_CLK0_OE_R_N")
	)
	(segment
		(start 6.116066 -433.197)
		(end 5.842 -433.197)
		(width 0.17145)
		(layer "B.Cu")
		(net "SSD5_CLK0_OE_R_N")
	)
	(segment
		(start 37.3888 -438.023)
		(end 37.3888 -437.9976)
		(width 0.17145)
		(layer "B.Cu")
		(net "SSD5_CLK0_OE_R_N")
	)
	(segment
		(start 57.11825 -447.51625)
		(end 57.11825 -449.0974)
		(width 0.17145)
		(layer "B.Cu")
		(net "SSD5_CLK0_OE_R_N")
	)
	(segment
		(start 21.717 -441.579)
		(end 25.195784 -441.579)
		(width 0.17145)
		(layer "B.Cu")
		(net "SSD5_CLK0_OE_R_N")
	)
	(segment
		(start 59.2328 -445.4017)
		(end 57.11825 -447.51625)
		(width 0.17145)
		(layer "B.Cu")
		(net "SSD5_CLK0_OE_R_N")
	)
	(segment
		(start 85.92185 -443.318392)
		(end 72.479408 -443.318392)
		(width 0.17145)
		(layer "B.Cu")
		(net "SSD5_CLK0_OE_R_N")
	)
	(segment
		(start 19.815048 -439.677048)
		(end 12.596114 -439.677048)
		(width 0.17145)
		(layer "B.Cu")
		(net "SSD5_CLK0_OE_R_N")
	)
	(segment
		(start 12.596114 -439.677048)
		(end 6.116066 -433.197)
		(width 0.17145)
		(layer "B.Cu")
		(net "SSD5_CLK0_OE_R_N")
	)
	(segment
		(start 25.29078 -441.673996)
		(end 35.668204 -441.673996)
		(width 0.17145)
		(layer "B.Cu")
		(net "SSD5_CLK0_OE_R_N")
	)
	(segment
		(start 25.195784 -441.579)
		(end 25.29078 -441.673996)
		(width 0.17145)
		(layer "B.Cu")
		(net "SSD5_CLK0_OE_R_N")
	)
	(segment
		(start 72.479408 -443.318392)
		(end 70.3961 -445.4017)
		(width 0.17145)
		(layer "B.Cu")
		(net "SSD5_CLK0_OE_R_N")
	)
	(segment
		(start 87.291672 -444.688214)
		(end 85.92185 -443.318392)
		(width 0.17145)
		(layer "B.Cu")
		(net "SSD5_CLK0_OE_R_N")
	)
	(segment
		(start 84.39531 -443.0522)
		(end 79.541878 -443.0522)
		(width 0.1524)
		(layer "In5.Cu")
		(net "SSD5_CLK0_OE_R_N")
	)
	(segment
		(start 86.031324 -444.688214)
		(end 84.39531 -443.0522)
		(width 0.1524)
		(layer "In5.Cu")
		(net "SSD5_CLK0_OE_R_N")
	)
	(segment
		(start 65.3034 -437.769)
		(end 54.2544 -437.769)
		(width 0.1524)
		(layer "In5.Cu")
		(net "SSD5_CLK0_OE_R_N")
	)
	(segment
		(start 39.12362 -436.372)
		(end 37.49802 -437.9976)
		(width 0.1524)
		(layer "In5.Cu")
		(net "SSD5_CLK0_OE_R_N")
	)
	(segment
		(start 76.849478 -440.3598)
		(end 67.8942 -440.3598)
		(width 0.1524)
		(layer "In5.Cu")
		(net "SSD5_CLK0_OE_R_N")
	)
	(segment
		(start 37.49802 -437.9976)
		(end 37.3888 -437.9976)
		(width 0.1524)
		(layer "In5.Cu")
		(net "SSD5_CLK0_OE_R_N")
	)
	(segment
		(start 52.8574 -436.372)
		(end 39.12362 -436.372)
		(width 0.1524)
		(layer "In5.Cu")
		(net "SSD5_CLK0_OE_R_N")
	)
	(segment
		(start 67.8942 -440.3598)
		(end 65.3034 -437.769)
		(width 0.1524)
		(layer "In5.Cu")
		(net "SSD5_CLK0_OE_R_N")
	)
	(segment
		(start 54.2544 -437.769)
		(end 52.8574 -436.372)
		(width 0.1524)
		(layer "In5.Cu")
		(net "SSD5_CLK0_OE_R_N")
	)
	(segment
		(start 87.291672 -444.688214)
		(end 86.031324 -444.688214)
		(width 0.1524)
		(layer "In5.Cu")
		(net "SSD5_CLK0_OE_R_N")
	)
	(segment
		(start 79.541878 -443.0522)
		(end 76.849478 -440.3598)
		(width 0.1524)
		(layer "In5.Cu")
		(net "SSD5_CLK0_OE_R_N")
	)
	(segment
		(start 96.4184 -200.8886)
		(end 96.4184 -202.0062)
		(width 0.17145)
		(layer "F.Cu")
		(net "SSD4_CLK0_OE_R_N")
	)
	(segment
		(start 96.9645 -198.755)
		(end 96.9645 -200.3425)
		(width 0.17145)
		(layer "F.Cu")
		(net "SSD4_CLK0_OE_R_N")
	)
	(segment
		(start 97.028 -197.8025)
		(end 97.747836 -197.8025)
		(width 0.17145)
		(layer "F.Cu")
		(net "SSD4_CLK0_OE_R_N")
	)
	(segment
		(start 96.4184 -203.9366)
		(end 96.23044 -204.12456)
		(width 0.17145)
		(layer "F.Cu")
		(net "SSD4_CLK0_OE_R_N")
	)
	(segment
		(start 97.747836 -197.8025)
		(end 97.839784 -197.894448)
		(width 0.17145)
		(layer "F.Cu")
		(net "SSD4_CLK0_OE_R_N")
	)
	(segment
		(start 220.7895 -37.81425)
		(end 219.70365 -37.81425)
		(width 0.17145)
		(layer "F.Cu")
		(net "SSD4_CLK0_OE_R_N")
	)
	(segment
		(start 96.4184 -202.0062)
		(end 96.4184 -203.9366)
		(width 0.17145)
		(layer "F.Cu")
		(net "SSD4_CLK0_OE_R_N")
	)
	(segment
		(start 96.9645 -200.3425)
		(end 96.4184 -200.8886)
		(width 0.17145)
		(layer "F.Cu")
		(net "SSD4_CLK0_OE_R_N")
	)
	(segment
		(start 96.23044 -204.12456)
		(end 96.23044 -206.39659)
		(width 0.17145)
		(layer "F.Cu")
		(net "SSD4_CLK0_OE_R_N")
	)
	(segment
		(start 97.028 -198.6915)
		(end 97.028 -197.8025)
		(width 0.17145)
		(layer "F.Cu")
		(net "SSD4_CLK0_OE_R_N")
	)
	(segment
		(start 96.9645 -198.755)
		(end 97.028 -198.6915)
		(width 0.17145)
		(layer "F.Cu")
		(net "SSD4_CLK0_OE_R_N")
	)
	(via
		(at 96.4184 -202.0062)
		(size 0.7112)
		(drill 0.3556)
		(layers "F.Cu" "B.Cu")
		(net "SSD4_CLK0_OE_R_N")
	)
	(via
		(at 219.70365 -37.81425)
		(size 0.508)
		(drill 0.254)
		(layers "F.Cu" "B.Cu")
		(net "SSD4_CLK0_OE_R_N")
	)
	(via
		(at 97.839784 -197.894448)
		(size 0.508)
		(drill 0.254)
		(layers "F.Cu" "B.Cu")
		(net "SSD4_CLK0_OE_R_N")
	)
	(segment
		(start 29.1211 -55.047896)
		(end 29.1211 -52.247292)
		(width 0.17145)
		(layer "B.Cu")
		(net "SSD4_CLK0_OE_R_N")
	)
	(segment
		(start 18.0213 -81.68767)
		(end 18.0213 -72.618092)
		(width 0.17145)
		(layer "B.Cu")
		(net "SSD4_CLK0_OE_R_N")
	)
	(segment
		(start 204.844142 -37.81425)
		(end 219.70365 -37.81425)
		(width 0.17145)
		(layer "B.Cu")
		(net "SSD4_CLK0_OE_R_N")
	)
	(segment
		(start 5.969 -197.866)
		(end 7.112 -197.866)
		(width 0.17145)
		(layer "B.Cu")
		(net "SSD4_CLK0_OE_R_N")
	)
	(segment
		(start 29.1211 -52.247292)
		(end 37.896292 -43.4721)
		(width 0.17145)
		(layer "B.Cu")
		(net "SSD4_CLK0_OE_R_N")
	)
	(segment
		(start 8.7503 -90.95867)
		(end 18.0213 -81.68767)
		(width 0.17145)
		(layer "B.Cu")
		(net "SSD4_CLK0_OE_R_N")
	)
	(segment
		(start 3.81 -196.55155)
		(end 4.65455 -196.55155)
		(width 0.17145)
		(layer "B.Cu")
		(net "SSD4_CLK0_OE_R_N")
	)
	(segment
		(start 25.114504 -59.054492)
		(end 29.1211 -55.047896)
		(width 0.17145)
		(layer "B.Cu")
		(net "SSD4_CLK0_OE_R_N")
	)
	(segment
		(start 37.896292 -43.4721)
		(end 199.186292 -43.4721)
		(width 0.17145)
		(layer "B.Cu")
		(net "SSD4_CLK0_OE_R_N")
	)
	(segment
		(start 4.65455 -196.55155)
		(end 5.969 -197.866)
		(width 0.17145)
		(layer "B.Cu")
		(net "SSD4_CLK0_OE_R_N")
	)
	(segment
		(start 3.6195 -196.74205)
		(end 3.81 -196.55155)
		(width 0.17145)
		(layer "B.Cu")
		(net "SSD4_CLK0_OE_R_N")
	)
	(segment
		(start 1.868932 -196.74205)
		(end 3.6195 -196.74205)
		(width 0.17145)
		(layer "B.Cu")
		(net "SSD4_CLK0_OE_R_N")
	)
	(segment
		(start 25.114504 -65.524888)
		(end 25.114504 -59.054492)
		(width 0.17145)
		(layer "B.Cu")
		(net "SSD4_CLK0_OE_R_N")
	)
	(segment
		(start 8.7503 -196.2277)
		(end 8.7503 -90.95867)
		(width 0.17145)
		(layer "B.Cu")
		(net "SSD4_CLK0_OE_R_N")
	)
	(segment
		(start 199.186292 -43.4721)
		(end 204.844142 -37.81425)
		(width 0.17145)
		(layer "B.Cu")
		(net "SSD4_CLK0_OE_R_N")
	)
	(segment
		(start 18.0213 -72.618092)
		(end 25.114504 -65.524888)
		(width 0.17145)
		(layer "B.Cu")
		(net "SSD4_CLK0_OE_R_N")
	)
	(segment
		(start 7.112 -197.866)
		(end 8.7503 -196.2277)
		(width 0.17145)
		(layer "B.Cu")
		(net "SSD4_CLK0_OE_R_N")
	)
	(segment
		(start 223.6216 -183.918352)
		(end 223.6216 -155.4988)
		(width 0.1524)
		(layer "In5.Cu")
		(net "SSD4_CLK0_OE_R_N")
	)
	(segment
		(start 228.102414 -84.287614)
		(end 228.102414 -77.840586)
		(width 0.1524)
		(layer "In5.Cu")
		(net "SSD4_CLK0_OE_R_N")
	)
	(segment
		(start 97.839784 -197.894448)
		(end 97.932748 -197.894448)
		(width 0.1524)
		(layer "In5.Cu")
		(net "SSD4_CLK0_OE_R_N")
	)
	(segment
		(start 223.030288 -37.81425)
		(end 219.70365 -37.81425)
		(width 0.1524)
		(layer "In5.Cu")
		(net "SSD4_CLK0_OE_R_N")
	)
	(segment
		(start 219.20835 -151.08555)
		(end 219.20835 -133.41985)
		(width 0.1524)
		(layer "In5.Cu")
		(net "SSD4_CLK0_OE_R_N")
	)
	(segment
		(start 191.1604 -207.2386)
		(end 207.9498 -190.4492)
		(width 0.1524)
		(layer "In5.Cu")
		(net "SSD4_CLK0_OE_R_N")
	)
	(segment
		(start 234.631484 -49.415446)
		(end 223.030288 -37.81425)
		(width 0.1524)
		(layer "In5.Cu")
		(net "SSD4_CLK0_OE_R_N")
	)
	(segment
		(start 234.631484 -71.311516)
		(end 234.631484 -49.415446)
		(width 0.1524)
		(layer "In5.Cu")
		(net "SSD4_CLK0_OE_R_N")
	)
	(segment
		(start 230.125016 -122.503184)
		(end 230.125016 -86.310216)
		(width 0.1524)
		(layer "In5.Cu")
		(net "SSD4_CLK0_OE_R_N")
	)
	(segment
		(start 217.090752 -190.4492)
		(end 223.6216 -183.918352)
		(width 0.1524)
		(layer "In5.Cu")
		(net "SSD4_CLK0_OE_R_N")
	)
	(segment
		(start 219.20835 -133.41985)
		(end 230.125016 -122.503184)
		(width 0.1524)
		(layer "In5.Cu")
		(net "SSD4_CLK0_OE_R_N")
	)
	(segment
		(start 102.0445 -202.0062)
		(end 137.922 -202.0062)
		(width 0.1524)
		(layer "In5.Cu")
		(net "SSD4_CLK0_OE_R_N")
	)
	(segment
		(start 230.125016 -86.310216)
		(end 228.102414 -84.287614)
		(width 0.1524)
		(layer "In5.Cu")
		(net "SSD4_CLK0_OE_R_N")
	)
	(segment
		(start 137.922 -202.0062)
		(end 143.1544 -207.2386)
		(width 0.1524)
		(layer "In5.Cu")
		(net "SSD4_CLK0_OE_R_N")
	)
	(segment
		(start 97.932748 -197.894448)
		(end 102.0445 -202.0062)
		(width 0.1524)
		(layer "In5.Cu")
		(net "SSD4_CLK0_OE_R_N")
	)
	(segment
		(start 207.9498 -190.4492)
		(end 217.090752 -190.4492)
		(width 0.1524)
		(layer "In5.Cu")
		(net "SSD4_CLK0_OE_R_N")
	)
	(segment
		(start 143.1544 -207.2386)
		(end 191.1604 -207.2386)
		(width 0.1524)
		(layer "In5.Cu")
		(net "SSD4_CLK0_OE_R_N")
	)
	(segment
		(start 223.6216 -155.4988)
		(end 219.20835 -151.08555)
		(width 0.1524)
		(layer "In5.Cu")
		(net "SSD4_CLK0_OE_R_N")
	)
	(segment
		(start 228.102414 -77.840586)
		(end 234.631484 -71.311516)
		(width 0.1524)
		(layer "In5.Cu")
		(net "SSD4_CLK0_OE_R_N")
	)
	(segment
		(start 106.934 -207.5815)
		(end 106.045 -207.5815)
		(width 0.17145)
		(layer "F.Cu")
		(net "SSD3_CLK0_OE_R_N")
	)
	(segment
		(start 99.66706 -209.06994)
		(end 101.55555 -207.18145)
		(width 0.17145)
		(layer "F.Cu")
		(net "SSD3_CLK0_OE_R_N")
	)
	(segment
		(start 104.5845 -207.5815)
		(end 106.045 -207.5815)
		(width 0.17145)
		(layer "F.Cu")
		(net "SSD3_CLK0_OE_R_N")
	)
	(segment
		(start 4.211066 -286.93237)
		(end 4.02082 -286.742124)
		(width 0.17145)
		(layer "F.Cu")
		(net "SSD3_CLK0_OE_R_N")
	)
	(segment
		(start 104.18445 -207.18145)
		(end 104.5845 -207.5815)
		(width 0.17145)
		(layer "F.Cu")
		(net "SSD3_CLK0_OE_R_N")
	)
	(segment
		(start 101.55555 -207.18145)
		(end 104.18445 -207.18145)
		(width 0.17145)
		(layer "F.Cu")
		(net "SSD3_CLK0_OE_R_N")
	)
	(segment
		(start 8.628634 -287.462214)
		(end 7.34441 -287.462214)
		(width 0.17145)
		(layer "F.Cu")
		(net "SSD3_CLK0_OE_R_N")
	)
	(segment
		(start 7.34441 -287.462214)
		(end 6.814566 -286.93237)
		(width 0.17145)
		(layer "F.Cu")
		(net "SSD3_CLK0_OE_R_N")
	)
	(segment
		(start 106.9975 -207.645)
		(end 106.934 -207.5815)
		(width 0.17145)
		(layer "F.Cu")
		(net "SSD3_CLK0_OE_R_N")
	)
	(segment
		(start 106.9975 -208.305146)
		(end 106.9975 -207.645)
		(width 0.17145)
		(layer "F.Cu")
		(net "SSD3_CLK0_OE_R_N")
	)
	(segment
		(start 219.74175 -137.08761)
		(end 219.74175 -138.176)
		(width 0.17145)
		(layer "F.Cu")
		(net "SSD3_CLK0_OE_R_N")
	)
	(segment
		(start 6.814566 -286.93237)
		(end 4.211066 -286.93237)
		(width 0.17145)
		(layer "F.Cu")
		(net "SSD3_CLK0_OE_R_N")
	)
	(segment
		(start 98.40341 -209.06994)
		(end 99.66706 -209.06994)
		(width 0.17145)
		(layer "F.Cu")
		(net "SSD3_CLK0_OE_R_N")
	)
	(segment
		(start 106.863388 -208.439258)
		(end 106.9975 -208.305146)
		(width 0.17145)
		(layer "F.Cu")
		(net "SSD3_CLK0_OE_R_N")
	)
	(segment
		(start 4.02082 -286.742124)
		(end 2.249932 -286.742124)
		(width 0.17145)
		(layer "F.Cu")
		(net "SSD3_CLK0_OE_R_N")
	)
	(via
		(at 8.628634 -287.462214)
		(size 0.508)
		(drill 0.254)
		(layers "F.Cu" "B.Cu")
		(net "SSD3_CLK0_OE_R_N")
	)
	(via
		(at 35.8775 -248.4247)
		(size 0.7112)
		(drill 0.3556)
		(layers "F.Cu" "B.Cu")
		(net "SSD3_CLK0_OE_R_N")
	)
	(via
		(at 219.74175 -138.176)
		(size 0.508)
		(drill 0.254)
		(layers "F.Cu" "B.Cu")
		(net "SSD3_CLK0_OE_R_N")
	)
	(via
		(at 41.0718 -241.5032)
		(size 0.508)
		(drill 0.254)
		(layers "F.Cu" "B.Cu")
		(net "SSD3_CLK0_OE_R_N")
	)
	(via
		(at 106.863388 -208.439258)
		(size 0.508)
		(drill 0.254)
		(layers "F.Cu" "B.Cu")
		(net "SSD3_CLK0_OE_R_N")
	)
	(segment
		(start 41.0718 -243.2304)
		(end 35.8775 -248.4247)
		(width 0.17145)
		(layer "B.Cu")
		(net "SSD3_CLK0_OE_R_N")
	)
	(segment
		(start 10.854436 -287.82518)
		(end 32.5882 -266.091416)
		(width 0.17145)
		(layer "B.Cu")
		(net "SSD3_CLK0_OE_R_N")
	)
	(segment
		(start 8.628634 -287.462214)
		(end 8.9916 -287.82518)
		(width 0.17145)
		(layer "B.Cu")
		(net "SSD3_CLK0_OE_R_N")
	)
	(segment
		(start 32.5882 -251.714)
		(end 35.8775 -248.4247)
		(width 0.17145)
		(layer "B.Cu")
		(net "SSD3_CLK0_OE_R_N")
	)
	(segment
		(start 32.5882 -266.091416)
		(end 32.5882 -251.714)
		(width 0.17145)
		(layer "B.Cu")
		(net "SSD3_CLK0_OE_R_N")
	)
	(segment
		(start 8.9916 -287.82518)
		(end 10.854436 -287.82518)
		(width 0.17145)
		(layer "B.Cu")
		(net "SSD3_CLK0_OE_R_N")
	)
	(segment
		(start 41.0718 -241.5032)
		(end 41.0718 -243.2304)
		(width 0.17145)
		(layer "B.Cu")
		(net "SSD3_CLK0_OE_R_N")
	)
	(segment
		(start 111.01705 -202.5396)
		(end 107.435904 -206.120746)
		(width 0.1524)
		(layer "In5.Cu")
		(net "SSD3_CLK0_OE_R_N")
	)
	(segment
		(start 188.56198 -210.5914)
		(end 145.75282 -210.5914)
		(width 0.1524)
		(layer "In5.Cu")
		(net "SSD3_CLK0_OE_R_N")
	)
	(segment
		(start 107.435904 -206.120746)
		(end 107.435904 -207.866742)
		(width 0.1524)
		(layer "In5.Cu")
		(net "SSD3_CLK0_OE_R_N")
	)
	(segment
		(start 217.3224 -190.9826)
		(end 208.17078 -190.9826)
		(width 0.1524)
		(layer "In5.Cu")
		(net "SSD3_CLK0_OE_R_N")
	)
	(segment
		(start 224.155 -155.27782)
		(end 224.155 -184.15)
		(width 0.1524)
		(layer "In5.Cu")
		(net "SSD3_CLK0_OE_R_N")
	)
	(segment
		(start 105.2068 -219.0242)
		(end 97.1804 -227.0506)
		(width 0.1524)
		(layer "In5.Cu")
		(net "SSD3_CLK0_OE_R_N")
	)
	(segment
		(start 208.17078 -190.9826)
		(end 188.56198 -210.5914)
		(width 0.1524)
		(layer "In5.Cu")
		(net "SSD3_CLK0_OE_R_N")
	)
	(segment
		(start 105.2068 -210.095846)
		(end 105.2068 -219.0242)
		(width 0.1524)
		(layer "In5.Cu")
		(net "SSD3_CLK0_OE_R_N")
	)
	(segment
		(start 106.863388 -208.439258)
		(end 105.2068 -210.095846)
		(width 0.1524)
		(layer "In5.Cu")
		(net "SSD3_CLK0_OE_R_N")
	)
	(segment
		(start 107.435904 -207.866742)
		(end 106.863388 -208.439258)
		(width 0.1524)
		(layer "In5.Cu")
		(net "SSD3_CLK0_OE_R_N")
	)
	(segment
		(start 145.75282 -210.5914)
		(end 137.70102 -202.5396)
		(width 0.1524)
		(layer "In5.Cu")
		(net "SSD3_CLK0_OE_R_N")
	)
	(segment
		(start 219.74175 -150.86457)
		(end 224.155 -155.27782)
		(width 0.1524)
		(layer "In5.Cu")
		(net "SSD3_CLK0_OE_R_N")
	)
	(segment
		(start 137.70102 -202.5396)
		(end 111.01705 -202.5396)
		(width 0.1524)
		(layer "In5.Cu")
		(net "SSD3_CLK0_OE_R_N")
	)
	(segment
		(start 97.1804 -227.0506)
		(end 57.16778 -227.0506)
		(width 0.1524)
		(layer "In5.Cu")
		(net "SSD3_CLK0_OE_R_N")
	)
	(segment
		(start 42.71518 -241.5032)
		(end 41.0718 -241.5032)
		(width 0.1524)
		(layer "In5.Cu")
		(net "SSD3_CLK0_OE_R_N")
	)
	(segment
		(start 219.74175 -138.176)
		(end 219.74175 -150.86457)
		(width 0.1524)
		(layer "In5.Cu")
		(net "SSD3_CLK0_OE_R_N")
	)
	(segment
		(start 57.16778 -227.0506)
		(end 42.71518 -241.5032)
		(width 0.1524)
		(layer "In5.Cu")
		(net "SSD3_CLK0_OE_R_N")
	)
	(segment
		(start 224.155 -184.15)
		(end 217.3224 -190.9826)
		(width 0.1524)
		(layer "In5.Cu")
		(net "SSD3_CLK0_OE_R_N")
	)
	(segment
		(start 98.6155 -293.116)
		(end 98.679 -293.0525)
		(width 0.17145)
		(layer "F.Cu")
		(net "SSD2_CLK0_OE_R_N")
	)
	(segment
		(start 98.679 -292.1635)
		(end 99.5426 -292.1635)
		(width 0.17145)
		(layer "F.Cu")
		(net "SSD2_CLK0_OE_R_N")
	)
	(segment
		(start 98.0186 -296.1894)
		(end 98.0186 -297.688)
		(width 0.17145)
		(layer "F.Cu")
		(net "SSD2_CLK0_OE_R_N")
	)
	(segment
		(start 7.6962 -332.486)
		(end 7.7978 -332.3844)
		(width 0.17145)
		(layer "F.Cu")
		(net "SSD2_CLK0_OE_R_N")
	)
	(segment
		(start 98.6155 -294.6781)
		(end 98.0186 -295.275)
		(width 0.17145)
		(layer "F.Cu")
		(net "SSD2_CLK0_OE_R_N")
	)
	(segment
		(start 98.679 -293.0525)
		(end 98.679 -292.1635)
		(width 0.17145)
		(layer "F.Cu")
		(net "SSD2_CLK0_OE_R_N")
	)
	(segment
		(start 96.23044 -299.47616)
		(end 96.23044 -300.75759)
		(width 0.17145)
		(layer "F.Cu")
		(net "SSD2_CLK0_OE_R_N")
	)
	(segment
		(start 98.0186 -295.275)
		(end 98.0186 -296.1894)
		(width 0.17145)
		(layer "F.Cu")
		(net "SSD2_CLK0_OE_R_N")
	)
	(segment
		(start 98.0186 -297.688)
		(end 96.23044 -299.47616)
		(width 0.17145)
		(layer "F.Cu")
		(net "SSD2_CLK0_OE_R_N")
	)
	(segment
		(start 2.249932 -332.342236)
		(end 6.333236 -332.342236)
		(width 0.17145)
		(layer "F.Cu")
		(net "SSD2_CLK0_OE_R_N")
	)
	(segment
		(start 219.74175 -241.1984)
		(end 219.74175 -240.087658)
		(width 0.17145)
		(layer "F.Cu")
		(net "SSD2_CLK0_OE_R_N")
	)
	(segment
		(start 6.477 -332.486)
		(end 7.6962 -332.486)
		(width 0.17145)
		(layer "F.Cu")
		(net "SSD2_CLK0_OE_R_N")
	)
	(segment
		(start 98.6155 -293.116)
		(end 98.6155 -294.6781)
		(width 0.17145)
		(layer "F.Cu")
		(net "SSD2_CLK0_OE_R_N")
	)
	(segment
		(start 6.333236 -332.342236)
		(end 6.477 -332.486)
		(width 0.17145)
		(layer "F.Cu")
		(net "SSD2_CLK0_OE_R_N")
	)
	(via
		(at 7.7978 -332.3844)
		(size 0.508)
		(drill 0.254)
		(layers "F.Cu" "B.Cu")
		(net "SSD2_CLK0_OE_R_N")
	)
	(via
		(at 219.74175 -241.1984)
		(size 0.508)
		(drill 0.254)
		(layers "F.Cu" "B.Cu")
		(net "SSD2_CLK0_OE_R_N")
	)
	(via
		(at 99.5426 -292.1635)
		(size 0.508)
		(drill 0.254)
		(layers "F.Cu" "B.Cu")
		(net "SSD2_CLK0_OE_R_N")
	)
	(via
		(at 98.0186 -296.1894)
		(size 0.7112)
		(drill 0.3556)
		(layers "F.Cu" "B.Cu")
		(net "SSD2_CLK0_OE_R_N")
	)
	(segment
		(start 99.0981 -291.719)
		(end 99.5426 -292.1635)
		(width 0.1524)
		(layer "In5.Cu")
		(net "SSD2_CLK0_OE_R_N")
	)
	(segment
		(start 211.00796 -292.1762)
		(end 99.5553 -292.1762)
		(width 0.1524)
		(layer "In5.Cu")
		(net "SSD2_CLK0_OE_R_N")
	)
	(segment
		(start 220.853 -292.5572)
		(end 211.38896 -292.5572)
		(width 0.1524)
		(layer "In5.Cu")
		(net "SSD2_CLK0_OE_R_N")
	)
	(segment
		(start 96.2152 -291.719)
		(end 99.0981 -291.719)
		(width 0.1524)
		(layer "In5.Cu")
		(net "SSD2_CLK0_OE_R_N")
	)
	(segment
		(start 73.59904 -292.1762)
		(end 95.758 -292.1762)
		(width 0.1524)
		(layer "In5.Cu")
		(net "SSD2_CLK0_OE_R_N")
	)
	(segment
		(start 224.23882 -241.1984)
		(end 226.2378 -243.19738)
		(width 0.1524)
		(layer "In5.Cu")
		(net "SSD2_CLK0_OE_R_N")
	)
	(segment
		(start 226.2378 -247.164098)
		(end 224.1042 -249.297698)
		(width 0.1524)
		(layer "In5.Cu")
		(net "SSD2_CLK0_OE_R_N")
	)
	(segment
		(start 25.46604 -315.4172)
		(end 43.62704 -315.4172)
		(width 0.1524)
		(layer "In5.Cu")
		(net "SSD2_CLK0_OE_R_N")
	)
	(segment
		(start 8.136636 -332.3844)
		(end 8.7122 -331.808836)
		(width 0.1524)
		(layer "In5.Cu")
		(net "SSD2_CLK0_OE_R_N")
	)
	(segment
		(start 8.7122 -331.808836)
		(end 9.074404 -331.808836)
		(width 0.1524)
		(layer "In5.Cu")
		(net "SSD2_CLK0_OE_R_N")
	)
	(segment
		(start 224.1042 -249.297698)
		(end 224.1042 -289.306)
		(width 0.1524)
		(layer "In5.Cu")
		(net "SSD2_CLK0_OE_R_N")
	)
	(segment
		(start 64.32804 -301.4472)
		(end 73.59904 -292.1762)
		(width 0.1524)
		(layer "In5.Cu")
		(net "SSD2_CLK0_OE_R_N")
	)
	(segment
		(start 43.62704 -315.4172)
		(end 57.59704 -301.4472)
		(width 0.1524)
		(layer "In5.Cu")
		(net "SSD2_CLK0_OE_R_N")
	)
	(segment
		(start 226.2378 -243.19738)
		(end 226.2378 -247.164098)
		(width 0.1524)
		(layer "In5.Cu")
		(net "SSD2_CLK0_OE_R_N")
	)
	(segment
		(start 57.59704 -301.4472)
		(end 64.32804 -301.4472)
		(width 0.1524)
		(layer "In5.Cu")
		(net "SSD2_CLK0_OE_R_N")
	)
	(segment
		(start 7.7978 -332.3844)
		(end 8.136636 -332.3844)
		(width 0.1524)
		(layer "In5.Cu")
		(net "SSD2_CLK0_OE_R_N")
	)
	(segment
		(start 9.074404 -331.808836)
		(end 25.46604 -315.4172)
		(width 0.1524)
		(layer "In5.Cu")
		(net "SSD2_CLK0_OE_R_N")
	)
	(segment
		(start 211.38896 -292.5572)
		(end 211.00796 -292.1762)
		(width 0.1524)
		(layer "In5.Cu")
		(net "SSD2_CLK0_OE_R_N")
	)
	(segment
		(start 219.74175 -241.1984)
		(end 224.23882 -241.1984)
		(width 0.1524)
		(layer "In5.Cu")
		(net "SSD2_CLK0_OE_R_N")
	)
	(segment
		(start 95.758 -292.1762)
		(end 96.2152 -291.719)
		(width 0.1524)
		(layer "In5.Cu")
		(net "SSD2_CLK0_OE_R_N")
	)
	(segment
		(start 224.1042 -289.306)
		(end 220.853 -292.5572)
		(width 0.1524)
		(layer "In5.Cu")
		(net "SSD2_CLK0_OE_R_N")
	)
	(segment
		(start 99.5553 -292.1762)
		(end 99.5426 -292.1635)
		(width 0.1524)
		(layer "In5.Cu")
		(net "SSD2_CLK0_OE_R_N")
	)
	(segment
		(start 97.83445 -94.40037)
		(end 96.23044 -96.00438)
		(width 0.17145)
		(layer "F.Cu")
		(net "SSD14_CLK0_OE_R_N")
	)
	(segment
		(start 2.249932 -164.742114)
		(end 3.366262 -164.742114)
		(width 0.17145)
		(layer "F.Cu")
		(net "SSD14_CLK0_OE_R_N")
	)
	(segment
		(start 74.3458 -42.40657)
		(end 74.3204 -42.40657)
		(width 0.17145)
		(layer "F.Cu")
		(net "SSD14_CLK0_OE_R_N")
	)
	(segment
		(start 98.679 -88.5825)
		(end 99.5045 -88.5825)
		(width 0.17145)
		(layer "F.Cu")
		(net "SSD14_CLK0_OE_R_N")
	)
	(segment
		(start 3.366262 -164.742114)
		(end 3.724148 -165.1)
		(width 0.17145)
		(layer "F.Cu")
		(net "SSD14_CLK0_OE_R_N")
	)
	(segment
		(start 3.724148 -165.1)
		(end 3.724148 -165.283388)
		(width 0.17145)
		(layer "F.Cu")
		(net "SSD14_CLK0_OE_R_N")
	)
	(segment
		(start 98.6155 -90.9955)
		(end 97.83445 -91.77655)
		(width 0.17145)
		(layer "F.Cu")
		(net "SSD14_CLK0_OE_R_N")
	)
	(segment
		(start 24.7396 -55.9054)
		(end 24.7396 -55.9308)
		(width 0.17145)
		(layer "F.Cu")
		(net "SSD14_CLK0_OE_R_N")
	)
	(segment
		(start 6.010148 -165.439852)
		(end 8.123174 -163.326826)
		(width 0.17145)
		(layer "F.Cu")
		(net "SSD14_CLK0_OE_R_N")
	)
	(segment
		(start 100.258372 -87.828628)
		(end 100.258372 -68.319142)
		(width 0.17145)
		(layer "F.Cu")
		(net "SSD14_CLK0_OE_R_N")
	)
	(segment
		(start 99.5045 -88.5825)
		(end 100.258372 -87.828628)
		(width 0.17145)
		(layer "F.Cu")
		(net "SSD14_CLK0_OE_R_N")
	)
	(segment
		(start 97.83445 -91.77655)
		(end 97.83445 -94.40037)
		(width 0.17145)
		(layer "F.Cu")
		(net "SSD14_CLK0_OE_R_N")
	)
	(segment
		(start 8.123174 -98.349308)
		(end 14.230096 -92.242386)
		(width 0.17145)
		(layer "F.Cu")
		(net "SSD14_CLK0_OE_R_N")
	)
	(segment
		(start 8.123174 -163.326826)
		(end 8.123174 -98.349308)
		(width 0.17145)
		(layer "F.Cu")
		(net "SSD14_CLK0_OE_R_N")
	)
	(segment
		(start 96.23044 -96.00438)
		(end 96.23044 -97.17659)
		(width 0.17145)
		(layer "F.Cu")
		(net "SSD14_CLK0_OE_R_N")
	)
	(segment
		(start 14.230096 -92.242386)
		(end 14.230096 -74.307446)
		(width 0.17145)
		(layer "F.Cu")
		(net "SSD14_CLK0_OE_R_N")
	)
	(segment
		(start 3.880612 -165.439852)
		(end 6.010148 -165.439852)
		(width 0.17145)
		(layer "F.Cu")
		(net "SSD14_CLK0_OE_R_N")
	)
	(segment
		(start 25.8445 -55.90286)
		(end 24.74214 -55.90286)
		(width 0.17145)
		(layer "F.Cu")
		(net "SSD14_CLK0_OE_R_N")
	)
	(segment
		(start 100.258372 -68.319142)
		(end 74.3458 -42.40657)
		(width 0.17145)
		(layer "F.Cu")
		(net "SSD14_CLK0_OE_R_N")
	)
	(segment
		(start 98.679 -89.4715)
		(end 98.679 -88.5825)
		(width 0.17145)
		(layer "F.Cu")
		(net "SSD14_CLK0_OE_R_N")
	)
	(segment
		(start 24.74214 -55.90286)
		(end 24.7396 -55.9054)
		(width 0.17145)
		(layer "F.Cu")
		(net "SSD14_CLK0_OE_R_N")
	)
	(segment
		(start 98.6155 -89.535)
		(end 98.6155 -90.9955)
		(width 0.17145)
		(layer "F.Cu")
		(net "SSD14_CLK0_OE_R_N")
	)
	(segment
		(start 98.6155 -89.535)
		(end 98.679 -89.4715)
		(width 0.17145)
		(layer "F.Cu")
		(net "SSD14_CLK0_OE_R_N")
	)
	(segment
		(start 3.724148 -165.283388)
		(end 3.880612 -165.439852)
		(width 0.17145)
		(layer "F.Cu")
		(net "SSD14_CLK0_OE_R_N")
	)
	(via
		(at 26.8605 -55.3085)
		(size 0.7112)
		(drill 0.3556)
		(layers "F.Cu" "B.Cu")
		(net "SSD14_CLK0_OE_R_N")
	)
	(via
		(at 24.7396 -55.9308)
		(size 0.508)
		(drill 0.254)
		(layers "F.Cu" "B.Cu")
		(net "SSD14_CLK0_OE_R_N")
	)
	(via
		(at 74.3204 -42.40657)
		(size 0.508)
		(drill 0.254)
		(layers "F.Cu" "B.Cu")
		(net "SSD14_CLK0_OE_R_N")
	)
	(via
		(at 14.230096 -74.307446)
		(size 0.508)
		(drill 0.254)
		(layers "F.Cu" "B.Cu")
		(net "SSD14_CLK0_OE_R_N")
	)
	(segment
		(start 24.7396 -55.9308)
		(end 26.2382 -55.9308)
		(width 0.17145)
		(layer "B.Cu")
		(net "SSD14_CLK0_OE_R_N")
	)
	(segment
		(start 51.6636 -42.3672)
		(end 74.28103 -42.3672)
		(width 0.17145)
		(layer "B.Cu")
		(net "SSD14_CLK0_OE_R_N")
	)
	(segment
		(start 26.8605 -55.3085)
		(end 27.9146 -54.2544)
		(width 0.17145)
		(layer "B.Cu")
		(net "SSD14_CLK0_OE_R_N")
	)
	(segment
		(start 49.3522 -42.3672)
		(end 49.8348 -41.8846)
		(width 0.17145)
		(layer "B.Cu")
		(net "SSD14_CLK0_OE_R_N")
	)
	(segment
		(start 49.8348 -41.8846)
		(end 51.181 -41.8846)
		(width 0.17145)
		(layer "B.Cu")
		(net "SSD14_CLK0_OE_R_N")
	)
	(segment
		(start 51.181 -41.8846)
		(end 51.6636 -42.3672)
		(width 0.17145)
		(layer "B.Cu")
		(net "SSD14_CLK0_OE_R_N")
	)
	(segment
		(start 26.2382 -55.9308)
		(end 26.8605 -55.3085)
		(width 0.17145)
		(layer "B.Cu")
		(net "SSD14_CLK0_OE_R_N")
	)
	(segment
		(start 27.9146 -51.891184)
		(end 37.438584 -42.3672)
		(width 0.17145)
		(layer "B.Cu")
		(net "SSD14_CLK0_OE_R_N")
	)
	(segment
		(start 37.438584 -42.3672)
		(end 49.3522 -42.3672)
		(width 0.17145)
		(layer "B.Cu")
		(net "SSD14_CLK0_OE_R_N")
	)
	(segment
		(start 74.28103 -42.3672)
		(end 74.3204 -42.40657)
		(width 0.17145)
		(layer "B.Cu")
		(net "SSD14_CLK0_OE_R_N")
	)
	(segment
		(start 27.9146 -54.2544)
		(end 27.9146 -51.891184)
		(width 0.17145)
		(layer "B.Cu")
		(net "SSD14_CLK0_OE_R_N")
	)
	(segment
		(start 14.230096 -74.307446)
		(end 14.230096 -73.958704)
		(width 0.1524)
		(layer "In5.Cu")
		(net "SSD14_CLK0_OE_R_N")
	)
	(segment
		(start 24.7396 -63.4492)
		(end 24.7396 -55.9308)
		(width 0.1524)
		(layer "In5.Cu")
		(net "SSD14_CLK0_OE_R_N")
	)
	(segment
		(start 14.230096 -73.958704)
		(end 24.7396 -63.4492)
		(width 0.1524)
		(layer "In5.Cu")
		(net "SSD14_CLK0_OE_R_N")
	)
	(segment
		(start 24.1046 -158.3182)
		(end 24.689308 -158.902908)
		(width 0.17145)
		(layer "F.Cu")
		(net "SSD13_CLK0_OE_R_N")
	)
	(segment
		(start 88.138 -113.7285)
		(end 88.2015 -113.665)
		(width 0.17145)
		(layer "F.Cu")
		(net "SSD13_CLK0_OE_R_N")
	)
	(segment
		(start 42.780712 -146.812)
		(end 37.61486 -151.977852)
		(width 0.17145)
		(layer "F.Cu")
		(net "SSD13_CLK0_OE_R_N")
	)
	(segment
		(start 88.934798 -114.6175)
		(end 88.138 -114.6175)
		(width 0.17145)
		(layer "F.Cu")
		(net "SSD13_CLK0_OE_R_N")
	)
	(segment
		(start 24.689308 -158.902908)
		(end 25.8445 -158.902908)
		(width 0.17145)
		(layer "F.Cu")
		(net "SSD13_CLK0_OE_R_N")
	)
	(segment
		(start 12.427204 -193.802)
		(end 12.427204 -185.057796)
		(width 0.17145)
		(layer "F.Cu")
		(net "SSD13_CLK0_OE_R_N")
	)
	(segment
		(start 3.707384 -199.492616)
		(end 3.707384 -199.389746)
		(width 0.17145)
		(layer "F.Cu")
		(net "SSD13_CLK0_OE_R_N")
	)
	(segment
		(start 12.84224 -184.64276)
		(end 12.84224 -165.989)
		(width 0.17145)
		(layer "F.Cu")
		(net "SSD13_CLK0_OE_R_N")
	)
	(segment
		(start 47.9806 -148.0312)
		(end 46.7614 -146.812)
		(width 0.17145)
		(layer "F.Cu")
		(net "SSD13_CLK0_OE_R_N")
	)
	(segment
		(start 12.427204 -185.057796)
		(end 12.84224 -184.64276)
		(width 0.17145)
		(layer "F.Cu")
		(net "SSD13_CLK0_OE_R_N")
	)
	(segment
		(start 32.66186 -151.977852)
		(end 25.8445 -158.795212)
		(width 0.17145)
		(layer "F.Cu")
		(net "SSD13_CLK0_OE_R_N")
	)
	(segment
		(start 22.5044 -158.3182)
		(end 24.1046 -158.3182)
		(width 0.17145)
		(layer "F.Cu")
		(net "SSD13_CLK0_OE_R_N")
	)
	(segment
		(start 3.257804 -199.942196)
		(end 3.707384 -199.492616)
		(width 0.17145)
		(layer "F.Cu")
		(net "SSD13_CLK0_OE_R_N")
	)
	(segment
		(start 88.138 -114.6175)
		(end 88.138 -113.7285)
		(width 0.17145)
		(layer "F.Cu")
		(net "SSD13_CLK0_OE_R_N")
	)
	(segment
		(start 37.61486 -151.977852)
		(end 32.66186 -151.977852)
		(width 0.17145)
		(layer "F.Cu")
		(net "SSD13_CLK0_OE_R_N")
	)
	(segment
		(start 88.646 -111.8616)
		(end 88.646 -109.5756)
		(width 0.17145)
		(layer "F.Cu")
		(net "SSD13_CLK0_OE_R_N")
	)
	(segment
		(start 89.300304 -108.921296)
		(end 91.23045 -106.99115)
		(width 0.17145)
		(layer "F.Cu")
		(net "SSD13_CLK0_OE_R_N")
	)
	(segment
		(start 88.2015 -113.665)
		(end 88.2015 -112.3061)
		(width 0.17145)
		(layer "F.Cu")
		(net "SSD13_CLK0_OE_R_N")
	)
	(segment
		(start 52.18303 -148.0312)
		(end 47.9806 -148.0312)
		(width 0.17145)
		(layer "F.Cu")
		(net "SSD13_CLK0_OE_R_N")
	)
	(segment
		(start 89.147904 -108.921296)
		(end 89.300304 -108.921296)
		(width 0.17145)
		(layer "F.Cu")
		(net "SSD13_CLK0_OE_R_N")
	)
	(segment
		(start 88.656922 -109.412278)
		(end 89.147904 -108.921296)
		(width 0.17145)
		(layer "F.Cu")
		(net "SSD13_CLK0_OE_R_N")
	)
	(segment
		(start 74.15657 -128.274318)
		(end 71.939912 -128.274318)
		(width 0.17145)
		(layer "F.Cu")
		(net "SSD13_CLK0_OE_R_N")
	)
	(segment
		(start 75.5142 -128.274318)
		(end 74.15657 -128.274318)
		(width 0.17145)
		(layer "F.Cu")
		(net "SSD13_CLK0_OE_R_N")
	)
	(segment
		(start 88.646 -109.5756)
		(end 88.656922 -109.564678)
		(width 0.17145)
		(layer "F.Cu")
		(net "SSD13_CLK0_OE_R_N")
	)
	(segment
		(start 46.7614 -146.812)
		(end 42.780712 -146.812)
		(width 0.17145)
		(layer "F.Cu")
		(net "SSD13_CLK0_OE_R_N")
	)
	(segment
		(start 2.249932 -199.942196)
		(end 3.257804 -199.942196)
		(width 0.17145)
		(layer "F.Cu")
		(net "SSD13_CLK0_OE_R_N")
	)
	(segment
		(start 71.939912 -128.274318)
		(end 52.18303 -148.0312)
		(width 0.17145)
		(layer "F.Cu")
		(net "SSD13_CLK0_OE_R_N")
	)
	(segment
		(start 88.656922 -109.564678)
		(end 88.656922 -109.412278)
		(width 0.17145)
		(layer "F.Cu")
		(net "SSD13_CLK0_OE_R_N")
	)
	(segment
		(start 7.220204 -199.009)
		(end 12.427204 -193.802)
		(width 0.17145)
		(layer "F.Cu")
		(net "SSD13_CLK0_OE_R_N")
	)
	(segment
		(start 91.23045 -106.99115)
		(end 91.23045 -106.02341)
		(width 0.17145)
		(layer "F.Cu")
		(net "SSD13_CLK0_OE_R_N")
	)
	(segment
		(start 4.08813 -199.009)
		(end 7.220204 -199.009)
		(width 0.17145)
		(layer "F.Cu")
		(net "SSD13_CLK0_OE_R_N")
	)
	(segment
		(start 88.2015 -112.3061)
		(end 88.646 -111.8616)
		(width 0.17145)
		(layer "F.Cu")
		(net "SSD13_CLK0_OE_R_N")
	)
	(segment
		(start 3.707384 -199.389746)
		(end 4.08813 -199.009)
		(width 0.17145)
		(layer "F.Cu")
		(net "SSD13_CLK0_OE_R_N")
	)
	(segment
		(start 25.8445 -158.795212)
		(end 25.8445 -158.902908)
		(width 0.17145)
		(layer "F.Cu")
		(net "SSD13_CLK0_OE_R_N")
	)
	(via
		(at 74.15657 -128.274318)
		(size 0.7112)
		(drill 0.3556)
		(layers "F.Cu" "B.Cu")
		(net "SSD13_CLK0_OE_R_N")
	)
	(via
		(at 75.5142 -128.274318)
		(size 0.508)
		(drill 0.254)
		(layers "F.Cu" "B.Cu")
		(net "SSD13_CLK0_OE_R_N")
	)
	(via
		(at 88.934798 -114.6175)
		(size 0.508)
		(drill 0.254)
		(layers "F.Cu" "B.Cu")
		(net "SSD13_CLK0_OE_R_N")
	)
	(via
		(at 22.5044 -158.3182)
		(size 0.508)
		(drill 0.254)
		(layers "F.Cu" "B.Cu")
		(net "SSD13_CLK0_OE_R_N")
	)
	(via
		(at 12.84224 -165.989)
		(size 0.508)
		(drill 0.254)
		(layers "F.Cu" "B.Cu")
		(net "SSD13_CLK0_OE_R_N")
	)
	(segment
		(start 88.45931 -115.092988)
		(end 85.960712 -115.092988)
		(width 0.1524)
		(layer "In2.Cu")
		(net "SSD13_CLK0_OE_R_N")
	)
	(segment
		(start 85.960712 -115.092988)
		(end 75.5142 -125.5395)
		(width 0.1524)
		(layer "In2.Cu")
		(net "SSD13_CLK0_OE_R_N")
	)
	(segment
		(start 88.934798 -114.6175)
		(end 88.45931 -115.092988)
		(width 0.1524)
		(layer "In2.Cu")
		(net "SSD13_CLK0_OE_R_N")
	)
	(segment
		(start 75.5142 -125.5395)
		(end 75.5142 -128.274318)
		(width 0.1524)
		(layer "In2.Cu")
		(net "SSD13_CLK0_OE_R_N")
	)
	(segment
		(start 18.823178 -165.989)
		(end 12.84224 -165.989)
		(width 0.1524)
		(layer "In5.Cu")
		(net "SSD13_CLK0_OE_R_N")
	)
	(segment
		(start 19.05 -161.7726)
		(end 19.05 -165.762178)
		(width 0.1524)
		(layer "In5.Cu")
		(net "SSD13_CLK0_OE_R_N")
	)
	(segment
		(start 19.05 -165.762178)
		(end 18.823178 -165.989)
		(width 0.1524)
		(layer "In5.Cu")
		(net "SSD13_CLK0_OE_R_N")
	)
	(segment
		(start 22.5044 -158.3182)
		(end 19.05 -161.7726)
		(width 0.1524)
		(layer "In5.Cu")
		(net "SSD13_CLK0_OE_R_N")
	)
	(segment
		(start 88.138 -222.9485)
		(end 88.2015 -222.885)
		(width 0.17145)
		(layer "F.Cu")
		(net "SSD12_CLK0_OE_R_N")
	)
	(segment
		(start 88.2015 -222.885)
		(end 88.2015 -221.0943)
		(width 0.17145)
		(layer "F.Cu")
		(net "SSD12_CLK0_OE_R_N")
	)
	(segment
		(start 88.646 -220.6498)
		(end 88.646 -218.821)
		(width 0.17145)
		(layer "F.Cu")
		(net "SSD12_CLK0_OE_R_N")
	)
	(segment
		(start 88.2015 -221.0943)
		(end 88.646 -220.6498)
		(width 0.17145)
		(layer "F.Cu")
		(net "SSD12_CLK0_OE_R_N")
	)
	(segment
		(start 88.646 -218.821)
		(end 91.23045 -216.23655)
		(width 0.17145)
		(layer "F.Cu")
		(net "SSD12_CLK0_OE_R_N")
	)
	(segment
		(start 26.666698 -261.902702)
		(end 26.9494 -261.62)
		(width 0.17145)
		(layer "F.Cu")
		(net "SSD12_CLK0_OE_R_N")
	)
	(segment
		(start 87.349076 -223.699578)
		(end 87.486998 -223.8375)
		(width 0.17145)
		(layer "F.Cu")
		(net "SSD12_CLK0_OE_R_N")
	)
	(segment
		(start 25.8445 -261.902702)
		(end 26.666698 -261.902702)
		(width 0.17145)
		(layer "F.Cu")
		(net "SSD12_CLK0_OE_R_N")
	)
	(segment
		(start 91.23045 -216.23655)
		(end 91.23045 -215.24341)
		(width 0.17145)
		(layer "F.Cu")
		(net "SSD12_CLK0_OE_R_N")
	)
	(segment
		(start 88.138 -223.8375)
		(end 88.138 -222.9485)
		(width 0.17145)
		(layer "F.Cu")
		(net "SSD12_CLK0_OE_R_N")
	)
	(segment
		(start 87.486998 -223.8375)
		(end 88.138 -223.8375)
		(width 0.17145)
		(layer "F.Cu")
		(net "SSD12_CLK0_OE_R_N")
	)
	(via
		(at 26.9494 -261.62)
		(size 0.508)
		(drill 0.254)
		(layers "F.Cu" "B.Cu")
		(net "SSD12_CLK0_OE_R_N")
	)
	(via
		(at 40.9448 -240.3094)
		(size 0.508)
		(drill 0.254)
		(layers "F.Cu" "B.Cu")
		(net "SSD12_CLK0_OE_R_N")
	)
	(via
		(at 87.349076 -223.699578)
		(size 0.508)
		(drill 0.254)
		(layers "F.Cu" "B.Cu")
		(net "SSD12_CLK0_OE_R_N")
	)
	(via
		(at 36.084764 -243.391436)
		(size 0.7112)
		(drill 0.3556)
		(layers "F.Cu" "B.Cu")
		(net "SSD12_CLK0_OE_R_N")
	)
	(segment
		(start 26.9494 -261.62)
		(end 30.0228 -258.5466)
		(width 0.17145)
		(layer "B.Cu")
		(net "SSD12_CLK0_OE_R_N")
	)
	(segment
		(start 8.649462 -286.904176)
		(end 26.9494 -268.604238)
		(width 0.17145)
		(layer "B.Cu")
		(net "SSD12_CLK0_OE_R_N")
	)
	(segment
		(start 3.88747 -288.34207)
		(end 3.9878 -288.4424)
		(width 0.17145)
		(layer "B.Cu")
		(net "SSD12_CLK0_OE_R_N")
	)
	(segment
		(start 4.700778 -288.4424)
		(end 6.239002 -286.904176)
		(width 0.17145)
		(layer "B.Cu")
		(net "SSD12_CLK0_OE_R_N")
	)
	(segment
		(start 40.7924 -240.4618)
		(end 40.9448 -240.3094)
		(width 0.17145)
		(layer "B.Cu")
		(net "SSD12_CLK0_OE_R_N")
	)
	(segment
		(start 26.9494 -268.604238)
		(end 26.9494 -261.62)
		(width 0.17145)
		(layer "B.Cu")
		(net "SSD12_CLK0_OE_R_N")
	)
	(segment
		(start 30.0228 -249.4534)
		(end 36.084764 -243.391436)
		(width 0.17145)
		(layer "B.Cu")
		(net "SSD12_CLK0_OE_R_N")
	)
	(segment
		(start 6.239002 -286.904176)
		(end 8.649462 -286.904176)
		(width 0.17145)
		(layer "B.Cu")
		(net "SSD12_CLK0_OE_R_N")
	)
	(segment
		(start 36.084764 -243.391436)
		(end 39.0144 -240.4618)
		(width 0.17145)
		(layer "B.Cu")
		(net "SSD12_CLK0_OE_R_N")
	)
	(segment
		(start 1.868932 -288.34207)
		(end 3.88747 -288.34207)
		(width 0.17145)
		(layer "B.Cu")
		(net "SSD12_CLK0_OE_R_N")
	)
	(segment
		(start 30.0228 -258.5466)
		(end 30.0228 -249.4534)
		(width 0.17145)
		(layer "B.Cu")
		(net "SSD12_CLK0_OE_R_N")
	)
	(segment
		(start 39.0144 -240.4618)
		(end 40.7924 -240.4618)
		(width 0.17145)
		(layer "B.Cu")
		(net "SSD12_CLK0_OE_R_N")
	)
	(segment
		(start 3.9878 -288.4424)
		(end 4.700778 -288.4424)
		(width 0.17145)
		(layer "B.Cu")
		(net "SSD12_CLK0_OE_R_N")
	)
	(segment
		(start 87.349076 -223.699578)
		(end 85.748622 -223.699578)
		(width 0.1524)
		(layer "In5.Cu")
		(net "SSD12_CLK0_OE_R_N")
	)
	(segment
		(start 85.748622 -223.699578)
		(end 82.931 -226.5172)
		(width 0.1524)
		(layer "In5.Cu")
		(net "SSD12_CLK0_OE_R_N")
	)
	(segment
		(start 41.6052 -240.9698)
		(end 40.9448 -240.3094)
		(width 0.1524)
		(layer "In5.Cu")
		(net "SSD12_CLK0_OE_R_N")
	)
	(segment
		(start 82.931 -226.5172)
		(end 56.9468 -226.5172)
		(width 0.1524)
		(layer "In5.Cu")
		(net "SSD12_CLK0_OE_R_N")
	)
	(segment
		(start 56.9468 -226.5172)
		(end 42.4942 -240.9698)
		(width 0.1524)
		(layer "In5.Cu")
		(net "SSD12_CLK0_OE_R_N")
	)
	(segment
		(start 42.4942 -240.9698)
		(end 41.6052 -240.9698)
		(width 0.1524)
		(layer "In5.Cu")
		(net "SSD12_CLK0_OE_R_N")
	)
	(segment
		(start 88.226138 -317.221362)
		(end 88.2015 -317.246)
		(width 0.17145)
		(layer "F.Cu")
		(net "SSD11_CLK0_OE_R_N")
	)
	(segment
		(start 23.140416 -358.715056)
		(end 24.984456 -358.715056)
		(width 0.17145)
		(layer "F.Cu")
		(net "SSD11_CLK0_OE_R_N")
	)
	(segment
		(start 15.4432 -335.0006)
		(end 15.4432 -336.2706)
		(width 0.17145)
		(layer "F.Cu")
		(net "SSD11_CLK0_OE_R_N")
	)
	(segment
		(start 26.0604 -364.68685)
		(end 25.8445 -364.90275)
		(width 0.17145)
		(layer "F.Cu")
		(net "SSD11_CLK0_OE_R_N")
	)
	(segment
		(start 88.226138 -315.709046)
		(end 88.226138 -317.221362)
		(width 0.17145)
		(layer "F.Cu")
		(net "SSD11_CLK0_OE_R_N")
	)
	(segment
		(start 15.4432 -336.2706)
		(end 15.19555 -336.51825)
		(width 0.17145)
		(layer "F.Cu")
		(net "SSD11_CLK0_OE_R_N")
	)
	(segment
		(start 24.984456 -358.715056)
		(end 26.0604 -359.791)
		(width 0.17145)
		(layer "F.Cu")
		(net "SSD11_CLK0_OE_R_N")
	)
	(segment
		(start 88.138 -318.1985)
		(end 88.2015 -318.135)
		(width 0.17145)
		(layer "F.Cu")
		(net "SSD11_CLK0_OE_R_N")
	)
	(segment
		(start 15.19555 -336.51825)
		(end 15.19555 -354.604828)
		(width 0.17145)
		(layer "F.Cu")
		(net "SSD11_CLK0_OE_R_N")
	)
	(segment
		(start 15.19555 -354.604828)
		(end 16.246856 -355.656134)
		(width 0.17145)
		(layer "F.Cu")
		(net "SSD11_CLK0_OE_R_N")
	)
	(segment
		(start 87.330788 -318.064388)
		(end 87.4649 -318.1985)
		(width 0.17145)
		(layer "F.Cu")
		(net "SSD11_CLK0_OE_R_N")
	)
	(segment
		(start 88.2015 -318.135)
		(end 88.2015 -317.246)
		(width 0.17145)
		(layer "F.Cu")
		(net "SSD11_CLK0_OE_R_N")
	)
	(segment
		(start 26.0604 -359.791)
		(end 26.0604 -364.68685)
		(width 0.17145)
		(layer "F.Cu")
		(net "SSD11_CLK0_OE_R_N")
	)
	(segment
		(start 20.081494 -355.656134)
		(end 23.140416 -358.715056)
		(width 0.17145)
		(layer "F.Cu")
		(net "SSD11_CLK0_OE_R_N")
	)
	(segment
		(start 91.23045 -309.60441)
		(end 91.23045 -310.47055)
		(width 0.17145)
		(layer "F.Cu")
		(net "SSD11_CLK0_OE_R_N")
	)
	(segment
		(start 88.519 -313.182)
		(end 88.519 -315.416184)
		(width 0.17145)
		(layer "F.Cu")
		(net "SSD11_CLK0_OE_R_N")
	)
	(segment
		(start 87.4649 -318.1985)
		(end 88.138 -318.1985)
		(width 0.17145)
		(layer "F.Cu")
		(net "SSD11_CLK0_OE_R_N")
	)
	(segment
		(start 14.9606 -334.518)
		(end 15.4432 -335.0006)
		(width 0.17145)
		(layer "F.Cu")
		(net "SSD11_CLK0_OE_R_N")
	)
	(segment
		(start 91.23045 -310.47055)
		(end 88.519 -313.182)
		(width 0.17145)
		(layer "F.Cu")
		(net "SSD11_CLK0_OE_R_N")
	)
	(segment
		(start 88.519 -315.416184)
		(end 88.226138 -315.709046)
		(width 0.17145)
		(layer "F.Cu")
		(net "SSD11_CLK0_OE_R_N")
	)
	(segment
		(start 16.246856 -355.656134)
		(end 20.081494 -355.656134)
		(width 0.17145)
		(layer "F.Cu")
		(net "SSD11_CLK0_OE_R_N")
	)
	(via
		(at 87.330788 -318.064388)
		(size 0.508)
		(drill 0.254)
		(layers "F.Cu" "B.Cu")
		(net "SSD11_CLK0_OE_R_N")
	)
	(via
		(at 14.9606 -334.518)
		(size 0.508)
		(drill 0.254)
		(layers "F.Cu" "B.Cu")
		(net "SSD11_CLK0_OE_R_N")
	)
	(via
		(at 12.7254 -334.6196)
		(size 0.7112)
		(drill 0.3556)
		(layers "F.Cu" "B.Cu")
		(net "SSD11_CLK0_OE_R_N")
	)
	(segment
		(start 3.7338 -334.1116)
		(end 4.384548 -334.1116)
		(width 0.17145)
		(layer "B.Cu")
		(net "SSD11_CLK0_OE_R_N")
	)
	(segment
		(start 4.384548 -334.1116)
		(end 5.787898 -332.70825)
		(width 0.17145)
		(layer "B.Cu")
		(net "SSD11_CLK0_OE_R_N")
	)
	(segment
		(start 14.859 -334.6196)
		(end 14.9606 -334.518)
		(width 0.17145)
		(layer "B.Cu")
		(net "SSD11_CLK0_OE_R_N")
	)
	(segment
		(start 6.629146 -332.70825)
		(end 8.540496 -334.6196)
		(width 0.17145)
		(layer "B.Cu")
		(net "SSD11_CLK0_OE_R_N")
	)
	(segment
		(start 5.787898 -332.70825)
		(end 6.629146 -332.70825)
		(width 0.17145)
		(layer "B.Cu")
		(net "SSD11_CLK0_OE_R_N")
	)
	(segment
		(start 3.564382 -333.942182)
		(end 3.7338 -334.1116)
		(width 0.17145)
		(layer "B.Cu")
		(net "SSD11_CLK0_OE_R_N")
	)
	(segment
		(start 1.868932 -333.942182)
		(end 3.564382 -333.942182)
		(width 0.17145)
		(layer "B.Cu")
		(net "SSD11_CLK0_OE_R_N")
	)
	(segment
		(start 12.7254 -334.6196)
		(end 14.859 -334.6196)
		(width 0.17145)
		(layer "B.Cu")
		(net "SSD11_CLK0_OE_R_N")
	)
	(segment
		(start 8.540496 -334.6196)
		(end 12.7254 -334.6196)
		(width 0.17145)
		(layer "B.Cu")
		(net "SSD11_CLK0_OE_R_N")
	)
	(segment
		(start 86.2076 -316.9412)
		(end 87.330788 -318.064388)
		(width 0.1524)
		(layer "In5.Cu")
		(net "SSD11_CLK0_OE_R_N")
	)
	(segment
		(start 14.9606 -334.518)
		(end 14.9606 -331.089)
		(width 0.1524)
		(layer "In5.Cu")
		(net "SSD11_CLK0_OE_R_N")
	)
	(segment
		(start 54.0766 -320.6242)
		(end 57.7596 -316.9412)
		(width 0.1524)
		(layer "In5.Cu")
		(net "SSD11_CLK0_OE_R_N")
	)
	(segment
		(start 20.4978 -323.40296)
		(end 23.27656 -320.6242)
		(width 0.1524)
		(layer "In5.Cu")
		(net "SSD11_CLK0_OE_R_N")
	)
	(segment
		(start 20.4978 -325.5518)
		(end 20.4978 -323.40296)
		(width 0.1524)
		(layer "In5.Cu")
		(net "SSD11_CLK0_OE_R_N")
	)
	(segment
		(start 23.27656 -320.6242)
		(end 54.0766 -320.6242)
		(width 0.1524)
		(layer "In5.Cu")
		(net "SSD11_CLK0_OE_R_N")
	)
	(segment
		(start 14.9606 -331.089)
		(end 20.4978 -325.5518)
		(width 0.1524)
		(layer "In5.Cu")
		(net "SSD11_CLK0_OE_R_N")
	)
	(segment
		(start 57.7596 -316.9412)
		(end 86.2076 -316.9412)
		(width 0.1524)
		(layer "In5.Cu")
		(net "SSD11_CLK0_OE_R_N")
	)
	(segment
		(start 31.0769 -449.327778)
		(end 31.0769 -453.553576)
		(width 0.17145)
		(layer "F.Cu")
		(net "SSD10_CLK0_OE_R_N")
	)
	(segment
		(start 36.449 -443.955678)
		(end 31.0769 -449.327778)
		(width 0.17145)
		(layer "F.Cu")
		(net "SSD10_CLK0_OE_R_N")
	)
	(segment
		(start 89.143078 -423.661078)
		(end 89.143078 -421.650922)
		(width 0.17145)
		(layer "F.Cu")
		(net "SSD10_CLK0_OE_R_N")
	)
	(segment
		(start 89.143078 -421.650922)
		(end 89.5985 -421.1955)
		(width 0.17145)
		(layer "F.Cu")
		(net "SSD10_CLK0_OE_R_N")
	)
	(segment
		(start 31.0769 -453.553576)
		(end 28.484576 -456.1459)
		(width 0.17145)
		(layer "F.Cu")
		(net "SSD10_CLK0_OE_R_N")
	)
	(segment
		(start 25.0317 -456.1459)
		(end 23.78075 -457.39685)
		(width 0.17145)
		(layer "F.Cu")
		(net "SSD10_CLK0_OE_R_N")
	)
	(segment
		(start 17.58315 -472.3511)
		(end 17.58315 -471.58275)
		(width 0.17145)
		(layer "F.Cu")
		(net "SSD10_CLK0_OE_R_N")
	)
	(segment
		(start 90.330782 -418.7825)
		(end 89.662 -418.7825)
		(width 0.17145)
		(layer "F.Cu")
		(net "SSD10_CLK0_OE_R_N")
	)
	(segment
		(start 23.78075 -457.39685)
		(end 23.78075 -457.7588)
		(width 0.17145)
		(layer "F.Cu")
		(net "SSD10_CLK0_OE_R_N")
	)
	(segment
		(start 91.72956 -427.37659)
		(end 91.72956 -426.24756)
		(width 0.17145)
		(layer "F.Cu")
		(net "SSD10_CLK0_OE_R_N")
	)
	(segment
		(start 36.449 -438.7342)
		(end 36.449 -443.955678)
		(width 0.17145)
		(layer "F.Cu")
		(net "SSD10_CLK0_OE_R_N")
	)
	(segment
		(start 35.6362 -437.9214)
		(end 36.449 -438.7342)
		(width 0.17145)
		(layer "F.Cu")
		(net "SSD10_CLK0_OE_R_N")
	)
	(segment
		(start 28.484576 -456.1459)
		(end 25.0317 -456.1459)
		(width 0.17145)
		(layer "F.Cu")
		(net "SSD10_CLK0_OE_R_N")
	)
	(segment
		(start 89.5985 -418.846)
		(end 89.5985 -419.735)
		(width 0.17145)
		(layer "F.Cu")
		(net "SSD10_CLK0_OE_R_N")
	)
	(segment
		(start 91.72956 -426.24756)
		(end 89.143078 -423.661078)
		(width 0.17145)
		(layer "F.Cu")
		(net "SSD10_CLK0_OE_R_N")
	)
	(segment
		(start 89.662 -418.7825)
		(end 89.5985 -418.846)
		(width 0.17145)
		(layer "F.Cu")
		(net "SSD10_CLK0_OE_R_N")
	)
	(segment
		(start 90.468196 -418.919914)
		(end 90.330782 -418.7825)
		(width 0.17145)
		(layer "F.Cu")
		(net "SSD10_CLK0_OE_R_N")
	)
	(segment
		(start 89.5985 -421.1955)
		(end 89.5985 -419.735)
		(width 0.17145)
		(layer "F.Cu")
		(net "SSD10_CLK0_OE_R_N")
	)
	(segment
		(start 17.58315 -471.58275)
		(end 17.2212 -471.2208)
		(width 0.17145)
		(layer "F.Cu")
		(net "SSD10_CLK0_OE_R_N")
	)
	(via
		(at 90.468196 -418.919914)
		(size 0.508)
		(drill 0.254)
		(layers "F.Cu" "B.Cu")
		(net "SSD10_CLK0_OE_R_N")
	)
	(via
		(at 23.78075 -457.7588)
		(size 0.508)
		(drill 0.254)
		(layers "F.Cu" "B.Cu")
		(net "SSD10_CLK0_OE_R_N")
	)
	(via
		(at 12.58697 -402.26996)
		(size 0.7112)
		(drill 0.3556)
		(layers "F.Cu" "B.Cu")
		(net "SSD10_CLK0_OE_R_N")
	)
	(via
		(at 17.2212 -471.2208)
		(size 0.508)
		(drill 0.254)
		(layers "F.Cu" "B.Cu")
		(net "SSD10_CLK0_OE_R_N")
	)
	(via
		(at 35.6362 -437.9214)
		(size 0.508)
		(drill 0.254)
		(layers "F.Cu" "B.Cu")
		(net "SSD10_CLK0_OE_R_N")
	)
	(segment
		(start 18.407888 -436.822088)
		(end 21.189696 -436.822088)
		(width 0.17145)
		(layer "B.Cu")
		(net "SSD10_CLK0_OE_R_N")
	)
	(segment
		(start 17.789652 -470.652348)
		(end 21.38807 -470.652348)
		(width 0.17145)
		(layer "B.Cu")
		(net "SSD10_CLK0_OE_R_N")
	)
	(segment
		(start 12.58697 -402.26996)
		(end 14.696948 -404.379938)
		(width 0.17145)
		(layer "B.Cu")
		(net "SSD10_CLK0_OE_R_N")
	)
	(segment
		(start 4.064 -402.59)
		(end 4.445 -402.59)
		(width 0.17145)
		(layer "B.Cu")
		(net "SSD10_CLK0_OE_R_N")
	)
	(segment
		(start 1.868932 -402.341842)
		(end 3.815842 -402.341842)
		(width 0.17145)
		(layer "B.Cu")
		(net "SSD10_CLK0_OE_R_N")
	)
	(segment
		(start 29.57195 -437.9214)
		(end 35.6362 -437.9214)
		(width 0.17145)
		(layer "B.Cu")
		(net "SSD10_CLK0_OE_R_N")
	)
	(segment
		(start 24.333708 -467.70671)
		(end 24.333708 -465.84997)
		(width 0.17145)
		(layer "B.Cu")
		(net "SSD10_CLK0_OE_R_N")
	)
	(segment
		(start 21.189696 -436.822088)
		(end 21.190458 -436.82285)
		(width 0.17145)
		(layer "B.Cu")
		(net "SSD10_CLK0_OE_R_N")
	)
	(segment
		(start 11.830812 -401.513802)
		(end 12.58697 -402.26996)
		(width 0.17145)
		(layer "B.Cu")
		(net "SSD10_CLK0_OE_R_N")
	)
	(segment
		(start 22.022816 -437.642)
		(end 25.63241 -437.642)
		(width 0.17145)
		(layer "B.Cu")
		(net "SSD10_CLK0_OE_R_N")
	)
	(segment
		(start 4.445 -402.59)
		(end 5.89915 -401.13585)
		(width 0.17145)
		(layer "B.Cu")
		(net "SSD10_CLK0_OE_R_N")
	)
	(segment
		(start 26.384758 -436.889652)
		(end 28.540202 -436.889652)
		(width 0.17145)
		(layer "B.Cu")
		(net "SSD10_CLK0_OE_R_N")
	)
	(segment
		(start 6.943344 -401.513802)
		(end 11.830812 -401.513802)
		(width 0.17145)
		(layer "B.Cu")
		(net "SSD10_CLK0_OE_R_N")
	)
	(segment
		(start 28.540202 -436.889652)
		(end 29.57195 -437.9214)
		(width 0.17145)
		(layer "B.Cu")
		(net "SSD10_CLK0_OE_R_N")
	)
	(segment
		(start 24.333708 -465.84997)
		(end 23.78075 -465.297012)
		(width 0.17145)
		(layer "B.Cu")
		(net "SSD10_CLK0_OE_R_N")
	)
	(segment
		(start 17.2212 -471.2208)
		(end 17.789652 -470.652348)
		(width 0.17145)
		(layer "B.Cu")
		(net "SSD10_CLK0_OE_R_N")
	)
	(segment
		(start 25.63241 -437.642)
		(end 26.384758 -436.889652)
		(width 0.17145)
		(layer "B.Cu")
		(net "SSD10_CLK0_OE_R_N")
	)
	(segment
		(start 21.190458 -436.82285)
		(end 21.203666 -436.82285)
		(width 0.17145)
		(layer "B.Cu")
		(net "SSD10_CLK0_OE_R_N")
	)
	(segment
		(start 14.696948 -433.111148)
		(end 18.407888 -436.822088)
		(width 0.17145)
		(layer "B.Cu")
		(net "SSD10_CLK0_OE_R_N")
	)
	(segment
		(start 3.815842 -402.341842)
		(end 4.064 -402.59)
		(width 0.17145)
		(layer "B.Cu")
		(net "SSD10_CLK0_OE_R_N")
	)
	(segment
		(start 21.38807 -470.652348)
		(end 24.333708 -467.70671)
		(width 0.17145)
		(layer "B.Cu")
		(net "SSD10_CLK0_OE_R_N")
	)
	(segment
		(start 21.203666 -436.82285)
		(end 22.022816 -437.642)
		(width 0.17145)
		(layer "B.Cu")
		(net "SSD10_CLK0_OE_R_N")
	)
	(segment
		(start 6.565392 -401.13585)
		(end 6.943344 -401.513802)
		(width 0.17145)
		(layer "B.Cu")
		(net "SSD10_CLK0_OE_R_N")
	)
	(segment
		(start 14.696948 -404.379938)
		(end 14.696948 -433.111148)
		(width 0.17145)
		(layer "B.Cu")
		(net "SSD10_CLK0_OE_R_N")
	)
	(segment
		(start 23.78075 -465.297012)
		(end 23.78075 -457.7588)
		(width 0.17145)
		(layer "B.Cu")
		(net "SSD10_CLK0_OE_R_N")
	)
	(segment
		(start 5.89915 -401.13585)
		(end 6.565392 -401.13585)
		(width 0.17145)
		(layer "B.Cu")
		(net "SSD10_CLK0_OE_R_N")
	)
	(segment
		(start 77.57922 -423.799)
		(end 67.97802 -433.4002)
		(width 0.1524)
		(layer "In5.Cu")
		(net "SSD10_CLK0_OE_R_N")
	)
	(segment
		(start 82.81162 -421.3606)
		(end 80.37322 -423.799)
		(width 0.1524)
		(layer "In5.Cu")
		(net "SSD10_CLK0_OE_R_N")
	)
	(segment
		(start 60.30722 -435.3052)
		(end 37.0332 -435.3052)
		(width 0.1524)
		(layer "In5.Cu")
		(net "SSD10_CLK0_OE_R_N")
	)
	(segment
		(start 62.21222 -433.4002)
		(end 60.30722 -435.3052)
		(width 0.1524)
		(layer "In5.Cu")
		(net "SSD10_CLK0_OE_R_N")
	)
	(segment
		(start 35.6362 -436.7022)
		(end 35.6362 -437.9214)
		(width 0.1524)
		(layer "In5.Cu")
		(net "SSD10_CLK0_OE_R_N")
	)
	(segment
		(start 80.37322 -423.799)
		(end 77.57922 -423.799)
		(width 0.1524)
		(layer "In5.Cu")
		(net "SSD10_CLK0_OE_R_N")
	)
	(segment
		(start 90.468196 -418.919914)
		(end 88.02751 -421.3606)
		(width 0.1524)
		(layer "In5.Cu")
		(net "SSD10_CLK0_OE_R_N")
	)
	(segment
		(start 37.0332 -435.3052)
		(end 35.6362 -436.7022)
		(width 0.1524)
		(layer "In5.Cu")
		(net "SSD10_CLK0_OE_R_N")
	)
	(segment
		(start 67.97802 -433.4002)
		(end 62.21222 -433.4002)
		(width 0.1524)
		(layer "In5.Cu")
		(net "SSD10_CLK0_OE_R_N")
	)
	(segment
		(start 88.02751 -421.3606)
		(end 82.81162 -421.3606)
		(width 0.1524)
		(layer "In5.Cu")
		(net "SSD10_CLK0_OE_R_N")
	)
	(segment
		(start 106.1085 -309.88)
		(end 106.045 -309.8165)
		(width 0.17145)
		(layer "F.Cu")
		(net "SSD1_CLK0_OE_R_N")
	)
	(segment
		(start 106.873802 -310.68899)
		(end 106.9975 -310.565292)
		(width 0.17145)
		(layer "F.Cu")
		(net "SSD1_CLK0_OE_R_N")
	)
	(segment
		(start 10.1092 -395.6558)
		(end 5.715 -400.05)
		(width 0.17145)
		(layer "F.Cu")
		(net "SSD1_CLK0_OE_R_N")
	)
	(segment
		(start 10.91184 -385.421632)
		(end 10.1092 -386.224272)
		(width 0.17145)
		(layer "F.Cu")
		(net "SSD1_CLK0_OE_R_N")
	)
	(segment
		(start 3.724148 -399.583148)
		(end 3.28295 -399.14195)
		(width 0.17145)
		(layer "F.Cu")
		(net "SSD1_CLK0_OE_R_N")
	)
	(segment
		(start 219.74175 -343.087452)
		(end 219.74175 -342.007952)
		(width 0.17145)
		(layer "F.Cu")
		(net "SSD1_CLK0_OE_R_N")
	)
	(segment
		(start 103.80345 -309.03545)
		(end 101.00183 -309.03545)
		(width 0.17145)
		(layer "F.Cu")
		(net "SSD1_CLK0_OE_R_N")
	)
	(segment
		(start 3.28295 -399.14195)
		(end 2.249932 -399.14195)
		(width 0.17145)
		(layer "F.Cu")
		(net "SSD1_CLK0_OE_R_N")
	)
	(segment
		(start 99.39782 -307.43144)
		(end 98.40341 -307.43144)
		(width 0.17145)
		(layer "F.Cu")
		(net "SSD1_CLK0_OE_R_N")
	)
	(segment
		(start 4.038854 -400.05)
		(end 3.724148 -399.735294)
		(width 0.17145)
		(layer "F.Cu")
		(net "SSD1_CLK0_OE_R_N")
	)
	(segment
		(start 5.715 -400.05)
		(end 4.038854 -400.05)
		(width 0.17145)
		(layer "F.Cu")
		(net "SSD1_CLK0_OE_R_N")
	)
	(segment
		(start 10.1092 -393.0396)
		(end 10.1092 -395.6558)
		(width 0.17145)
		(layer "F.Cu")
		(net "SSD1_CLK0_OE_R_N")
	)
	(segment
		(start 104.5845 -309.8165)
		(end 103.80345 -309.03545)
		(width 0.17145)
		(layer "F.Cu")
		(net "SSD1_CLK0_OE_R_N")
	)
	(segment
		(start 101.00183 -309.03545)
		(end 99.39782 -307.43144)
		(width 0.17145)
		(layer "F.Cu")
		(net "SSD1_CLK0_OE_R_N")
	)
	(segment
		(start 106.9975 -309.88)
		(end 106.1085 -309.88)
		(width 0.17145)
		(layer "F.Cu")
		(net "SSD1_CLK0_OE_R_N")
	)
	(segment
		(start 106.9975 -310.565292)
		(end 106.9975 -309.88)
		(width 0.17145)
		(layer "F.Cu")
		(net "SSD1_CLK0_OE_R_N")
	)
	(segment
		(start 3.724148 -399.735294)
		(end 3.724148 -399.583148)
		(width 0.17145)
		(layer "F.Cu")
		(net "SSD1_CLK0_OE_R_N")
	)
	(segment
		(start 106.045 -309.8165)
		(end 104.5845 -309.8165)
		(width 0.17145)
		(layer "F.Cu")
		(net "SSD1_CLK0_OE_R_N")
	)
	(segment
		(start 10.1092 -386.224272)
		(end 10.1092 -393.0396)
		(width 0.17145)
		(layer "F.Cu")
		(net "SSD1_CLK0_OE_R_N")
	)
	(via
		(at 10.1092 -393.0396)
		(size 0.7112)
		(drill 0.3556)
		(layers "F.Cu" "B.Cu")
		(net "SSD1_CLK0_OE_R_N")
	)
	(via
		(at 106.873802 -310.68899)
		(size 0.508)
		(drill 0.254)
		(layers "F.Cu" "B.Cu")
		(net "SSD1_CLK0_OE_R_N")
	)
	(via
		(at 219.74175 -342.007952)
		(size 0.508)
		(drill 0.254)
		(layers "F.Cu" "B.Cu")
		(net "SSD1_CLK0_OE_R_N")
	)
	(via
		(at 10.91184 -385.421632)
		(size 0.508)
		(drill 0.254)
		(layers "F.Cu" "B.Cu")
		(net "SSD1_CLK0_OE_R_N")
	)
	(segment
		(start 106.873802 -310.68899)
		(end 105.2322 -312.330592)
		(width 0.1524)
		(layer "In5.Cu")
		(net "SSD1_CLK0_OE_R_N")
	)
	(segment
		(start 107.746292 -309.8165)
		(end 106.873802 -310.68899)
		(width 0.1524)
		(layer "In5.Cu")
		(net "SSD1_CLK0_OE_R_N")
	)
	(segment
		(start 32.12592 -387.35)
		(end 22.8346 -387.35)
		(width 0.1524)
		(layer "In5.Cu")
		(net "SSD1_CLK0_OE_R_N")
	)
	(segment
		(start 75.7682 -390.652)
		(end 35.42792 -390.652)
		(width 0.1524)
		(layer "In5.Cu")
		(net "SSD1_CLK0_OE_R_N")
	)
	(segment
		(start 121.1834 -338.118704)
		(end 121.1834 -317.246)
		(width 0.1524)
		(layer "In5.Cu")
		(net "SSD1_CLK0_OE_R_N")
	)
	(segment
		(start 105.2322 -312.330592)
		(end 105.2322 -361.188)
		(width 0.1524)
		(layer "In5.Cu")
		(net "SSD1_CLK0_OE_R_N")
	)
	(segment
		(start 113.7539 -309.8165)
		(end 107.746292 -309.8165)
		(width 0.1524)
		(layer "In5.Cu")
		(net "SSD1_CLK0_OE_R_N")
	)
	(segment
		(start 20.906232 -385.421632)
		(end 10.91184 -385.421632)
		(width 0.1524)
		(layer "In5.Cu")
		(net "SSD1_CLK0_OE_R_N")
	)
	(segment
		(start 35.42792 -390.652)
		(end 32.12592 -387.35)
		(width 0.1524)
		(layer "In5.Cu")
		(net "SSD1_CLK0_OE_R_N")
	)
	(segment
		(start 219.74175 -342.007952)
		(end 125.072648 -342.007952)
		(width 0.1524)
		(layer "In5.Cu")
		(net "SSD1_CLK0_OE_R_N")
	)
	(segment
		(start 105.2322 -361.188)
		(end 75.7682 -390.652)
		(width 0.1524)
		(layer "In5.Cu")
		(net "SSD1_CLK0_OE_R_N")
	)
	(segment
		(start 22.8346 -387.35)
		(end 20.906232 -385.421632)
		(width 0.1524)
		(layer "In5.Cu")
		(net "SSD1_CLK0_OE_R_N")
	)
	(segment
		(start 125.072648 -342.007952)
		(end 121.1834 -338.118704)
		(width 0.1524)
		(layer "In5.Cu")
		(net "SSD1_CLK0_OE_R_N")
	)
	(segment
		(start 121.1834 -317.246)
		(end 113.7539 -309.8165)
		(width 0.1524)
		(layer "In5.Cu")
		(net "SSD1_CLK0_OE_R_N")
	)
	(segment
		(start 3.707384 -434.683916)
		(end 3.707384 -434.67147)
		(width 0.17145)
		(layer "F.Cu")
		(net "SSD0_CLK0_OE_R_N")
	)
	(segment
		(start 104.8004 -436.4355)
		(end 104.01935 -435.65445)
		(width 0.17145)
		(layer "F.Cu")
		(net "SSD0_CLK0_OE_R_N")
	)
	(segment
		(start 106.045 -436.4355)
		(end 104.8004 -436.4355)
		(width 0.17145)
		(layer "F.Cu")
		(net "SSD0_CLK0_OE_R_N")
	)
	(segment
		(start 106.9975 -436.499)
		(end 106.934 -436.4355)
		(width 0.17145)
		(layer "F.Cu")
		(net "SSD0_CLK0_OE_R_N")
	)
	(segment
		(start 4.165854 -434.213)
		(end 5.7658 -434.213)
		(width 0.17145)
		(layer "F.Cu")
		(net "SSD0_CLK0_OE_R_N")
	)
	(segment
		(start 106.865928 -437.326278)
		(end 106.9975 -437.194706)
		(width 0.17145)
		(layer "F.Cu")
		(net "SSD0_CLK0_OE_R_N")
	)
	(segment
		(start 7.1628 -435.61)
		(end 9.652 -435.61)
		(width 0.17145)
		(layer "F.Cu")
		(net "SSD0_CLK0_OE_R_N")
	)
	(segment
		(start 2.249932 -435.141878)
		(end 3.249422 -435.141878)
		(width 0.17145)
		(layer "F.Cu")
		(net "SSD0_CLK0_OE_R_N")
	)
	(segment
		(start 219.74175 -446.0875)
		(end 219.74175 -444.9572)
		(width 0.17145)
		(layer "F.Cu")
		(net "SSD0_CLK0_OE_R_N")
	)
	(segment
		(start 5.7658 -434.213)
		(end 7.1628 -435.61)
		(width 0.17145)
		(layer "F.Cu")
		(net "SSD0_CLK0_OE_R_N")
	)
	(segment
		(start 3.707384 -434.67147)
		(end 4.165854 -434.213)
		(width 0.17145)
		(layer "F.Cu")
		(net "SSD0_CLK0_OE_R_N")
	)
	(segment
		(start 3.249422 -435.141878)
		(end 3.707384 -434.683916)
		(width 0.17145)
		(layer "F.Cu")
		(net "SSD0_CLK0_OE_R_N")
	)
	(segment
		(start 104.01935 -435.65445)
		(end 101.39045 -435.65445)
		(width 0.17145)
		(layer "F.Cu")
		(net "SSD0_CLK0_OE_R_N")
	)
	(segment
		(start 101.39045 -435.65445)
		(end 99.78644 -434.05044)
		(width 0.17145)
		(layer "F.Cu")
		(net "SSD0_CLK0_OE_R_N")
	)
	(segment
		(start 106.934 -436.4355)
		(end 106.045 -436.4355)
		(width 0.17145)
		(layer "F.Cu")
		(net "SSD0_CLK0_OE_R_N")
	)
	(segment
		(start 106.9975 -437.194706)
		(end 106.9975 -436.499)
		(width 0.17145)
		(layer "F.Cu")
		(net "SSD0_CLK0_OE_R_N")
	)
	(segment
		(start 99.78644 -434.05044)
		(end 98.40341 -434.05044)
		(width 0.17145)
		(layer "F.Cu")
		(net "SSD0_CLK0_OE_R_N")
	)
	(via
		(at 106.865928 -437.326278)
		(size 0.508)
		(drill 0.254)
		(layers "F.Cu" "B.Cu")
		(net "SSD0_CLK0_OE_R_N")
	)
	(via
		(at 11.4681 -437.0451)
		(size 0.7112)
		(drill 0.3556)
		(layers "F.Cu" "B.Cu")
		(net "SSD0_CLK0_OE_R_N")
	)
	(via
		(at 219.74175 -444.9572)
		(size 0.508)
		(drill 0.254)
		(layers "F.Cu" "B.Cu")
		(net "SSD0_CLK0_OE_R_N")
	)
	(via
		(at 36.6776 -436.9816)
		(size 0.508)
		(drill 0.254)
		(layers "F.Cu" "B.Cu")
		(net "SSD0_CLK0_OE_R_N")
	)
	(via
		(at 9.652 -435.61)
		(size 0.508)
		(drill 0.254)
		(layers "F.Cu" "B.Cu")
		(net "SSD0_CLK0_OE_R_N")
	)
	(segment
		(start 36.703 -437.007)
		(end 36.6776 -436.9816)
		(width 0.17145)
		(layer "B.Cu")
		(net "SSD0_CLK0_OE_R_N")
	)
	(segment
		(start 25.519634 -441.121546)
		(end 35.433254 -441.121546)
		(width 0.17145)
		(layer "B.Cu")
		(net "SSD0_CLK0_OE_R_N")
	)
	(segment
		(start 36.703 -439.8518)
		(end 36.703 -437.007)
		(width 0.17145)
		(layer "B.Cu")
		(net "SSD0_CLK0_OE_R_N")
	)
	(segment
		(start 35.433254 -441.121546)
		(end 36.703 -439.8518)
		(width 0.17145)
		(layer "B.Cu")
		(net "SSD0_CLK0_OE_R_N")
	)
	(segment
		(start 13.547598 -439.124598)
		(end 20.380198 -439.124598)
		(width 0.17145)
		(layer "B.Cu")
		(net "SSD0_CLK0_OE_R_N")
	)
	(segment
		(start 20.380198 -439.124598)
		(end 21.718016 -440.462416)
		(width 0.17145)
		(layer "B.Cu")
		(net "SSD0_CLK0_OE_R_N")
	)
	(segment
		(start 9.652 -435.61)
		(end 10.033 -435.61)
		(width 0.17145)
		(layer "B.Cu")
		(net "SSD0_CLK0_OE_R_N")
	)
	(segment
		(start 11.4681 -437.0451)
		(end 13.547598 -439.124598)
		(width 0.17145)
		(layer "B.Cu")
		(net "SSD0_CLK0_OE_R_N")
	)
	(segment
		(start 10.033 -435.61)
		(end 11.4681 -437.0451)
		(width 0.17145)
		(layer "B.Cu")
		(net "SSD0_CLK0_OE_R_N")
	)
	(segment
		(start 21.718016 -440.462416)
		(end 24.860504 -440.462416)
		(width 0.17145)
		(layer "B.Cu")
		(net "SSD0_CLK0_OE_R_N")
	)
	(segment
		(start 24.860504 -440.462416)
		(end 25.519634 -441.121546)
		(width 0.17145)
		(layer "B.Cu")
		(net "SSD0_CLK0_OE_R_N")
	)
	(segment
		(start 120.026938 -428.1678)
		(end 172.8724 -428.1678)
		(width 0.1524)
		(layer "In5.Cu")
		(net "SSD0_CLK0_OE_R_N")
	)
	(segment
		(start 111.39932 -436.795418)
		(end 120.026938 -428.1678)
		(width 0.1524)
		(layer "In5.Cu")
		(net "SSD0_CLK0_OE_R_N")
	)
	(segment
		(start 217.35415 -442.5696)
		(end 219.74175 -444.9572)
		(width 0.1524)
		(layer "In5.Cu")
		(net "SSD0_CLK0_OE_R_N")
	)
	(segment
		(start 107.887516 -436.795418)
		(end 111.39932 -436.795418)
		(width 0.1524)
		(layer "In5.Cu")
		(net "SSD0_CLK0_OE_R_N")
	)
	(segment
		(start 62.4332 -433.9336)
		(end 60.5282 -435.8386)
		(width 0.1524)
		(layer "In5.Cu")
		(net "SSD0_CLK0_OE_R_N")
	)
	(segment
		(start 60.5282 -435.8386)
		(end 37.8206 -435.8386)
		(width 0.1524)
		(layer "In5.Cu")
		(net "SSD0_CLK0_OE_R_N")
	)
	(segment
		(start 80.5942 -424.3324)
		(end 77.8002 -424.3324)
		(width 0.1524)
		(layer "In5.Cu")
		(net "SSD0_CLK0_OE_R_N")
	)
	(segment
		(start 107.356656 -437.326278)
		(end 107.887516 -436.795418)
		(width 0.1524)
		(layer "In5.Cu")
		(net "SSD0_CLK0_OE_R_N")
	)
	(segment
		(start 106.865928 -437.326278)
		(end 107.356656 -437.326278)
		(width 0.1524)
		(layer "In5.Cu")
		(net "SSD0_CLK0_OE_R_N")
	)
	(segment
		(start 95.5802 -421.894)
		(end 83.0326 -421.894)
		(width 0.1524)
		(layer "In5.Cu")
		(net "SSD0_CLK0_OE_R_N")
	)
	(segment
		(start 106.865928 -437.326278)
		(end 104.8004 -435.26075)
		(width 0.1524)
		(layer "In5.Cu")
		(net "SSD0_CLK0_OE_R_N")
	)
	(segment
		(start 172.8724 -428.1678)
		(end 187.2742 -442.5696)
		(width 0.1524)
		(layer "In5.Cu")
		(net "SSD0_CLK0_OE_R_N")
	)
	(segment
		(start 68.199 -433.9336)
		(end 62.4332 -433.9336)
		(width 0.1524)
		(layer "In5.Cu")
		(net "SSD0_CLK0_OE_R_N")
	)
	(segment
		(start 104.8004 -435.26075)
		(end 104.8004 -427.8122)
		(width 0.1524)
		(layer "In5.Cu")
		(net "SSD0_CLK0_OE_R_N")
	)
	(segment
		(start 83.0326 -421.894)
		(end 80.5942 -424.3324)
		(width 0.1524)
		(layer "In5.Cu")
		(net "SSD0_CLK0_OE_R_N")
	)
	(segment
		(start 104.8004 -427.8122)
		(end 99.7204 -422.7322)
		(width 0.1524)
		(layer "In5.Cu")
		(net "SSD0_CLK0_OE_R_N")
	)
	(segment
		(start 187.2742 -442.5696)
		(end 217.35415 -442.5696)
		(width 0.1524)
		(layer "In5.Cu")
		(net "SSD0_CLK0_OE_R_N")
	)
	(segment
		(start 99.7204 -422.7322)
		(end 96.4184 -422.7322)
		(width 0.1524)
		(layer "In5.Cu")
		(net "SSD0_CLK0_OE_R_N")
	)
	(segment
		(start 96.4184 -422.7322)
		(end 95.5802 -421.894)
		(width 0.1524)
		(layer "In5.Cu")
		(net "SSD0_CLK0_OE_R_N")
	)
	(segment
		(start 77.8002 -424.3324)
		(end 68.199 -433.9336)
		(width 0.1524)
		(layer "In5.Cu")
		(net "SSD0_CLK0_OE_R_N")
	)
	(segment
		(start 37.8206 -435.8386)
		(end 36.6776 -436.9816)
		(width 0.1524)
		(layer "In5.Cu")
		(net "SSD0_CLK0_OE_R_N")
	)
	(segment
		(start 71.1835 -356.489)
		(end 71.1835 -357.505)
		(width 0.17145)
		(layer "F.Cu")
		(net "I2C_SW_EU17_ADDRESS_A2")
	)
	(segment
		(start 71.1835 -357.505)
		(end 71.959216 -358.280716)
		(width 0.17145)
		(layer "F.Cu")
		(net "I2C_SW_EU17_ADDRESS_A2")
	)
	(segment
		(start 74.1426 -359.811066)
		(end 73.527666 -359.811066)
		(width 0.17145)
		(layer "F.Cu")
		(net "I2C_SW_EU17_ADDRESS_A2")
	)
	(segment
		(start 73.527666 -359.811066)
		(end 72.4154 -358.6988)
		(width 0.17145)
		(layer "F.Cu")
		(net "I2C_SW_EU17_ADDRESS_A2")
	)
	(segment
		(start 71.959216 -358.280716)
		(end 71.997316 -358.280716)
		(width 0.17145)
		(layer "F.Cu")
		(net "I2C_SW_EU17_ADDRESS_A2")
	)
	(segment
		(start 71.997316 -358.280716)
		(end 72.4154 -358.6988)
		(width 0.17145)
		(layer "F.Cu")
		(net "I2C_SW_EU17_ADDRESS_A2")
	)
	(via
		(at 72.4154 -358.6988)
		(size 0.7112)
		(drill 0.3556)
		(layers "F.Cu" "B.Cu")
		(net "I2C_SW_EU17_ADDRESS_A2")
	)
	(segment
		(start 79.121 -354.5205)
		(end 80.137 -354.5205)
		(width 0.17145)
		(layer "F.Cu")
		(net "I2C_SW_EU17_ADDRESS_A1")
	)
	(segment
		(start 76.950062 -358.405938)
		(end 76.950062 -359.0798)
		(width 0.17145)
		(layer "F.Cu")
		(net "I2C_SW_EU17_ADDRESS_A1")
	)
	(segment
		(start 78.0796 -357.2764)
		(end 76.950062 -358.405938)
		(width 0.17145)
		(layer "F.Cu")
		(net "I2C_SW_EU17_ADDRESS_A1")
	)
	(segment
		(start 78.0796 -355.8032)
		(end 78.0796 -357.2764)
		(width 0.17145)
		(layer "F.Cu")
		(net "I2C_SW_EU17_ADDRESS_A1")
	)
	(segment
		(start 79.121 -354.7618)
		(end 78.0796 -355.8032)
		(width 0.17145)
		(layer "F.Cu")
		(net "I2C_SW_EU17_ADDRESS_A1")
	)
	(segment
		(start 79.121 -354.5205)
		(end 79.121 -354.7618)
		(width 0.17145)
		(layer "F.Cu")
		(net "I2C_SW_EU17_ADDRESS_A1")
	)
	(via
		(at 78.0796 -355.8032)
		(size 0.7112)
		(drill 0.3556)
		(layers "F.Cu" "B.Cu")
		(net "I2C_SW_EU17_ADDRESS_A1")
	)
	(segment
		(start 76.581 -357.505)
		(end 77.089 -356.997)
		(width 0.17145)
		(layer "F.Cu")
		(net "I2C_SW_EU17_ADDRESS_A0")
	)
	(segment
		(start 76.449936 -358.398064)
		(end 76.449936 -359.0798)
		(width 0.17145)
		(layer "F.Cu")
		(net "I2C_SW_EU17_ADDRESS_A0")
	)
	(segment
		(start 78.105 -354.5205)
		(end 77.089 -354.5205)
		(width 0.17145)
		(layer "F.Cu")
		(net "I2C_SW_EU17_ADDRESS_A0")
	)
	(segment
		(start 77.089 -356.997)
		(end 77.089 -354.5205)
		(width 0.17145)
		(layer "F.Cu")
		(net "I2C_SW_EU17_ADDRESS_A0")
	)
	(segment
		(start 76.581 -357.505)
		(end 76.581 -358.267)
		(width 0.17145)
		(layer "F.Cu")
		(net "I2C_SW_EU17_ADDRESS_A0")
	)
	(segment
		(start 76.581 -358.267)
		(end 76.449936 -358.398064)
		(width 0.17145)
		(layer "F.Cu")
		(net "I2C_SW_EU17_ADDRESS_A0")
	)
	(via
		(at 76.581 -357.505)
		(size 0.7112)
		(drill 0.3556)
		(layers "F.Cu" "B.Cu")
		(net "I2C_SW_EU17_ADDRESS_A0")
	)
	(segment
		(start 77.851 -144.3736)
		(end 78.5241 -143.7005)
		(width 0.17145)
		(layer "F.Cu")
		(net "I2C_SW_EU16_ADDRESS_A2")
	)
	(segment
		(start 77.449934 -144.774666)
		(end 77.449934 -146.6596)
		(width 0.17145)
		(layer "F.Cu")
		(net "I2C_SW_EU16_ADDRESS_A2")
	)
	(segment
		(start 79.502 -143.7005)
		(end 80.645 -143.7005)
		(width 0.17145)
		(layer "F.Cu")
		(net "I2C_SW_EU16_ADDRESS_A2")
	)
	(segment
		(start 78.5241 -143.7005)
		(end 79.502 -143.7005)
		(width 0.17145)
		(layer "F.Cu")
		(net "I2C_SW_EU16_ADDRESS_A2")
	)
	(segment
		(start 77.851 -144.3736)
		(end 77.449934 -144.774666)
		(width 0.17145)
		(layer "F.Cu")
		(net "I2C_SW_EU16_ADDRESS_A2")
	)
	(via
		(at 77.851 -144.3736)
		(size 0.7112)
		(drill 0.3556)
		(layers "F.Cu" "B.Cu")
		(net "I2C_SW_EU16_ADDRESS_A2")
	)
	(segment
		(start 82.7405 -152.654)
		(end 82.7405 -151.638)
		(width 0.17145)
		(layer "F.Cu")
		(net "I2C_SW_EU16_ADDRESS_A1")
	)
	(segment
		(start 78.855062 -149.467062)
		(end 78.1812 -149.467062)
		(width 0.17145)
		(layer "F.Cu")
		(net "I2C_SW_EU16_ADDRESS_A1")
	)
	(segment
		(start 79.20355 -149.81555)
		(end 78.855062 -149.467062)
		(width 0.17145)
		(layer "F.Cu")
		(net "I2C_SW_EU16_ADDRESS_A1")
	)
	(segment
		(start 79.990442 -150.622)
		(end 79.20355 -149.835108)
		(width 0.17145)
		(layer "F.Cu")
		(net "I2C_SW_EU16_ADDRESS_A1")
	)
	(segment
		(start 81.5086 -150.622)
		(end 79.990442 -150.622)
		(width 0.17145)
		(layer "F.Cu")
		(net "I2C_SW_EU16_ADDRESS_A1")
	)
	(segment
		(start 82.5246 -151.638)
		(end 81.5086 -150.622)
		(width 0.17145)
		(layer "F.Cu")
		(net "I2C_SW_EU16_ADDRESS_A1")
	)
	(segment
		(start 79.20355 -149.835108)
		(end 79.20355 -149.81555)
		(width 0.17145)
		(layer "F.Cu")
		(net "I2C_SW_EU16_ADDRESS_A1")
	)
	(segment
		(start 82.7405 -151.638)
		(end 82.5246 -151.638)
		(width 0.17145)
		(layer "F.Cu")
		(net "I2C_SW_EU16_ADDRESS_A1")
	)
	(via
		(at 81.5086 -150.622)
		(size 0.7112)
		(drill 0.3556)
		(layers "F.Cu" "B.Cu")
		(net "I2C_SW_EU16_ADDRESS_A1")
	)
	(segment
		(start 81.927446 -149.606)
		(end 81.825846 -149.7076)
		(width 0.17145)
		(layer "F.Cu")
		(net "I2C_SW_EU16_ADDRESS_A0")
	)
	(segment
		(start 80.3656 -149.7076)
		(end 79.756 -149.098)
		(width 0.17145)
		(layer "F.Cu")
		(net "I2C_SW_EU16_ADDRESS_A0")
	)
	(segment
		(start 82.7405 -150.622)
		(end 82.7405 -149.606)
		(width 0.17145)
		(layer "F.Cu")
		(net "I2C_SW_EU16_ADDRESS_A0")
	)
	(segment
		(start 82.7405 -149.606)
		(end 81.927446 -149.606)
		(width 0.17145)
		(layer "F.Cu")
		(net "I2C_SW_EU16_ADDRESS_A0")
	)
	(segment
		(start 78.994 -149.098)
		(end 78.862936 -148.966936)
		(width 0.17145)
		(layer "F.Cu")
		(net "I2C_SW_EU16_ADDRESS_A0")
	)
	(segment
		(start 81.825846 -149.7076)
		(end 80.3656 -149.7076)
		(width 0.17145)
		(layer "F.Cu")
		(net "I2C_SW_EU16_ADDRESS_A0")
	)
	(segment
		(start 78.862936 -148.966936)
		(end 78.1812 -148.966936)
		(width 0.17145)
		(layer "F.Cu")
		(net "I2C_SW_EU16_ADDRESS_A0")
	)
	(segment
		(start 79.756 -149.098)
		(end 78.994 -149.098)
		(width 0.17145)
		(layer "F.Cu")
		(net "I2C_SW_EU16_ADDRESS_A0")
	)
	(via
		(at 79.756 -149.098)
		(size 0.7112)
		(drill 0.3556)
		(layers "F.Cu" "B.Cu")
		(net "I2C_SW_EU16_ADDRESS_A0")
	)
	(segment
		(start 77.8256 -359.0036)
		(end 77.449934 -359.0036)
		(width 0.17145)
		(layer "F.Cu")
		(net "I2C_MUX_RESET_R_EU17")
	)
	(segment
		(start 81.153 -355.6762)
		(end 79.629 -357.2002)
		(width 0.17145)
		(layer "F.Cu")
		(net "I2C_MUX_RESET_R_EU17")
	)
	(segment
		(start 79.629 -357.2002)
		(end 77.8256 -359.0036)
		(width 0.17145)
		(layer "F.Cu")
		(net "I2C_MUX_RESET_R_EU17")
	)
	(segment
		(start 81.153 -354.5205)
		(end 81.153 -355.6762)
		(width 0.17145)
		(layer "F.Cu")
		(net "I2C_MUX_RESET_R_EU17")
	)
	(via
		(at 79.629 -357.2002)
		(size 0.7112)
		(drill 0.3556)
		(layers "F.Cu" "B.Cu")
		(net "I2C_MUX_RESET_R_EU17")
	)
	(segment
		(start 80.1116 -151.9936)
		(end 79.4004 -151.2824)
		(width 0.17145)
		(layer "F.Cu")
		(net "I2C_MUX_RESET_R_EU16")
	)
	(segment
		(start 78.2574 -150.3172)
		(end 78.2574 -149.966934)
		(width 0.17145)
		(layer "F.Cu")
		(net "I2C_MUX_RESET_R_EU16")
	)
	(segment
		(start 82.7405 -153.67)
		(end 81.788 -153.67)
		(width 0.17145)
		(layer "F.Cu")
		(net "I2C_MUX_RESET_R_EU16")
	)
	(segment
		(start 79.4004 -151.2824)
		(end 79.2226 -151.2824)
		(width 0.17145)
		(layer "F.Cu")
		(net "I2C_MUX_RESET_R_EU16")
	)
	(segment
		(start 81.788 -153.67)
		(end 80.1116 -151.9936)
		(width 0.17145)
		(layer "F.Cu")
		(net "I2C_MUX_RESET_R_EU16")
	)
	(segment
		(start 79.2226 -151.2824)
		(end 78.2574 -150.3172)
		(width 0.17145)
		(layer "F.Cu")
		(net "I2C_MUX_RESET_R_EU16")
	)
	(via
		(at 80.1116 -151.9936)
		(size 0.7112)
		(drill 0.3556)
		(layers "F.Cu" "B.Cu")
		(net "I2C_MUX_RESET_R_EU16")
	)
	(segment
		(start 48.8315 -42.418)
		(end 48.014636 -42.418)
		(width 0.17145)
		(layer "F.Cu")
		(net "DRV_ATTN_9")
	)
	(segment
		(start 48.014636 -42.418)
		(end 47.367698 -41.771062)
		(width 0.17145)
		(layer "F.Cu")
		(net "DRV_ATTN_9")
	)
	(segment
		(start 47.10303 -41.506394)
		(end 47.367698 -41.771062)
		(width 0.17145)
		(layer "F.Cu")
		(net "DRV_ATTN_9")
	)
	(segment
		(start 44.23029 -41.506394)
		(end 47.10303 -41.506394)
		(width 0.17145)
		(layer "F.Cu")
		(net "DRV_ATTN_9")
	)
	(via
		(at 47.367698 -41.771062)
		(size 0.7112)
		(drill 0.3556)
		(layers "F.Cu" "B.Cu")
		(net "DRV_ATTN_9")
	)
	(segment
		(start 48.7045 -145.669)
		(end 48.265588 -145.669)
		(width 0.17145)
		(layer "F.Cu")
		(net "DRV_ATTN_8")
	)
	(segment
		(start 48.265588 -145.669)
		(end 47.367698 -144.77111)
		(width 0.17145)
		(layer "F.Cu")
		(net "DRV_ATTN_8")
	)
	(segment
		(start 47.10303 -144.506442)
		(end 47.367698 -144.77111)
		(width 0.17145)
		(layer "F.Cu")
		(net "DRV_ATTN_8")
	)
	(segment
		(start 44.23029 -144.506442)
		(end 47.10303 -144.506442)
		(width 0.17145)
		(layer "F.Cu")
		(net "DRV_ATTN_8")
	)
	(via
		(at 47.367698 -144.77111)
		(size 0.7112)
		(drill 0.3556)
		(layers "F.Cu" "B.Cu")
		(net "DRV_ATTN_8")
	)
	(segment
		(start 48.063658 -247.771158)
		(end 47.367698 -247.771158)
		(width 0.17145)
		(layer "F.Cu")
		(net "DRV_ATTN_7")
	)
	(segment
		(start 44.23029 -247.50649)
		(end 45.466 -247.50649)
		(width 0.17145)
		(layer "F.Cu")
		(net "DRV_ATTN_7")
	)
	(segment
		(start 45.466 -247.50649)
		(end 45.730668 -247.771158)
		(width 0.17145)
		(layer "F.Cu")
		(net "DRV_ATTN_7")
	)
	(segment
		(start 48.8315 -248.539)
		(end 48.063658 -247.771158)
		(width 0.17145)
		(layer "F.Cu")
		(net "DRV_ATTN_7")
	)
	(segment
		(start 45.730668 -247.771158)
		(end 47.367698 -247.771158)
		(width 0.17145)
		(layer "F.Cu")
		(net "DRV_ATTN_7")
	)
	(via
		(at 47.367698 -247.771158)
		(size 0.7112)
		(drill 0.3556)
		(layers "F.Cu" "B.Cu")
		(net "DRV_ATTN_7")
	)
	(segment
		(start 46.736 -351.028)
		(end 46.6344 -351.1296)
		(width 0.17145)
		(layer "F.Cu")
		(net "DRV_ATTN_6")
	)
	(segment
		(start 44.817284 -350.506284)
		(end 45.4406 -351.1296)
		(width 0.17145)
		(layer "F.Cu")
		(net "DRV_ATTN_6")
	)
	(segment
		(start 46.6344 -351.1296)
		(end 46.101 -351.1296)
		(width 0.17145)
		(layer "F.Cu")
		(net "DRV_ATTN_6")
	)
	(segment
		(start 47.4345 -351.028)
		(end 46.736 -351.028)
		(width 0.17145)
		(layer "F.Cu")
		(net "DRV_ATTN_6")
	)
	(segment
		(start 44.23029 -350.506284)
		(end 44.817284 -350.506284)
		(width 0.17145)
		(layer "F.Cu")
		(net "DRV_ATTN_6")
	)
	(segment
		(start 45.4406 -351.1296)
		(end 46.101 -351.1296)
		(width 0.17145)
		(layer "F.Cu")
		(net "DRV_ATTN_6")
	)
	(via
		(at 46.101 -351.1296)
		(size 0.7112)
		(drill 0.3556)
		(layers "F.Cu" "B.Cu")
		(net "DRV_ATTN_6")
	)
	(segment
		(start 45.527468 -453.8218)
		(end 45.476668 -453.771)
		(width 0.17145)
		(layer "F.Cu")
		(net "DRV_ATTN_5")
	)
	(segment
		(start 45.212 -453.506332)
		(end 44.23029 -453.506332)
		(width 0.17145)
		(layer "F.Cu")
		(net "DRV_ATTN_5")
	)
	(segment
		(start 45.476668 -453.771)
		(end 45.212 -453.506332)
		(width 0.17145)
		(layer "F.Cu")
		(net "DRV_ATTN_5")
	)
	(segment
		(start 47.3456 -453.8218)
		(end 45.527468 -453.8218)
		(width 0.17145)
		(layer "F.Cu")
		(net "DRV_ATTN_5")
	)
	(segment
		(start 47.6123 -453.8218)
		(end 48.5775 -454.787)
		(width 0.17145)
		(layer "F.Cu")
		(net "DRV_ATTN_5")
	)
	(segment
		(start 47.3456 -453.8218)
		(end 47.6123 -453.8218)
		(width 0.17145)
		(layer "F.Cu")
		(net "DRV_ATTN_5")
	)
	(via
		(at 47.3456 -453.8218)
		(size 0.7112)
		(drill 0.3556)
		(layers "F.Cu" "B.Cu")
		(net "DRV_ATTN_5")
	)
	(segment
		(start 233.6165 -41.771062)
		(end 232.367582 -41.771062)
		(width 0.17145)
		(layer "F.Cu")
		(net "DRV_ATTN_4")
	)
	(segment
		(start 230.134668 -41.771062)
		(end 232.367582 -41.771062)
		(width 0.17145)
		(layer "F.Cu")
		(net "DRV_ATTN_4")
	)
	(segment
		(start 229.230174 -41.506394)
		(end 229.87 -41.506394)
		(width 0.17145)
		(layer "F.Cu")
		(net "DRV_ATTN_4")
	)
	(segment
		(start 229.87 -41.506394)
		(end 230.134668 -41.771062)
		(width 0.17145)
		(layer "F.Cu")
		(net "DRV_ATTN_4")
	)
	(via
		(at 232.367582 -41.771062)
		(size 0.7112)
		(drill 0.3556)
		(layers "F.Cu" "B.Cu")
		(net "DRV_ATTN_4")
	)
	(segment
		(start 230.134668 -144.77111)
		(end 232.367582 -144.77111)
		(width 0.17145)
		(layer "F.Cu")
		(net "DRV_ATTN_3")
	)
	(segment
		(start 229.87 -144.506442)
		(end 230.134668 -144.77111)
		(width 0.17145)
		(layer "F.Cu")
		(net "DRV_ATTN_3")
	)
	(segment
		(start 233.6165 -144.77111)
		(end 232.367582 -144.77111)
		(width 0.17145)
		(layer "F.Cu")
		(net "DRV_ATTN_3")
	)
	(segment
		(start 229.230174 -144.506442)
		(end 229.87 -144.506442)
		(width 0.17145)
		(layer "F.Cu")
		(net "DRV_ATTN_3")
	)
	(via
		(at 232.367582 -144.77111)
		(size 0.7112)
		(drill 0.3556)
		(layers "F.Cu" "B.Cu")
		(net "DRV_ATTN_3")
	)
	(segment
		(start 229.230174 -247.50649)
		(end 229.997 -247.50649)
		(width 0.17145)
		(layer "F.Cu")
		(net "DRV_ATTN_2")
	)
	(segment
		(start 229.997 -247.50649)
		(end 230.261668 -247.771158)
		(width 0.17145)
		(layer "F.Cu")
		(net "DRV_ATTN_2")
	)
	(segment
		(start 233.6165 -247.771158)
		(end 232.367582 -247.771158)
		(width 0.17145)
		(layer "F.Cu")
		(net "DRV_ATTN_2")
	)
	(segment
		(start 230.261668 -247.771158)
		(end 232.367582 -247.771158)
		(width 0.17145)
		(layer "F.Cu")
		(net "DRV_ATTN_2")
	)
	(via
		(at 232.367582 -247.771158)
		(size 0.7112)
		(drill 0.3556)
		(layers "F.Cu" "B.Cu")
		(net "DRV_ATTN_2")
	)
	(segment
		(start 22.2504 -53.306472)
		(end 22.928072 -53.306472)
		(width 0.17145)
		(layer "F.Cu")
		(net "DRV_ATTN_14")
	)
	(segment
		(start 22.9616 -53.34)
		(end 23.5585 -53.34)
		(width 0.17145)
		(layer "F.Cu")
		(net "DRV_ATTN_14")
	)
	(segment
		(start 22.928072 -53.306472)
		(end 22.9616 -53.34)
		(width 0.17145)
		(layer "F.Cu")
		(net "DRV_ATTN_14")
	)
	(segment
		(start 19.23034 -53.306472)
		(end 22.2504 -53.306472)
		(width 0.17145)
		(layer "F.Cu")
		(net "DRV_ATTN_14")
	)
	(via
		(at 22.2504 -53.306472)
		(size 0.7112)
		(drill 0.3556)
		(layers "F.Cu" "B.Cu")
		(net "DRV_ATTN_14")
	)
	(segment
		(start 23.5585 -156.337)
		(end 22.641052 -156.337)
		(width 0.17145)
		(layer "F.Cu")
		(net "DRV_ATTN_13")
	)
	(segment
		(start 19.23034 -156.30652)
		(end 19.887438 -156.30652)
		(width 0.17145)
		(layer "F.Cu")
		(net "DRV_ATTN_13")
	)
	(segment
		(start 19.887438 -156.30652)
		(end 20.20697 -156.626052)
		(width 0.17145)
		(layer "F.Cu")
		(net "DRV_ATTN_13")
	)
	(segment
		(start 20.20697 -156.626052)
		(end 21.072348 -156.626052)
		(width 0.17145)
		(layer "F.Cu")
		(net "DRV_ATTN_13")
	)
	(segment
		(start 22.352 -156.626052)
		(end 21.072348 -156.626052)
		(width 0.17145)
		(layer "F.Cu")
		(net "DRV_ATTN_13")
	)
	(segment
		(start 22.641052 -156.337)
		(end 22.352 -156.626052)
		(width 0.17145)
		(layer "F.Cu")
		(net "DRV_ATTN_13")
	)
	(via
		(at 21.072348 -156.626052)
		(size 0.7112)
		(drill 0.3556)
		(layers "F.Cu" "B.Cu")
		(net "DRV_ATTN_13")
	)
	(segment
		(start 22.389846 -259.334)
		(end 22.098 -259.625846)
		(width 0.17145)
		(layer "F.Cu")
		(net "DRV_ATTN_12")
	)
	(segment
		(start 19.887438 -259.306314)
		(end 20.20697 -259.625846)
		(width 0.17145)
		(layer "F.Cu")
		(net "DRV_ATTN_12")
	)
	(segment
		(start 19.23034 -259.306314)
		(end 19.887438 -259.306314)
		(width 0.17145)
		(layer "F.Cu")
		(net "DRV_ATTN_12")
	)
	(segment
		(start 20.20697 -259.625846)
		(end 21.072348 -259.625846)
		(width 0.17145)
		(layer "F.Cu")
		(net "DRV_ATTN_12")
	)
	(segment
		(start 23.5585 -259.334)
		(end 22.389846 -259.334)
		(width 0.17145)
		(layer "F.Cu")
		(net "DRV_ATTN_12")
	)
	(segment
		(start 22.098 -259.625846)
		(end 21.072348 -259.625846)
		(width 0.17145)
		(layer "F.Cu")
		(net "DRV_ATTN_12")
	)
	(via
		(at 21.072348 -259.625846)
		(size 0.7112)
		(drill 0.3556)
		(layers "F.Cu" "B.Cu")
		(net "DRV_ATTN_12")
	)
	(segment
		(start 19.887438 -362.306362)
		(end 19.23034 -362.306362)
		(width 0.17145)
		(layer "F.Cu")
		(net "DRV_ATTN_11")
	)
	(segment
		(start 20.20697 -362.625894)
		(end 19.887438 -362.306362)
		(width 0.17145)
		(layer "F.Cu")
		(net "DRV_ATTN_11")
	)
	(segment
		(start 21.072348 -362.625894)
		(end 20.20697 -362.625894)
		(width 0.17145)
		(layer "F.Cu")
		(net "DRV_ATTN_11")
	)
	(segment
		(start 22.646894 -362.331)
		(end 22.352 -362.625894)
		(width 0.17145)
		(layer "F.Cu")
		(net "DRV_ATTN_11")
	)
	(segment
		(start 23.5585 -362.331)
		(end 22.646894 -362.331)
		(width 0.17145)
		(layer "F.Cu")
		(net "DRV_ATTN_11")
	)
	(segment
		(start 22.352 -362.625894)
		(end 21.072348 -362.625894)
		(width 0.17145)
		(layer "F.Cu")
		(net "DRV_ATTN_11")
	)
	(via
		(at 21.072348 -362.625894)
		(size 0.7112)
		(drill 0.3556)
		(layers "F.Cu" "B.Cu")
		(net "DRV_ATTN_11")
	)
	(segment
		(start 23.8125 -464.82)
		(end 22.624796 -464.82)
		(width 0.17145)
		(layer "F.Cu")
		(net "DRV_ATTN_10")
	)
	(segment
		(start 22.269196 -465.1756)
		(end 21.072856 -465.1756)
		(width 0.17145)
		(layer "F.Cu")
		(net "DRV_ATTN_10")
	)
	(segment
		(start 22.624796 -464.82)
		(end 22.269196 -465.1756)
		(width 0.17145)
		(layer "F.Cu")
		(net "DRV_ATTN_10")
	)
	(segment
		(start 20.40001 -465.1756)
		(end 20.2692 -465.30641)
		(width 0.17145)
		(layer "F.Cu")
		(net "DRV_ATTN_10")
	)
	(segment
		(start 21.072856 -465.1756)
		(end 20.40001 -465.1756)
		(width 0.17145)
		(layer "F.Cu")
		(net "DRV_ATTN_10")
	)
	(segment
		(start 20.2692 -465.30641)
		(end 19.23034 -465.30641)
		(width 0.17145)
		(layer "F.Cu")
		(net "DRV_ATTN_10")
	)
	(via
		(at 21.072856 -465.1756)
		(size 0.7112)
		(drill 0.3556)
		(layers "F.Cu" "B.Cu")
		(net "DRV_ATTN_10")
	)
	(segment
		(start 229.983284 -350.506284)
		(end 230.247952 -350.770952)
		(width 0.17145)
		(layer "F.Cu")
		(net "DRV_ATTN_1")
	)
	(segment
		(start 229.230174 -350.506284)
		(end 229.983284 -350.506284)
		(width 0.17145)
		(layer "F.Cu")
		(net "DRV_ATTN_1")
	)
	(segment
		(start 233.6165 -350.770952)
		(end 232.367582 -350.770952)
		(width 0.17145)
		(layer "F.Cu")
		(net "DRV_ATTN_1")
	)
	(segment
		(start 230.247952 -350.770952)
		(end 232.367582 -350.770952)
		(width 0.17145)
		(layer "F.Cu")
		(net "DRV_ATTN_1")
	)
	(via
		(at 232.367582 -350.770952)
		(size 0.7112)
		(drill 0.3556)
		(layers "F.Cu" "B.Cu")
		(net "DRV_ATTN_1")
	)
	(segment
		(start 230.113332 -453.506332)
		(end 230.378 -453.771)
		(width 0.17145)
		(layer "F.Cu")
		(net "DRV_ATTN_0")
	)
	(segment
		(start 233.6165 -453.771)
		(end 232.367582 -453.771)
		(width 0.17145)
		(layer "F.Cu")
		(net "DRV_ATTN_0")
	)
	(segment
		(start 229.230174 -453.506332)
		(end 230.113332 -453.506332)
		(width 0.17145)
		(layer "F.Cu")
		(net "DRV_ATTN_0")
	)
	(segment
		(start 230.378 -453.771)
		(end 232.367582 -453.771)
		(width 0.17145)
		(layer "F.Cu")
		(net "DRV_ATTN_0")
	)
	(via
		(at 232.367582 -453.771)
		(size 0.7112)
		(drill 0.3556)
		(layers "F.Cu" "B.Cu")
		(net "DRV_ATTN_0")
	)
	(segment
		(start 86.741 -94.742)
		(end 84.8995 -94.742)
		(width 0.17145)
		(layer "F.Cu")
		(net "CLK_BUF_EU4_SMB_A1_TRI")
	)
	(segment
		(start 87.4776 -95.123)
		(end 87.122 -95.123)
		(width 0.17145)
		(layer "F.Cu")
		(net "CLK_BUF_EU4_SMB_A1_TRI")
	)
	(segment
		(start 84.8995 -95.758)
		(end 84.8995 -94.742)
		(width 0.17145)
		(layer "F.Cu")
		(net "CLK_BUF_EU4_SMB_A1_TRI")
	)
	(segment
		(start 87.8586 -95.504)
		(end 87.4776 -95.123)
		(width 0.17145)
		(layer "F.Cu")
		(net "CLK_BUF_EU4_SMB_A1_TRI")
	)
	(segment
		(start 88.392 -96.0374)
		(end 87.8586 -95.504)
		(width 0.17145)
		(layer "F.Cu")
		(net "CLK_BUF_EU4_SMB_A1_TRI")
	)
	(segment
		(start 88.392 -98.298)
		(end 88.392 -96.0374)
		(width 0.17145)
		(layer "F.Cu")
		(net "CLK_BUF_EU4_SMB_A1_TRI")
	)
	(segment
		(start 89.55659 -98.85045)
		(end 88.94445 -98.85045)
		(width 0.17145)
		(layer "F.Cu")
		(net "CLK_BUF_EU4_SMB_A1_TRI")
	)
	(segment
		(start 87.122 -95.123)
		(end 86.741 -94.742)
		(width 0.17145)
		(layer "F.Cu")
		(net "CLK_BUF_EU4_SMB_A1_TRI")
	)
	(segment
		(start 88.94445 -98.85045)
		(end 88.392 -98.298)
		(width 0.17145)
		(layer "F.Cu")
		(net "CLK_BUF_EU4_SMB_A1_TRI")
	)
	(via
		(at 87.8586 -95.504)
		(size 0.7112)
		(drill 0.3556)
		(layers "F.Cu" "B.Cu")
		(net "CLK_BUF_EU4_SMB_A1_TRI")
	)
	(segment
		(start 85.9155 -98.806)
		(end 85.9155 -99.822)
		(width 0.17145)
		(layer "F.Cu")
		(net "CLK_BUF_EU4_SMB_A0_TRI")
	)
	(segment
		(start 88.519 -100.584)
		(end 88.011 -100.584)
		(width 0.17145)
		(layer "F.Cu")
		(net "CLK_BUF_EU4_SMB_A0_TRI")
	)
	(segment
		(start 85.9155 -99.822)
		(end 87.249 -99.822)
		(width 0.17145)
		(layer "F.Cu")
		(net "CLK_BUF_EU4_SMB_A0_TRI")
	)
	(segment
		(start 88.011 -100.584)
		(end 87.249 -99.822)
		(width 0.17145)
		(layer "F.Cu")
		(net "CLK_BUF_EU4_SMB_A0_TRI")
	)
	(segment
		(start 88.75268 -100.35032)
		(end 88.519 -100.584)
		(width 0.17145)
		(layer "F.Cu")
		(net "CLK_BUF_EU4_SMB_A0_TRI")
	)
	(segment
		(start 89.55659 -100.35032)
		(end 88.75268 -100.35032)
		(width 0.17145)
		(layer "F.Cu")
		(net "CLK_BUF_EU4_SMB_A0_TRI")
	)
	(via
		(at 87.249 -99.822)
		(size 0.7112)
		(drill 0.3556)
		(layers "F.Cu" "B.Cu")
		(net "CLK_BUF_EU4_SMB_A0_TRI")
	)
	(segment
		(start 83.3755 -104.902)
		(end 84.709 -104.902)
		(width 0.17145)
		(layer "F.Cu")
		(net "CLK_BUF_EU4_HIBW_BYPM_LOBW#")
	)
	(segment
		(start 86.127844 -104.479852)
		(end 87.798148 -104.479852)
		(width 0.17145)
		(layer "F.Cu")
		(net "CLK_BUF_EU4_HIBW_BYPM_LOBW#")
	)
	(segment
		(start 84.709 -104.902)
		(end 85.705696 -104.902)
		(width 0.17145)
		(layer "F.Cu")
		(net "CLK_BUF_EU4_HIBW_BYPM_LOBW#")
	)
	(segment
		(start 88.92794 -103.35006)
		(end 89.55659 -103.35006)
		(width 0.17145)
		(layer "F.Cu")
		(net "CLK_BUF_EU4_HIBW_BYPM_LOBW#")
	)
	(segment
		(start 85.705696 -104.902)
		(end 86.127844 -104.479852)
		(width 0.17145)
		(layer "F.Cu")
		(net "CLK_BUF_EU4_HIBW_BYPM_LOBW#")
	)
	(segment
		(start 83.3755 -105.918)
		(end 83.3755 -104.902)
		(width 0.17145)
		(layer "F.Cu")
		(net "CLK_BUF_EU4_HIBW_BYPM_LOBW#")
	)
	(segment
		(start 87.798148 -104.479852)
		(end 88.92794 -103.35006)
		(width 0.17145)
		(layer "F.Cu")
		(net "CLK_BUF_EU4_HIBW_BYPM_LOBW#")
	)
	(via
		(at 84.709 -104.902)
		(size 0.7112)
		(drill 0.3556)
		(layers "F.Cu" "B.Cu")
		(net "CLK_BUF_EU4_HIBW_BYPM_LOBW#")
	)
	(segment
		(start 85.471 -106.172)
		(end 85.471 -105.918)
		(width 0.17145)
		(layer "F.Cu")
		(net "CLK_BUF_EU4_100M_133M#")
	)
	(segment
		(start 87.753698 -105.032302)
		(end 88.93556 -103.85044)
		(width 0.17145)
		(layer "F.Cu")
		(net "CLK_BUF_EU4_100M_133M#")
	)
	(segment
		(start 88.93556 -103.85044)
		(end 89.55659 -103.85044)
		(width 0.17145)
		(layer "F.Cu")
		(net "CLK_BUF_EU4_100M_133M#")
	)
	(segment
		(start 86.356698 -105.032302)
		(end 87.753698 -105.032302)
		(width 0.17145)
		(layer "F.Cu")
		(net "CLK_BUF_EU4_100M_133M#")
	)
	(segment
		(start 83.3755 -106.934)
		(end 84.709 -106.934)
		(width 0.17145)
		(layer "F.Cu")
		(net "CLK_BUF_EU4_100M_133M#")
	)
	(segment
		(start 85.471 -105.918)
		(end 86.356698 -105.032302)
		(width 0.17145)
		(layer "F.Cu")
		(net "CLK_BUF_EU4_100M_133M#")
	)
	(segment
		(start 84.709 -106.934)
		(end 85.471 -106.172)
		(width 0.17145)
		(layer "F.Cu")
		(net "CLK_BUF_EU4_100M_133M#")
	)
	(via
		(at 84.709 -106.934)
		(size 0.7112)
		(drill 0.3556)
		(layers "F.Cu" "B.Cu")
		(net "CLK_BUF_EU4_100M_133M#")
	)
	(segment
		(start 84.8995 -204.978)
		(end 84.8995 -203.962)
		(width 0.17145)
		(layer "F.Cu")
		(net "CLK_BUF_EU3_SMB_A1_TRI")
	)
	(segment
		(start 88.94445 -208.07045)
		(end 89.55659 -208.07045)
		(width 0.17145)
		(layer "F.Cu")
		(net "CLK_BUF_EU3_SMB_A1_TRI")
	)
	(segment
		(start 87.7062 -204.3176)
		(end 88.392 -205.0034)
		(width 0.17145)
		(layer "F.Cu")
		(net "CLK_BUF_EU3_SMB_A1_TRI")
	)
	(segment
		(start 87.7062 -204.3176)
		(end 87.3506 -203.962)
		(width 0.17145)
		(layer "F.Cu")
		(net "CLK_BUF_EU3_SMB_A1_TRI")
	)
	(segment
		(start 87.3506 -203.962)
		(end 84.8995 -203.962)
		(width 0.17145)
		(layer "F.Cu")
		(net "CLK_BUF_EU3_SMB_A1_TRI")
	)
	(segment
		(start 88.392 -205.0034)
		(end 88.392 -207.518)
		(width 0.17145)
		(layer "F.Cu")
		(net "CLK_BUF_EU3_SMB_A1_TRI")
	)
	(segment
		(start 88.392 -207.518)
		(end 88.94445 -208.07045)
		(width 0.17145)
		(layer "F.Cu")
		(net "CLK_BUF_EU3_SMB_A1_TRI")
	)
	(via
		(at 87.7062 -204.3176)
		(size 0.7112)
		(drill 0.3556)
		(layers "F.Cu" "B.Cu")
		(net "CLK_BUF_EU3_SMB_A1_TRI")
	)
	(segment
		(start 88.011 -209.804)
		(end 87.249 -209.042)
		(width 0.17145)
		(layer "F.Cu")
		(net "CLK_BUF_EU3_SMB_A0_TRI")
	)
	(segment
		(start 88.519 -209.804)
		(end 88.011 -209.804)
		(width 0.17145)
		(layer "F.Cu")
		(net "CLK_BUF_EU3_SMB_A0_TRI")
	)
	(segment
		(start 89.55659 -209.57032)
		(end 88.75268 -209.57032)
		(width 0.17145)
		(layer "F.Cu")
		(net "CLK_BUF_EU3_SMB_A0_TRI")
	)
	(segment
		(start 85.9155 -209.042)
		(end 87.249 -209.042)
		(width 0.17145)
		(layer "F.Cu")
		(net "CLK_BUF_EU3_SMB_A0_TRI")
	)
	(segment
		(start 88.75268 -209.57032)
		(end 88.519 -209.804)
		(width 0.17145)
		(layer "F.Cu")
		(net "CLK_BUF_EU3_SMB_A0_TRI")
	)
	(segment
		(start 85.9155 -208.026)
		(end 85.9155 -209.042)
		(width 0.17145)
		(layer "F.Cu")
		(net "CLK_BUF_EU3_SMB_A0_TRI")
	)
	(via
		(at 87.249 -209.042)
		(size 0.7112)
		(drill 0.3556)
		(layers "F.Cu" "B.Cu")
		(net "CLK_BUF_EU3_SMB_A0_TRI")
	)
	(segment
		(start 88.92794 -212.57006)
		(end 89.55659 -212.57006)
		(width 0.17145)
		(layer "F.Cu")
		(net "CLK_BUF_EU3_HIBW_BYPM_LOBW#")
	)
	(segment
		(start 84.709 -214.122)
		(end 85.654896 -214.122)
		(width 0.17145)
		(layer "F.Cu")
		(net "CLK_BUF_EU3_HIBW_BYPM_LOBW#")
	)
	(segment
		(start 85.654896 -214.122)
		(end 86.077044 -213.699852)
		(width 0.17145)
		(layer "F.Cu")
		(net "CLK_BUF_EU3_HIBW_BYPM_LOBW#")
	)
	(segment
		(start 86.077044 -213.699852)
		(end 87.798148 -213.699852)
		(width 0.17145)
		(layer "F.Cu")
		(net "CLK_BUF_EU3_HIBW_BYPM_LOBW#")
	)
	(segment
		(start 87.798148 -213.699852)
		(end 88.92794 -212.57006)
		(width 0.17145)
		(layer "F.Cu")
		(net "CLK_BUF_EU3_HIBW_BYPM_LOBW#")
	)
	(segment
		(start 83.3755 -214.122)
		(end 83.3755 -215.138)
		(width 0.17145)
		(layer "F.Cu")
		(net "CLK_BUF_EU3_HIBW_BYPM_LOBW#")
	)
	(segment
		(start 84.709 -214.122)
		(end 83.3755 -214.122)
		(width 0.17145)
		(layer "F.Cu")
		(net "CLK_BUF_EU3_HIBW_BYPM_LOBW#")
	)
	(via
		(at 84.709 -214.122)
		(size 0.7112)
		(drill 0.3556)
		(layers "F.Cu" "B.Cu")
		(net "CLK_BUF_EU3_HIBW_BYPM_LOBW#")
	)
	(segment
		(start 85.471 -215.0872)
		(end 86.305898 -214.252302)
		(width 0.17145)
		(layer "F.Cu")
		(net "CLK_BUF_EU3_100M_133M#")
	)
	(segment
		(start 87.753698 -214.252302)
		(end 88.93556 -213.07044)
		(width 0.17145)
		(layer "F.Cu")
		(net "CLK_BUF_EU3_100M_133M#")
	)
	(segment
		(start 85.471 -215.392)
		(end 85.471 -215.0872)
		(width 0.17145)
		(layer "F.Cu")
		(net "CLK_BUF_EU3_100M_133M#")
	)
	(segment
		(start 84.709 -216.154)
		(end 85.471 -215.392)
		(width 0.17145)
		(layer "F.Cu")
		(net "CLK_BUF_EU3_100M_133M#")
	)
	(segment
		(start 88.93556 -213.07044)
		(end 89.55659 -213.07044)
		(width 0.17145)
		(layer "F.Cu")
		(net "CLK_BUF_EU3_100M_133M#")
	)
	(segment
		(start 83.3755 -216.154)
		(end 84.709 -216.154)
		(width 0.17145)
		(layer "F.Cu")
		(net "CLK_BUF_EU3_100M_133M#")
	)
	(segment
		(start 86.305898 -214.252302)
		(end 87.753698 -214.252302)
		(width 0.17145)
		(layer "F.Cu")
		(net "CLK_BUF_EU3_100M_133M#")
	)
	(via
		(at 84.709 -216.154)
		(size 0.7112)
		(drill 0.3556)
		(layers "F.Cu" "B.Cu")
		(net "CLK_BUF_EU3_100M_133M#")
	)
	(segment
		(start 87.376 -298.323)
		(end 87.7824 -298.7294)
		(width 0.17145)
		(layer "F.Cu")
		(net "CLK_BUF_EU2_SMB_A1_TRI")
	)
	(segment
		(start 84.8995 -298.323)
		(end 87.376 -298.323)
		(width 0.17145)
		(layer "F.Cu")
		(net "CLK_BUF_EU2_SMB_A1_TRI")
	)
	(segment
		(start 89.55659 -302.43145)
		(end 88.94445 -302.43145)
		(width 0.17145)
		(layer "F.Cu")
		(net "CLK_BUF_EU2_SMB_A1_TRI")
	)
	(segment
		(start 88.94445 -302.43145)
		(end 88.392 -301.879)
		(width 0.17145)
		(layer "F.Cu")
		(net "CLK_BUF_EU2_SMB_A1_TRI")
	)
	(segment
		(start 88.392 -299.339)
		(end 87.7824 -298.7294)
		(width 0.17145)
		(layer "F.Cu")
		(net "CLK_BUF_EU2_SMB_A1_TRI")
	)
	(segment
		(start 84.8995 -299.339)
		(end 84.8995 -298.323)
		(width 0.17145)
		(layer "F.Cu")
		(net "CLK_BUF_EU2_SMB_A1_TRI")
	)
	(segment
		(start 88.392 -301.879)
		(end 88.392 -299.339)
		(width 0.17145)
		(layer "F.Cu")
		(net "CLK_BUF_EU2_SMB_A1_TRI")
	)
	(via
		(at 87.7824 -298.7294)
		(size 0.7112)
		(drill 0.3556)
		(layers "F.Cu" "B.Cu")
		(net "CLK_BUF_EU2_SMB_A1_TRI")
	)
	(segment
		(start 88.519 -304.165)
		(end 88.011 -304.165)
		(width 0.17145)
		(layer "F.Cu")
		(net "CLK_BUF_EU2_SMB_A0_TRI")
	)
	(segment
		(start 89.55659 -303.93132)
		(end 88.75268 -303.93132)
		(width 0.17145)
		(layer "F.Cu")
		(net "CLK_BUF_EU2_SMB_A0_TRI")
	)
	(segment
		(start 88.75268 -303.93132)
		(end 88.519 -304.165)
		(width 0.17145)
		(layer "F.Cu")
		(net "CLK_BUF_EU2_SMB_A0_TRI")
	)
	(segment
		(start 88.011 -304.165)
		(end 87.249 -303.403)
		(width 0.17145)
		(layer "F.Cu")
		(net "CLK_BUF_EU2_SMB_A0_TRI")
	)
	(segment
		(start 85.9155 -303.403)
		(end 85.9155 -302.387)
		(width 0.17145)
		(layer "F.Cu")
		(net "CLK_BUF_EU2_SMB_A0_TRI")
	)
	(segment
		(start 87.249 -303.403)
		(end 85.9155 -303.403)
		(width 0.17145)
		(layer "F.Cu")
		(net "CLK_BUF_EU2_SMB_A0_TRI")
	)
	(via
		(at 87.249 -303.403)
		(size 0.7112)
		(drill 0.3556)
		(layers "F.Cu" "B.Cu")
		(net "CLK_BUF_EU2_SMB_A0_TRI")
	)
	(segment
		(start 84.709 -308.483)
		(end 85.625432 -308.483)
		(width 0.17145)
		(layer "F.Cu")
		(net "CLK_BUF_EU2_HIBW_BYPM_LOBW#")
	)
	(segment
		(start 85.625432 -308.483)
		(end 86.04758 -308.060852)
		(width 0.17145)
		(layer "F.Cu")
		(net "CLK_BUF_EU2_HIBW_BYPM_LOBW#")
	)
	(segment
		(start 83.3755 -309.499)
		(end 83.3755 -308.483)
		(width 0.17145)
		(layer "F.Cu")
		(net "CLK_BUF_EU2_HIBW_BYPM_LOBW#")
	)
	(segment
		(start 88.92794 -306.93106)
		(end 89.55659 -306.93106)
		(width 0.17145)
		(layer "F.Cu")
		(net "CLK_BUF_EU2_HIBW_BYPM_LOBW#")
	)
	(segment
		(start 83.3755 -308.483)
		(end 84.709 -308.483)
		(width 0.17145)
		(layer "F.Cu")
		(net "CLK_BUF_EU2_HIBW_BYPM_LOBW#")
	)
	(segment
		(start 87.798148 -308.060852)
		(end 88.92794 -306.93106)
		(width 0.17145)
		(layer "F.Cu")
		(net "CLK_BUF_EU2_HIBW_BYPM_LOBW#")
	)
	(segment
		(start 86.04758 -308.060852)
		(end 87.798148 -308.060852)
		(width 0.17145)
		(layer "F.Cu")
		(net "CLK_BUF_EU2_HIBW_BYPM_LOBW#")
	)
	(via
		(at 84.709 -308.483)
		(size 0.7112)
		(drill 0.3556)
		(layers "F.Cu" "B.Cu")
		(net "CLK_BUF_EU2_HIBW_BYPM_LOBW#")
	)
	(segment
		(start 86.276434 -308.613302)
		(end 87.753698 -308.613302)
		(width 0.17145)
		(layer "F.Cu")
		(net "CLK_BUF_EU2_100M_133M#")
	)
	(segment
		(start 85.471 -309.418736)
		(end 86.276434 -308.613302)
		(width 0.17145)
		(layer "F.Cu")
		(net "CLK_BUF_EU2_100M_133M#")
	)
	(segment
		(start 85.471 -310.2102)
		(end 85.471 -309.418736)
		(width 0.17145)
		(layer "F.Cu")
		(net "CLK_BUF_EU2_100M_133M#")
	)
	(segment
		(start 88.93556 -307.43144)
		(end 89.55659 -307.43144)
		(width 0.17145)
		(layer "F.Cu")
		(net "CLK_BUF_EU2_100M_133M#")
	)
	(segment
		(start 83.3755 -310.515)
		(end 84.709 -310.515)
		(width 0.17145)
		(layer "F.Cu")
		(net "CLK_BUF_EU2_100M_133M#")
	)
	(segment
		(start 87.753698 -308.613302)
		(end 88.93556 -307.43144)
		(width 0.17145)
		(layer "F.Cu")
		(net "CLK_BUF_EU2_100M_133M#")
	)
	(segment
		(start 85.1662 -310.515)
		(end 85.471 -310.2102)
		(width 0.17145)
		(layer "F.Cu")
		(net "CLK_BUF_EU2_100M_133M#")
	)
	(segment
		(start 84.709 -310.515)
		(end 85.1662 -310.515)
		(width 0.17145)
		(layer "F.Cu")
		(net "CLK_BUF_EU2_100M_133M#")
	)
	(via
		(at 84.709 -310.515)
		(size 0.7112)
		(drill 0.3556)
		(layers "F.Cu" "B.Cu")
		(net "CLK_BUF_EU2_100M_133M#")
	)
	(segment
		(start 85.979 -424.942)
		(end 84.8995 -424.942)
		(width 0.17145)
		(layer "F.Cu")
		(net "CLK_BUF_EU1_SMB_A1_TRI")
	)
	(segment
		(start 88.4682 -426.4152)
		(end 88.4682 -428.5742)
		(width 0.17145)
		(layer "F.Cu")
		(net "CLK_BUF_EU1_SMB_A1_TRI")
	)
	(segment
		(start 88.94445 -429.05045)
		(end 89.55659 -429.05045)
		(width 0.17145)
		(layer "F.Cu")
		(net "CLK_BUF_EU1_SMB_A1_TRI")
	)
	(segment
		(start 87.884 -425.831)
		(end 86.868 -425.831)
		(width 0.17145)
		(layer "F.Cu")
		(net "CLK_BUF_EU1_SMB_A1_TRI")
	)
	(segment
		(start 87.884 -425.831)
		(end 88.4682 -426.4152)
		(width 0.17145)
		(layer "F.Cu")
		(net "CLK_BUF_EU1_SMB_A1_TRI")
	)
	(segment
		(start 86.868 -425.831)
		(end 85.979 -424.942)
		(width 0.17145)
		(layer "F.Cu")
		(net "CLK_BUF_EU1_SMB_A1_TRI")
	)
	(segment
		(start 84.8995 -424.942)
		(end 84.8995 -425.958)
		(width 0.17145)
		(layer "F.Cu")
		(net "CLK_BUF_EU1_SMB_A1_TRI")
	)
	(segment
		(start 88.4682 -428.5742)
		(end 88.94445 -429.05045)
		(width 0.17145)
		(layer "F.Cu")
		(net "CLK_BUF_EU1_SMB_A1_TRI")
	)
	(via
		(at 87.884 -425.831)
		(size 0.7112)
		(drill 0.3556)
		(layers "F.Cu" "B.Cu")
		(net "CLK_BUF_EU1_SMB_A1_TRI")
	)
	(segment
		(start 86.5886 -430.53)
		(end 85.9155 -430.53)
		(width 0.17145)
		(layer "F.Cu")
		(net "CLK_BUF_EU1_SMB_A0_TRI")
	)
	(segment
		(start 86.9442 -430.1744)
		(end 86.5886 -430.53)
		(width 0.17145)
		(layer "F.Cu")
		(net "CLK_BUF_EU1_SMB_A0_TRI")
	)
	(segment
		(start 87.376 -430.1744)
		(end 86.9442 -430.1744)
		(width 0.17145)
		(layer "F.Cu")
		(net "CLK_BUF_EU1_SMB_A0_TRI")
	)
	(segment
		(start 87.9348 -430.1744)
		(end 87.376 -430.1744)
		(width 0.17145)
		(layer "F.Cu")
		(net "CLK_BUF_EU1_SMB_A0_TRI")
	)
	(segment
		(start 85.9155 -429.514)
		(end 85.9155 -430.53)
		(width 0.17145)
		(layer "F.Cu")
		(net "CLK_BUF_EU1_SMB_A0_TRI")
	)
	(segment
		(start 89.55659 -430.55032)
		(end 88.31072 -430.55032)
		(width 0.17145)
		(layer "F.Cu")
		(net "CLK_BUF_EU1_SMB_A0_TRI")
	)
	(segment
		(start 88.31072 -430.55032)
		(end 87.9348 -430.1744)
		(width 0.17145)
		(layer "F.Cu")
		(net "CLK_BUF_EU1_SMB_A0_TRI")
	)
	(via
		(at 87.376 -430.1744)
		(size 0.7112)
		(drill 0.3556)
		(layers "F.Cu" "B.Cu")
		(net "CLK_BUF_EU1_SMB_A0_TRI")
	)
	(segment
		(start 85.654896 -435.102)
		(end 86.077044 -434.679852)
		(width 0.17145)
		(layer "F.Cu")
		(net "CLK_BUF_EU1_HIBW_BYPM_LOBW#")
	)
	(segment
		(start 86.077044 -434.679852)
		(end 87.798148 -434.679852)
		(width 0.17145)
		(layer "F.Cu")
		(net "CLK_BUF_EU1_HIBW_BYPM_LOBW#")
	)
	(segment
		(start 83.3755 -435.102)
		(end 83.3755 -436.118)
		(width 0.17145)
		(layer "F.Cu")
		(net "CLK_BUF_EU1_HIBW_BYPM_LOBW#")
	)
	(segment
		(start 84.709 -435.102)
		(end 83.3755 -435.102)
		(width 0.17145)
		(layer "F.Cu")
		(net "CLK_BUF_EU1_HIBW_BYPM_LOBW#")
	)
	(segment
		(start 87.798148 -434.679852)
		(end 88.92794 -433.55006)
		(width 0.17145)
		(layer "F.Cu")
		(net "CLK_BUF_EU1_HIBW_BYPM_LOBW#")
	)
	(segment
		(start 88.92794 -433.55006)
		(end 89.55659 -433.55006)
		(width 0.17145)
		(layer "F.Cu")
		(net "CLK_BUF_EU1_HIBW_BYPM_LOBW#")
	)
	(segment
		(start 84.709 -435.102)
		(end 85.654896 -435.102)
		(width 0.17145)
		(layer "F.Cu")
		(net "CLK_BUF_EU1_HIBW_BYPM_LOBW#")
	)
	(via
		(at 84.709 -435.102)
		(size 0.7112)
		(drill 0.3556)
		(layers "F.Cu" "B.Cu")
		(net "CLK_BUF_EU1_HIBW_BYPM_LOBW#")
	)
	(segment
		(start 84.709 -437.134)
		(end 85.471 -436.372)
		(width 0.17145)
		(layer "F.Cu")
		(net "CLK_BUF_EU1_100M_133M#")
	)
	(segment
		(start 86.305898 -435.232302)
		(end 87.753698 -435.232302)
		(width 0.17145)
		(layer "F.Cu")
		(net "CLK_BUF_EU1_100M_133M#")
	)
	(segment
		(start 88.93556 -434.05044)
		(end 89.55659 -434.05044)
		(width 0.17145)
		(layer "F.Cu")
		(net "CLK_BUF_EU1_100M_133M#")
	)
	(segment
		(start 85.471 -436.0672)
		(end 86.305898 -435.232302)
		(width 0.17145)
		(layer "F.Cu")
		(net "CLK_BUF_EU1_100M_133M#")
	)
	(segment
		(start 85.471 -436.372)
		(end 85.471 -436.0672)
		(width 0.17145)
		(layer "F.Cu")
		(net "CLK_BUF_EU1_100M_133M#")
	)
	(segment
		(start 83.3755 -437.134)
		(end 84.709 -437.134)
		(width 0.17145)
		(layer "F.Cu")
		(net "CLK_BUF_EU1_100M_133M#")
	)
	(segment
		(start 87.753698 -435.232302)
		(end 88.93556 -434.05044)
		(width 0.17145)
		(layer "F.Cu")
		(net "CLK_BUF_EU1_100M_133M#")
	)
	(via
		(at 84.709 -437.134)
		(size 0.7112)
		(drill 0.3556)
		(layers "F.Cu" "B.Cu")
		(net "CLK_BUF_EU1_100M_133M#")
	)
	(segment
		(start 98.911918 -106.150918)
		(end 97.73031 -106.150918)
		(width 0.3048)
		(layer "F.Cu")
		(net "VDD_IO_4")
	)
	(segment
		(start 97.73031 -97.049082)
		(end 98.340418 -97.049082)
		(width 0.3048)
		(layer "F.Cu")
		(net "VDD_IO_4")
	)
	(segment
		(start 99.949 -96.5835)
		(end 100.838 -96.5835)
		(width 0.508)
		(layer "F.Cu")
		(net "VDD_IO_4")
	)
	(segment
		(start 98.9965 -106.2355)
		(end 98.911918 -106.150918)
		(width 0.3048)
		(layer "F.Cu")
		(net "VDD_IO_4")
	)
	(segment
		(start 94.48419 -108.204)
		(end 94.23019 -107.95)
		(width 0.3048)
		(layer "F.Cu")
		(net "VDD_IO_4")
	)
	(segment
		(start 94.488 -109.0295)
		(end 95.3008 -109.0295)
		(width 0.508)
		(layer "F.Cu")
		(net "VDD_IO_4")
	)
	(segment
		(start 94.488 -94.996)
		(end 94.23019 -95.25381)
		(width 0.3048)
		(layer "F.Cu")
		(net "VDD_IO_4")
	)
	(segment
		(start 94.488 -94.2975)
		(end 95.3008 -94.2975)
		(width 0.508)
		(layer "F.Cu")
		(net "VDD_IO_4")
	)
	(segment
		(start 100.6983 -106.2355)
		(end 99.949 -106.2355)
		(width 0.508)
		(layer "F.Cu")
		(net "VDD_IO_4")
	)
	(segment
		(start 99.949 -106.2355)
		(end 99.949 -107.188)
		(width 0.508)
		(layer "F.Cu")
		(net "VDD_IO_4")
	)
	(segment
		(start 94.488 -94.2975)
		(end 94.488 -94.996)
		(width 0.3048)
		(layer "F.Cu")
		(net "VDD_IO_4")
	)
	(segment
		(start 98.340418 -97.049082)
		(end 98.806 -96.5835)
		(width 0.3048)
		(layer "F.Cu")
		(net "VDD_IO_4")
	)
	(segment
		(start 101.2698 -106.807)
		(end 100.6983 -106.2355)
		(width 0.508)
		(layer "F.Cu")
		(net "VDD_IO_4")
	)
	(segment
		(start 98.806 -96.5835)
		(end 99.949 -96.5835)
		(width 0.3048)
		(layer "F.Cu")
		(net "VDD_IO_4")
	)
	(segment
		(start 94.23019 -107.95)
		(end 94.23019 -106.02341)
		(width 0.3048)
		(layer "F.Cu")
		(net "VDD_IO_4")
	)
	(segment
		(start 94.488 -109.0295)
		(end 94.488 -108.204)
		(width 0.3048)
		(layer "F.Cu")
		(net "VDD_IO_4")
	)
	(segment
		(start 99.949 -106.2355)
		(end 98.9965 -106.2355)
		(width 0.3048)
		(layer "F.Cu")
		(net "VDD_IO_4")
	)
	(segment
		(start 94.23019 -95.25381)
		(end 94.23019 -97.17659)
		(width 0.3048)
		(layer "F.Cu")
		(net "VDD_IO_4")
	)
	(segment
		(start 94.488 -108.204)
		(end 94.48419 -108.204)
		(width 0.3048)
		(layer "F.Cu")
		(net "VDD_IO_4")
	)
	(via
		(at 95.3008 -109.0295)
		(size 0.508)
		(drill 0.254)
		(layers "F.Cu" "B.Cu")
		(net "VDD_IO_4")
	)
	(via
		(at 95.3008 -94.2975)
		(size 0.508)
		(drill 0.254)
		(layers "F.Cu" "B.Cu")
		(net "VDD_IO_4")
	)
	(via
		(at 100.838 -96.5835)
		(size 0.508)
		(drill 0.254)
		(layers "F.Cu" "B.Cu")
		(net "VDD_IO_4")
	)
	(via
		(at 99.949 -107.188)
		(size 0.5588)
		(drill 0.3048)
		(layers "F.Cu" "B.Cu")
		(net "VDD_IO_4")
	)
	(segment
		(start 94.488 -217.424)
		(end 94.48419 -217.424)
		(width 0.3048)
		(layer "F.Cu")
		(net "VDD_IO_3")
	)
	(segment
		(start 93.7895 -204.9145)
		(end 94.23019 -205.35519)
		(width 0.3048)
		(layer "F.Cu")
		(net "VDD_IO_3")
	)
	(segment
		(start 93.1545 -204.9145)
		(end 93.7895 -204.9145)
		(width 0.3048)
		(layer "F.Cu")
		(net "VDD_IO_3")
	)
	(segment
		(start 92.837 -204.1525)
		(end 93.6498 -204.1525)
		(width 0.508)
		(layer "F.Cu")
		(net "VDD_IO_3")
	)
	(segment
		(start 94.488 -217.9955)
		(end 94.488 -217.424)
		(width 0.3048)
		(layer "F.Cu")
		(net "VDD_IO_3")
	)
	(segment
		(start 100.6983 -215.4555)
		(end 99.949 -215.4555)
		(width 0.508)
		(layer "F.Cu")
		(net "VDD_IO_3")
	)
	(segment
		(start 101.2698 -216.027)
		(end 100.6983 -215.4555)
		(width 0.508)
		(layer "F.Cu")
		(net "VDD_IO_3")
	)
	(segment
		(start 92.837 -204.597)
		(end 93.1545 -204.9145)
		(width 0.3048)
		(layer "F.Cu")
		(net "VDD_IO_3")
	)
	(segment
		(start 94.23019 -217.17)
		(end 94.23019 -215.24341)
		(width 0.3048)
		(layer "F.Cu")
		(net "VDD_IO_3")
	)
	(segment
		(start 98.911918 -215.370918)
		(end 97.73031 -215.370918)
		(width 0.3048)
		(layer "F.Cu")
		(net "VDD_IO_3")
	)
	(segment
		(start 94.23019 -205.35519)
		(end 94.23019 -206.39659)
		(width 0.3048)
		(layer "F.Cu")
		(net "VDD_IO_3")
	)
	(segment
		(start 97.73031 -206.269082)
		(end 97.73031 -206.18069)
		(width 0.3048)
		(layer "F.Cu")
		(net "VDD_IO_3")
	)
	(segment
		(start 98.9965 -215.4555)
		(end 98.911918 -215.370918)
		(width 0.3048)
		(layer "F.Cu")
		(net "VDD_IO_3")
	)
	(segment
		(start 98.6155 -205.2955)
		(end 98.6155 -204.851)
		(width 0.3048)
		(layer "F.Cu")
		(net "VDD_IO_3")
	)
	(segment
		(start 92.837 -204.1525)
		(end 92.837 -204.597)
		(width 0.3048)
		(layer "F.Cu")
		(net "VDD_IO_3")
	)
	(segment
		(start 99.949 -215.4555)
		(end 98.9965 -215.4555)
		(width 0.3048)
		(layer "F.Cu")
		(net "VDD_IO_3")
	)
	(segment
		(start 98.6155 -204.851)
		(end 98.6155 -204.0382)
		(width 0.508)
		(layer "F.Cu")
		(net "VDD_IO_3")
	)
	(segment
		(start 94.488 -217.9955)
		(end 95.3008 -217.9955)
		(width 0.508)
		(layer "F.Cu")
		(net "VDD_IO_3")
	)
	(segment
		(start 97.73031 -206.18069)
		(end 98.6155 -205.2955)
		(width 0.3048)
		(layer "F.Cu")
		(net "VDD_IO_3")
	)
	(segment
		(start 94.48419 -217.424)
		(end 94.23019 -217.17)
		(width 0.3048)
		(layer "F.Cu")
		(net "VDD_IO_3")
	)
	(segment
		(start 99.949 -215.4555)
		(end 99.949 -216.408)
		(width 0.508)
		(layer "F.Cu")
		(net "VDD_IO_3")
	)
	(via
		(at 98.6155 -204.0382)
		(size 0.508)
		(drill 0.254)
		(layers "F.Cu" "B.Cu")
		(net "VDD_IO_3")
	)
	(via
		(at 95.3008 -217.9955)
		(size 0.508)
		(drill 0.254)
		(layers "F.Cu" "B.Cu")
		(net "VDD_IO_3")
	)
	(via
		(at 93.6498 -204.1525)
		(size 0.508)
		(drill 0.254)
		(layers "F.Cu" "B.Cu")
		(net "VDD_IO_3")
	)
	(via
		(at 99.949 -216.408)
		(size 0.5588)
		(drill 0.3048)
		(layers "F.Cu" "B.Cu")
		(net "VDD_IO_3")
	)
	(segment
		(start 99.211892 -311.2135)
		(end 97.73031 -309.731918)
		(width 0.3048)
		(layer "F.Cu")
		(net "VDD_IO_2")
	)
	(segment
		(start 97.73031 -300.41469)
		(end 98.9965 -299.1485)
		(width 0.3048)
		(layer "F.Cu")
		(net "VDD_IO_2")
	)
	(segment
		(start 94.23019 -311.531)
		(end 94.23019 -309.60441)
		(width 0.3048)
		(layer "F.Cu")
		(net "VDD_IO_2")
	)
	(segment
		(start 100.301298 -299.1485)
		(end 100.745798 -298.704)
		(width 0.508)
		(layer "F.Cu")
		(net "VDD_IO_2")
	)
	(segment
		(start 94.48419 -311.785)
		(end 94.23019 -311.531)
		(width 0.3048)
		(layer "F.Cu")
		(net "VDD_IO_2")
	)
	(segment
		(start 97.73031 -300.630082)
		(end 97.73031 -300.41469)
		(width 0.3048)
		(layer "F.Cu")
		(net "VDD_IO_2")
	)
	(segment
		(start 99.949 -311.2262)
		(end 101.7778 -313.055)
		(width 0.508)
		(layer "F.Cu")
		(net "VDD_IO_2")
	)
	(segment
		(start 94.23019 -298.39031)
		(end 94.23019 -300.75759)
		(width 0.3048)
		(layer "F.Cu")
		(net "VDD_IO_2")
	)
	(segment
		(start 98.9965 -299.1485)
		(end 99.949 -299.1485)
		(width 0.3048)
		(layer "F.Cu")
		(net "VDD_IO_2")
	)
	(segment
		(start 94.488 -311.785)
		(end 94.48419 -311.785)
		(width 0.3048)
		(layer "F.Cu")
		(net "VDD_IO_2")
	)
	(segment
		(start 99.949 -299.1485)
		(end 100.301298 -299.1485)
		(width 0.508)
		(layer "F.Cu")
		(net "VDD_IO_2")
	)
	(segment
		(start 99.949 -311.2135)
		(end 99.949 -311.2262)
		(width 0.508)
		(layer "F.Cu")
		(net "VDD_IO_2")
	)
	(segment
		(start 94.234 -298.3865)
		(end 94.23019 -298.39031)
		(width 0.3048)
		(layer "F.Cu")
		(net "VDD_IO_2")
	)
	(segment
		(start 94.234 -298.3865)
		(end 95.0468 -298.3865)
		(width 0.508)
		(layer "F.Cu")
		(net "VDD_IO_2")
	)
	(segment
		(start 94.488 -312.3565)
		(end 95.3008 -312.3565)
		(width 0.508)
		(layer "F.Cu")
		(net "VDD_IO_2")
	)
	(segment
		(start 101.7778 -313.055)
		(end 101.7778 -314.325)
		(width 0.508)
		(layer "F.Cu")
		(net "VDD_IO_2")
	)
	(segment
		(start 99.949 -311.2135)
		(end 99.211892 -311.2135)
		(width 0.3048)
		(layer "F.Cu")
		(net "VDD_IO_2")
	)
	(segment
		(start 94.488 -312.3565)
		(end 94.488 -311.785)
		(width 0.3048)
		(layer "F.Cu")
		(net "VDD_IO_2")
	)
	(via
		(at 95.0468 -298.3865)
		(size 0.508)
		(drill 0.254)
		(layers "F.Cu" "B.Cu")
		(net "VDD_IO_2")
	)
	(via
		(at 101.7778 -314.325)
		(size 0.508)
		(drill 0.254)
		(layers "F.Cu" "B.Cu")
		(net "VDD_IO_2")
	)
	(via
		(at 100.745798 -298.704)
		(size 0.5588)
		(drill 0.3048)
		(layers "F.Cu" "B.Cu")
		(net "VDD_IO_2")
	)
	(via
		(at 95.3008 -312.3565)
		(size 0.508)
		(drill 0.254)
		(layers "F.Cu" "B.Cu")
		(net "VDD_IO_2")
	)
	(segment
		(start 95.504 -425.323)
		(end 95.504 -425.1325)
		(width 0.3048)
		(layer "F.Cu")
		(net "VDD_IO_1")
	)
	(segment
		(start 94.615 -438.8485)
		(end 94.615 -438.531)
		(width 0.3048)
		(layer "F.Cu")
		(net "VDD_IO_1")
	)
	(segment
		(start 94.48419 -438.404)
		(end 94.23019 -438.15)
		(width 0.3048)
		(layer "F.Cu")
		(net "VDD_IO_1")
	)
	(segment
		(start 94.615 -438.531)
		(end 94.488 -438.404)
		(width 0.3048)
		(layer "F.Cu")
		(net "VDD_IO_1")
	)
	(segment
		(start 95.504 -425.1325)
		(end 96.393 -425.1325)
		(width 0.508)
		(layer "F.Cu")
		(net "VDD_IO_1")
	)
	(segment
		(start 97.8535 -425.831)
		(end 97.8535 -424.942)
		(width 0.508)
		(layer "F.Cu")
		(net "VDD_IO_1")
	)
	(segment
		(start 97.73031 -436.350918)
		(end 97.73031 -437.39181)
		(width 0.3048)
		(layer "F.Cu")
		(net "VDD_IO_1")
	)
	(segment
		(start 97.73031 -437.39181)
		(end 98.1075 -437.769)
		(width 0.3048)
		(layer "F.Cu")
		(net "VDD_IO_1")
	)
	(segment
		(start 94.23019 -426.59681)
		(end 95.504 -425.323)
		(width 0.3048)
		(layer "F.Cu")
		(net "VDD_IO_1")
	)
	(segment
		(start 98.1075 -437.769)
		(end 98.1075 -438.6453)
		(width 0.508)
		(layer "F.Cu")
		(net "VDD_IO_1")
	)
	(segment
		(start 94.615 -438.8485)
		(end 95.4278 -438.8485)
		(width 0.508)
		(layer "F.Cu")
		(net "VDD_IO_1")
	)
	(segment
		(start 98.552 -439.0898)
		(end 97.282 -439.0898)
		(width 1.016)
		(layer "F.Cu")
		(net "VDD_IO_1")
	)
	(segment
		(start 97.73031 -427.249082)
		(end 97.73031 -425.95419)
		(width 0.3048)
		(layer "F.Cu")
		(net "VDD_IO_1")
	)
	(segment
		(start 94.488 -438.404)
		(end 94.48419 -438.404)
		(width 0.3048)
		(layer "F.Cu")
		(net "VDD_IO_1")
	)
	(segment
		(start 94.23019 -427.37659)
		(end 94.23019 -426.59681)
		(width 0.3048)
		(layer "F.Cu")
		(net "VDD_IO_1")
	)
	(segment
		(start 98.1075 -438.6453)
		(end 98.552 -439.0898)
		(width 0.508)
		(layer "F.Cu")
		(net "VDD_IO_1")
	)
	(segment
		(start 97.73031 -425.95419)
		(end 97.8535 -425.831)
		(width 0.3048)
		(layer "F.Cu")
		(net "VDD_IO_1")
	)
	(segment
		(start 94.23019 -438.15)
		(end 94.23019 -436.22341)
		(width 0.3048)
		(layer "F.Cu")
		(net "VDD_IO_1")
	)
	(via
		(at 95.4278 -438.8485)
		(size 0.508)
		(drill 0.254)
		(layers "F.Cu" "B.Cu")
		(net "VDD_IO_1")
	)
	(via
		(at 96.393 -425.1325)
		(size 0.5588)
		(drill 0.3048)
		(layers "F.Cu" "B.Cu")
		(net "VDD_IO_1")
	)
	(via
		(at 97.8535 -424.942)
		(size 0.508)
		(drill 0.254)
		(layers "F.Cu" "B.Cu")
		(net "VDD_IO_1")
	)
	(via
		(at 97.282 -439.0898)
		(size 0.508)
		(drill 0.254)
		(layers "F.Cu" "B.Cu")
		(net "VDD_IO_1")
	)
	(segment
		(start 32.2072 -41.5798)
		(end 26.423112 -47.363888)
		(width 0.17145)
		(layer "F.Cu")
		(net "ATTN_LED_DR9_N")
	)
	(segment
		(start 13.930884 -54.599332)
		(end 14.351 -55.019448)
		(width 0.17145)
		(layer "F.Cu")
		(net "ATTN_LED_DR9_N")
	)
	(segment
		(start 37.1856 -34.6075)
		(end 33.2105 -34.6075)
		(width 0.17145)
		(layer "F.Cu")
		(net "ATTN_LED_DR9_N")
	)
	(segment
		(start 14.810232 -93.520768)
		(end 14.810232 -65.229232)
		(width 0.17145)
		(layer "F.Cu")
		(net "ATTN_LED_DR9_N")
	)
	(segment
		(start 39.5605 -34.6075)
		(end 40.120062 -35.167062)
		(width 0.17145)
		(layer "F.Cu")
		(net "ATTN_LED_DR9_N")
	)
	(segment
		(start 32.2072 -35.6108)
		(end 32.2072 -41.5798)
		(width 0.17145)
		(layer "F.Cu")
		(net "ATTN_LED_DR9_N")
	)
	(segment
		(start 20.077176 -47.363888)
		(end 19.576288 -46.863)
		(width 0.17145)
		(layer "F.Cu")
		(net "ATTN_LED_DR9_N")
	)
	(segment
		(start 3.250692 -166.34206)
		(end 3.556 -166.036752)
		(width 0.17145)
		(layer "F.Cu")
		(net "ATTN_LED_DR9_N")
	)
	(segment
		(start 15.0876 -46.863)
		(end 13.930884 -48.019716)
		(width 0.17145)
		(layer "F.Cu")
		(net "ATTN_LED_DR9_N")
	)
	(segment
		(start 14.810232 -65.229232)
		(end 14.351 -64.77)
		(width 0.17145)
		(layer "F.Cu")
		(net "ATTN_LED_DR9_N")
	)
	(segment
		(start 19.576288 -46.863)
		(end 15.0876 -46.863)
		(width 0.17145)
		(layer "F.Cu")
		(net "ATTN_LED_DR9_N")
	)
	(segment
		(start 2.249932 -166.34206)
		(end 3.250692 -166.34206)
		(width 0.17145)
		(layer "F.Cu")
		(net "ATTN_LED_DR9_N")
	)
	(segment
		(start 38.241478 -34.6075)
		(end 39.5605 -34.6075)
		(width 0.17145)
		(layer "F.Cu")
		(net "ATTN_LED_DR9_N")
	)
	(segment
		(start 13.930884 -48.019716)
		(end 13.930884 -54.599332)
		(width 0.17145)
		(layer "F.Cu")
		(net "ATTN_LED_DR9_N")
	)
	(segment
		(start 3.556 -166.036752)
		(end 7.191248 -166.036752)
		(width 0.17145)
		(layer "F.Cu")
		(net "ATTN_LED_DR9_N")
	)
	(segment
		(start 33.2105 -34.6075)
		(end 32.2072 -35.6108)
		(width 0.17145)
		(layer "F.Cu")
		(net "ATTN_LED_DR9_N")
	)
	(segment
		(start 26.423112 -47.363888)
		(end 20.077176 -47.363888)
		(width 0.17145)
		(layer "F.Cu")
		(net "ATTN_LED_DR9_N")
	)
	(segment
		(start 40.120062 -35.167062)
		(end 41.377616 -35.167062)
		(width 0.17145)
		(layer "F.Cu")
		(net "ATTN_LED_DR9_N")
	)
	(segment
		(start 14.351 -64.77)
		(end 14.351 -55.019448)
		(width 0.17145)
		(layer "F.Cu")
		(net "ATTN_LED_DR9_N")
	)
	(segment
		(start 37.1856 -34.6075)
		(end 38.241478 -34.6075)
		(width 0.17145)
		(layer "F.Cu")
		(net "ATTN_LED_DR9_N")
	)
	(segment
		(start 9.228074 -163.999926)
		(end 9.228074 -99.102926)
		(width 0.17145)
		(layer "F.Cu")
		(net "ATTN_LED_DR9_N")
	)
	(segment
		(start 9.228074 -99.102926)
		(end 14.810232 -93.520768)
		(width 0.17145)
		(layer "F.Cu")
		(net "ATTN_LED_DR9_N")
	)
	(segment
		(start 7.191248 -166.036752)
		(end 9.228074 -163.999926)
		(width 0.17145)
		(layer "F.Cu")
		(net "ATTN_LED_DR9_N")
	)
	(via
		(at 14.351 -55.019448)
		(size 0.7112)
		(drill 0.3556)
		(layers "F.Cu" "B.Cu")
		(net "ATTN_LED_DR9_N")
	)
	(segment
		(start 38.1 -138.811)
		(end 38.1 -138.3665)
		(width 0.17145)
		(layer "F.Cu")
		(net "ATTN_LED_DR8_N")
	)
	(segment
		(start 39.243 -138.3665)
		(end 40.0685 -138.3665)
		(width 0.17145)
		(layer "F.Cu")
		(net "ATTN_LED_DR8_N")
	)
	(segment
		(start 39.243 -138.3665)
		(end 38.1 -138.3665)
		(width 0.17145)
		(layer "F.Cu")
		(net "ATTN_LED_DR8_N")
	)
	(segment
		(start 38.989 -139.7)
		(end 38.1 -138.811)
		(width 0.17145)
		(layer "F.Cu")
		(net "ATTN_LED_DR8_N")
	)
	(segment
		(start 38.989 -141.4145)
		(end 38.989 -139.7)
		(width 0.17145)
		(layer "F.Cu")
		(net "ATTN_LED_DR8_N")
	)
	(via
		(at 40.0685 -138.3665)
		(size 0.508)
		(drill 0.254)
		(layers "F.Cu" "B.Cu")
		(net "ATTN_LED_DR8_N")
	)
	(via
		(at 11.020298 -204.089)
		(size 0.7112)
		(drill 0.3556)
		(layers "F.Cu" "B.Cu")
		(net "ATTN_LED_DR8_N")
	)
	(segment
		(start 11.020298 -221.668594)
		(end 6.933692 -225.7552)
		(width 0.17145)
		(layer "B.Cu")
		(net "ATTN_LED_DR8_N")
	)
	(segment
		(start 36.4998 -158.5468)
		(end 35.7886 -159.258)
		(width 0.17145)
		(layer "B.Cu")
		(net "ATTN_LED_DR8_N")
	)
	(segment
		(start 11.020298 -199.304402)
		(end 11.020298 -204.089)
		(width 0.17145)
		(layer "B.Cu")
		(net "ATTN_LED_DR8_N")
	)
	(segment
		(start 11.020298 -204.089)
		(end 11.020298 -221.668594)
		(width 0.17145)
		(layer "B.Cu")
		(net "ATTN_LED_DR8_N")
	)
	(segment
		(start 11.590528 -198.734172)
		(end 11.020298 -199.304402)
		(width 0.17145)
		(layer "B.Cu")
		(net "ATTN_LED_DR8_N")
	)
	(segment
		(start 22.072854 -185.21045)
		(end 11.590528 -195.692776)
		(width 0.17145)
		(layer "B.Cu")
		(net "ATTN_LED_DR8_N")
	)
	(segment
		(start 38.989 -147.749768)
		(end 36.4998 -150.238968)
		(width 0.17145)
		(layer "B.Cu")
		(net "ATTN_LED_DR8_N")
	)
	(segment
		(start 36.4998 -150.238968)
		(end 36.4998 -158.5468)
		(width 0.17145)
		(layer "B.Cu")
		(net "ATTN_LED_DR8_N")
	)
	(segment
		(start 11.590528 -195.692776)
		(end 11.590528 -198.734172)
		(width 0.17145)
		(layer "B.Cu")
		(net "ATTN_LED_DR8_N")
	)
	(segment
		(start 37.947854 -185.21045)
		(end 22.072854 -185.21045)
		(width 0.17145)
		(layer "B.Cu")
		(net "ATTN_LED_DR8_N")
	)
	(segment
		(start 41.846246 -181.312058)
		(end 37.947854 -185.21045)
		(width 0.17145)
		(layer "B.Cu")
		(net "ATTN_LED_DR8_N")
	)
	(segment
		(start 3.683 -225.542094)
		(end 1.868932 -225.542094)
		(width 0.17145)
		(layer "B.Cu")
		(net "ATTN_LED_DR8_N")
	)
	(segment
		(start 35.7886 -159.258)
		(end 35.7886 -164.5412)
		(width 0.17145)
		(layer "B.Cu")
		(net "ATTN_LED_DR8_N")
	)
	(segment
		(start 5.0292 -225.7552)
		(end 4.572 -225.298)
		(width 0.17145)
		(layer "B.Cu")
		(net "ATTN_LED_DR8_N")
	)
	(segment
		(start 3.927094 -225.298)
		(end 3.683 -225.542094)
		(width 0.17145)
		(layer "B.Cu")
		(net "ATTN_LED_DR8_N")
	)
	(segment
		(start 4.572 -225.298)
		(end 3.927094 -225.298)
		(width 0.17145)
		(layer "B.Cu")
		(net "ATTN_LED_DR8_N")
	)
	(segment
		(start 6.933692 -225.7552)
		(end 5.0292 -225.7552)
		(width 0.17145)
		(layer "B.Cu")
		(net "ATTN_LED_DR8_N")
	)
	(segment
		(start 40.0685 -138.3665)
		(end 38.989 -139.446)
		(width 0.17145)
		(layer "B.Cu")
		(net "ATTN_LED_DR8_N")
	)
	(segment
		(start 41.846246 -170.598846)
		(end 41.846246 -181.312058)
		(width 0.17145)
		(layer "B.Cu")
		(net "ATTN_LED_DR8_N")
	)
	(segment
		(start 35.7886 -164.5412)
		(end 41.846246 -170.598846)
		(width 0.17145)
		(layer "B.Cu")
		(net "ATTN_LED_DR8_N")
	)
	(segment
		(start 38.989 -139.446)
		(end 38.989 -147.749768)
		(width 0.17145)
		(layer "B.Cu")
		(net "ATTN_LED_DR8_N")
	)
	(segment
		(start 3.410966 -316.342014)
		(end 3.597148 -316.155832)
		(width 0.17145)
		(layer "F.Cu")
		(net "ATTN_LED_DR7_N")
	)
	(segment
		(start 7.8486 -314.8584)
		(end 7.8486 -314.080398)
		(width 0.17145)
		(layer "F.Cu")
		(net "ATTN_LED_DR7_N")
	)
	(segment
		(start 48.387 -242.062)
		(end 48.26 -241.935)
		(width 0.17145)
		(layer "F.Cu")
		(net "ATTN_LED_DR7_N")
	)
	(segment
		(start 51.7779 -244.088158)
		(end 50.3936 -244.088158)
		(width 0.17145)
		(layer "F.Cu")
		(net "ATTN_LED_DR7_N")
	)
	(segment
		(start 50.5206 -245.231158)
		(end 51.7779 -245.231158)
		(width 0.17145)
		(layer "F.Cu")
		(net "ATTN_LED_DR7_N")
	)
	(segment
		(start 49.3268 -242.062)
		(end 48.387 -242.062)
		(width 0.17145)
		(layer "F.Cu")
		(net "ATTN_LED_DR7_N")
	)
	(segment
		(start 7.8486 -314.080398)
		(end 8.371586 -313.557412)
		(width 0.17145)
		(layer "F.Cu")
		(net "ATTN_LED_DR7_N")
	)
	(segment
		(start 51.7779 -244.088158)
		(end 51.7779 -245.231158)
		(width 0.17145)
		(layer "F.Cu")
		(net "ATTN_LED_DR7_N")
	)
	(segment
		(start 3.597148 -316.155832)
		(end 6.551168 -316.155832)
		(width 0.17145)
		(layer "F.Cu")
		(net "ATTN_LED_DR7_N")
	)
	(segment
		(start 50.3936 -244.088158)
		(end 49.657 -243.351558)
		(width 0.17145)
		(layer "F.Cu")
		(net "ATTN_LED_DR7_N")
	)
	(segment
		(start 49.657 -243.351558)
		(end 49.657 -242.3922)
		(width 0.17145)
		(layer "F.Cu")
		(net "ATTN_LED_DR7_N")
	)
	(segment
		(start 2.249932 -316.342014)
		(end 3.410966 -316.342014)
		(width 0.17145)
		(layer "F.Cu")
		(net "ATTN_LED_DR7_N")
	)
	(segment
		(start 48.26 -241.935)
		(end 48.26 -241.2365)
		(width 0.17145)
		(layer "F.Cu")
		(net "ATTN_LED_DR7_N")
	)
	(segment
		(start 6.551168 -316.155832)
		(end 7.8486 -314.8584)
		(width 0.17145)
		(layer "F.Cu")
		(net "ATTN_LED_DR7_N")
	)
	(segment
		(start 49.657 -242.3922)
		(end 49.3268 -242.062)
		(width 0.17145)
		(layer "F.Cu")
		(net "ATTN_LED_DR7_N")
	)
	(via
		(at 50.5206 -245.231158)
		(size 0.508)
		(drill 0.254)
		(layers "F.Cu" "B.Cu")
		(net "ATTN_LED_DR7_N")
	)
	(via
		(at 8.371586 -313.557412)
		(size 0.508)
		(drill 0.254)
		(layers "F.Cu" "B.Cu")
		(net "ATTN_LED_DR7_N")
	)
	(via
		(at 33.528 -264.668)
		(size 0.7112)
		(drill 0.3556)
		(layers "F.Cu" "B.Cu")
		(net "ATTN_LED_DR7_N")
	)
	(segment
		(start 33.528 -267.015214)
		(end 18.095214 -282.448)
		(width 0.17145)
		(layer "B.Cu")
		(net "ATTN_LED_DR7_N")
	)
	(segment
		(start 17.018 -282.448)
		(end 9.25195 -290.21405)
		(width 0.17145)
		(layer "B.Cu")
		(net "ATTN_LED_DR7_N")
	)
	(segment
		(start 41.026842 -245.231158)
		(end 33.528 -252.73)
		(width 0.17145)
		(layer "B.Cu")
		(net "ATTN_LED_DR7_N")
	)
	(segment
		(start 9.25195 -312.677048)
		(end 8.371586 -313.557412)
		(width 0.17145)
		(layer "B.Cu")
		(net "ATTN_LED_DR7_N")
	)
	(segment
		(start 18.095214 -282.448)
		(end 17.018 -282.448)
		(width 0.17145)
		(layer "B.Cu")
		(net "ATTN_LED_DR7_N")
	)
	(segment
		(start 33.528 -264.668)
		(end 33.528 -267.015214)
		(width 0.17145)
		(layer "B.Cu")
		(net "ATTN_LED_DR7_N")
	)
	(segment
		(start 9.25195 -290.21405)
		(end 9.25195 -312.677048)
		(width 0.17145)
		(layer "B.Cu")
		(net "ATTN_LED_DR7_N")
	)
	(segment
		(start 33.528 -252.73)
		(end 33.528 -264.668)
		(width 0.17145)
		(layer "B.Cu")
		(net "ATTN_LED_DR7_N")
	)
	(segment
		(start 50.5206 -245.231158)
		(end 41.026842 -245.231158)
		(width 0.17145)
		(layer "B.Cu")
		(net "ATTN_LED_DR7_N")
	)
	(segment
		(start 40.084756 -343.484708)
		(end 40.513 -343.912952)
		(width 0.17145)
		(layer "F.Cu")
		(net "ATTN_LED_DR6_N")
	)
	(segment
		(start 40.513 -343.912952)
		(end 41.377616 -343.912952)
		(width 0.17145)
		(layer "F.Cu")
		(net "ATTN_LED_DR6_N")
	)
	(segment
		(start 39.296086 -342.341708)
		(end 39.296086 -341.506302)
		(width 0.17145)
		(layer "F.Cu")
		(net "ATTN_LED_DR6_N")
	)
	(segment
		(start 2.249932 -359.54208)
		(end 3.560572 -359.54208)
		(width 0.17145)
		(layer "F.Cu")
		(net "ATTN_LED_DR6_N")
	)
	(segment
		(start 39.296086 -343.484708)
		(end 40.084756 -343.484708)
		(width 0.17145)
		(layer "F.Cu")
		(net "ATTN_LED_DR6_N")
	)
	(segment
		(start 3.560572 -359.54208)
		(end 4.063492 -360.045)
		(width 0.17145)
		(layer "F.Cu")
		(net "ATTN_LED_DR6_N")
	)
	(segment
		(start 4.063492 -360.045)
		(end 6.858 -360.045)
		(width 0.17145)
		(layer "F.Cu")
		(net "ATTN_LED_DR6_N")
	)
	(segment
		(start 39.296086 -343.484708)
		(end 39.296086 -342.341708)
		(width 0.17145)
		(layer "F.Cu")
		(net "ATTN_LED_DR6_N")
	)
	(via
		(at 6.858 -360.045)
		(size 0.508)
		(drill 0.254)
		(layers "F.Cu" "B.Cu")
		(net "ATTN_LED_DR6_N")
	)
	(via
		(at 39.296086 -341.506302)
		(size 0.508)
		(drill 0.254)
		(layers "F.Cu" "B.Cu")
		(net "ATTN_LED_DR6_N")
	)
	(via
		(at 41.275 -350.647)
		(size 0.7112)
		(drill 0.3556)
		(layers "F.Cu" "B.Cu")
		(net "ATTN_LED_DR6_N")
	)
	(segment
		(start 41.275 -350.647)
		(end 41.275 -345.313)
		(width 0.17145)
		(layer "B.Cu")
		(net "ATTN_LED_DR6_N")
	)
	(segment
		(start 6.858 -360.045)
		(end 17.78 -370.967)
		(width 0.17145)
		(layer "B.Cu")
		(net "ATTN_LED_DR6_N")
	)
	(segment
		(start 40.1955 -342.405716)
		(end 39.296086 -341.506302)
		(width 0.17145)
		(layer "B.Cu")
		(net "ATTN_LED_DR6_N")
	)
	(segment
		(start 41.275 -354.965)
		(end 41.275 -350.647)
		(width 0.17145)
		(layer "B.Cu")
		(net "ATTN_LED_DR6_N")
	)
	(segment
		(start 17.78 -370.967)
		(end 25.273 -370.967)
		(width 0.17145)
		(layer "B.Cu")
		(net "ATTN_LED_DR6_N")
	)
	(segment
		(start 40.1955 -344.2335)
		(end 40.1955 -342.405716)
		(width 0.17145)
		(layer "B.Cu")
		(net "ATTN_LED_DR6_N")
	)
	(segment
		(start 41.275 -345.313)
		(end 40.1955 -344.2335)
		(width 0.17145)
		(layer "B.Cu")
		(net "ATTN_LED_DR6_N")
	)
	(segment
		(start 25.273 -370.967)
		(end 41.275 -354.965)
		(width 0.17145)
		(layer "B.Cu")
		(net "ATTN_LED_DR6_N")
	)
	(segment
		(start 54.8513 -451.1548)
		(end 54.8513 -450.1134)
		(width 0.17145)
		(layer "F.Cu")
		(net "ATTN_LED_DR5_N")
	)
	(segment
		(start 54.8513 -451.3707)
		(end 54.8513 -451.1548)
		(width 0.17145)
		(layer "F.Cu")
		(net "ATTN_LED_DR5_N")
	)
	(segment
		(start 40.106092 -452.15683)
		(end 40.106092 -454.188576)
		(width 0.17145)
		(layer "F.Cu")
		(net "ATTN_LED_DR5_N")
	)
	(segment
		(start 41.474136 -455.55662)
		(end 50.66538 -455.55662)
		(width 0.17145)
		(layer "F.Cu")
		(net "ATTN_LED_DR5_N")
	)
	(segment
		(start 52.729384 -450.088)
		(end 54.8259 -450.088)
		(width 0.17145)
		(layer "F.Cu")
		(net "ATTN_LED_DR5_N")
	)
	(segment
		(start 54.8259 -450.088)
		(end 54.8513 -450.1134)
		(width 0.17145)
		(layer "F.Cu")
		(net "ATTN_LED_DR5_N")
	)
	(segment
		(start 40.106092 -454.188576)
		(end 41.474136 -455.55662)
		(width 0.17145)
		(layer "F.Cu")
		(net "ATTN_LED_DR5_N")
	)
	(segment
		(start 50.66538 -455.55662)
		(end 54.8513 -451.3707)
		(width 0.17145)
		(layer "F.Cu")
		(net "ATTN_LED_DR5_N")
	)
	(via
		(at 40.106092 -452.15683)
		(size 0.508)
		(drill 0.254)
		(layers "F.Cu" "B.Cu")
		(net "ATTN_LED_DR5_N")
	)
	(via
		(at 40.1066 -449.707)
		(size 0.7112)
		(drill 0.3556)
		(layers "F.Cu" "B.Cu")
		(net "ATTN_LED_DR5_N")
	)
	(segment
		(start 4.0767 -433.0319)
		(end 3.786632 -432.741832)
		(width 0.17145)
		(layer "B.Cu")
		(net "ATTN_LED_DR5_N")
	)
	(segment
		(start 34.710116 -442.226446)
		(end 25.061926 -442.226446)
		(width 0.17145)
		(layer "B.Cu")
		(net "ATTN_LED_DR5_N")
	)
	(segment
		(start 3.786632 -432.741832)
		(end 1.868932 -432.741832)
		(width 0.17145)
		(layer "B.Cu")
		(net "ATTN_LED_DR5_N")
	)
	(segment
		(start 40.1066 -451.599808)
		(end 40.1066 -449.707)
		(width 0.17145)
		(layer "B.Cu")
		(net "ATTN_LED_DR5_N")
	)
	(segment
		(start 25.061926 -442.226446)
		(end 24.96693 -442.13145)
		(width 0.17145)
		(layer "B.Cu")
		(net "ATTN_LED_DR5_N")
	)
	(segment
		(start 40.1066 -447.62293)
		(end 34.710116 -442.226446)
		(width 0.17145)
		(layer "B.Cu")
		(net "ATTN_LED_DR5_N")
	)
	(segment
		(start 5.2832 -433.705)
		(end 4.6101 -433.0319)
		(width 0.17145)
		(layer "B.Cu")
		(net "ATTN_LED_DR5_N")
	)
	(segment
		(start 21.298154 -442.13145)
		(end 19.396202 -440.229498)
		(width 0.17145)
		(layer "B.Cu")
		(net "ATTN_LED_DR5_N")
	)
	(segment
		(start 5.809996 -433.705)
		(end 5.2832 -433.705)
		(width 0.17145)
		(layer "B.Cu")
		(net "ATTN_LED_DR5_N")
	)
	(segment
		(start 12.334494 -440.229498)
		(end 5.809996 -433.705)
		(width 0.17145)
		(layer "B.Cu")
		(net "ATTN_LED_DR5_N")
	)
	(segment
		(start 40.1066 -449.707)
		(end 40.1066 -447.62293)
		(width 0.17145)
		(layer "B.Cu")
		(net "ATTN_LED_DR5_N")
	)
	(segment
		(start 19.396202 -440.229498)
		(end 12.334494 -440.229498)
		(width 0.17145)
		(layer "B.Cu")
		(net "ATTN_LED_DR5_N")
	)
	(segment
		(start 40.106092 -451.600316)
		(end 40.1066 -451.599808)
		(width 0.17145)
		(layer "B.Cu")
		(net "ATTN_LED_DR5_N")
	)
	(segment
		(start 4.6101 -433.0319)
		(end 4.0767 -433.0319)
		(width 0.17145)
		(layer "B.Cu")
		(net "ATTN_LED_DR5_N")
	)
	(segment
		(start 24.96693 -442.13145)
		(end 21.298154 -442.13145)
		(width 0.17145)
		(layer "B.Cu")
		(net "ATTN_LED_DR5_N")
	)
	(segment
		(start 40.106092 -452.15683)
		(end 40.106092 -451.600316)
		(width 0.17145)
		(layer "B.Cu")
		(net "ATTN_LED_DR5_N")
	)
	(segment
		(start 227.457 -35.209226)
		(end 227.160836 -34.913062)
		(width 0.17145)
		(layer "F.Cu")
		(net "ATTN_LED_DR4_N")
	)
	(segment
		(start 227.160836 -34.913062)
		(end 226.6315 -34.913062)
		(width 0.17145)
		(layer "F.Cu")
		(net "ATTN_LED_DR4_N")
	)
	(segment
		(start 225.9965 -41.67759)
		(end 226.179126 -41.860216)
		(width 0.17145)
		(layer "F.Cu")
		(net "ATTN_LED_DR4_N")
	)
	(segment
		(start 225.9965 -40.894)
		(end 225.9965 -41.67759)
		(width 0.17145)
		(layer "F.Cu")
		(net "ATTN_LED_DR4_N")
	)
	(segment
		(start 227.017072 -36.45027)
		(end 227.457 -36.010342)
		(width 0.17145)
		(layer "F.Cu")
		(net "ATTN_LED_DR4_N")
	)
	(segment
		(start 227.457 -36.010342)
		(end 227.457 -35.209226)
		(width 0.17145)
		(layer "F.Cu")
		(net "ATTN_LED_DR4_N")
	)
	(segment
		(start 225.9965 -37.817044)
		(end 227.017072 -36.796472)
		(width 0.17145)
		(layer "F.Cu")
		(net "ATTN_LED_DR4_N")
	)
	(segment
		(start 227.017072 -36.796472)
		(end 227.017072 -36.45027)
		(width 0.17145)
		(layer "F.Cu")
		(net "ATTN_LED_DR4_N")
	)
	(segment
		(start 225.9965 -39.878)
		(end 225.9965 -37.817044)
		(width 0.17145)
		(layer "F.Cu")
		(net "ATTN_LED_DR4_N")
	)
	(segment
		(start 225.9965 -39.878)
		(end 225.9965 -40.894)
		(width 0.17145)
		(layer "F.Cu")
		(net "ATTN_LED_DR4_N")
	)
	(via
		(at 226.179126 -41.860216)
		(size 0.508)
		(drill 0.254)
		(layers "F.Cu" "B.Cu")
		(net "ATTN_LED_DR4_N")
	)
	(via
		(at 9.398 -193.548)
		(size 0.7112)
		(drill 0.3556)
		(layers "F.Cu" "B.Cu")
		(net "ATTN_LED_DR4_N")
	)
	(segment
		(start 18.57375 -81.965546)
		(end 9.398 -91.141296)
		(width 0.17145)
		(layer "B.Cu")
		(net "ATTN_LED_DR4_N")
	)
	(segment
		(start 3.987038 -197.049898)
		(end 3.494786 -197.54215)
		(width 0.17145)
		(layer "B.Cu")
		(net "ATTN_LED_DR4_N")
	)
	(segment
		(start 5.75945 -198.29145)
		(end 4.517898 -197.049898)
		(width 0.17145)
		(layer "B.Cu")
		(net "ATTN_LED_DR4_N")
	)
	(segment
		(start 226.179126 -41.267126)
		(end 223.3676 -38.4556)
		(width 0.17145)
		(layer "B.Cu")
		(net "ATTN_LED_DR4_N")
	)
	(segment
		(start 4.517898 -197.049898)
		(end 3.987038 -197.049898)
		(width 0.17145)
		(layer "B.Cu")
		(net "ATTN_LED_DR4_N")
	)
	(segment
		(start 25.666954 -65.753742)
		(end 18.57375 -72.846946)
		(width 0.17145)
		(layer "B.Cu")
		(net "ATTN_LED_DR4_N")
	)
	(segment
		(start 29.67355 -55.27675)
		(end 25.666954 -59.283346)
		(width 0.17145)
		(layer "B.Cu")
		(net "ATTN_LED_DR4_N")
	)
	(segment
		(start 18.57375 -72.846946)
		(end 18.57375 -81.965546)
		(width 0.17145)
		(layer "B.Cu")
		(net "ATTN_LED_DR4_N")
	)
	(segment
		(start 7.467854 -198.29145)
		(end 5.75945 -198.29145)
		(width 0.17145)
		(layer "B.Cu")
		(net "ATTN_LED_DR4_N")
	)
	(segment
		(start 226.179126 -41.860216)
		(end 226.179126 -41.267126)
		(width 0.17145)
		(layer "B.Cu")
		(net "ATTN_LED_DR4_N")
	)
	(segment
		(start 9.398 -196.361304)
		(end 7.467854 -198.29145)
		(width 0.17145)
		(layer "B.Cu")
		(net "ATTN_LED_DR4_N")
	)
	(segment
		(start 3.494786 -197.54215)
		(end 1.868932 -197.54215)
		(width 0.17145)
		(layer "B.Cu")
		(net "ATTN_LED_DR4_N")
	)
	(segment
		(start 9.398 -91.141296)
		(end 9.398 -193.548)
		(width 0.17145)
		(layer "B.Cu")
		(net "ATTN_LED_DR4_N")
	)
	(segment
		(start 9.398 -193.548)
		(end 9.398 -196.361304)
		(width 0.17145)
		(layer "B.Cu")
		(net "ATTN_LED_DR4_N")
	)
	(segment
		(start 223.3676 -38.4556)
		(end 204.984096 -38.4556)
		(width 0.17145)
		(layer "B.Cu")
		(net "ATTN_LED_DR4_N")
	)
	(segment
		(start 204.984096 -38.4556)
		(end 199.415146 -44.02455)
		(width 0.17145)
		(layer "B.Cu")
		(net "ATTN_LED_DR4_N")
	)
	(segment
		(start 29.67355 -52.476146)
		(end 29.67355 -55.27675)
		(width 0.17145)
		(layer "B.Cu")
		(net "ATTN_LED_DR4_N")
	)
	(segment
		(start 25.666954 -59.283346)
		(end 25.666954 -65.753742)
		(width 0.17145)
		(layer "B.Cu")
		(net "ATTN_LED_DR4_N")
	)
	(segment
		(start 199.415146 -44.02455)
		(end 38.125146 -44.02455)
		(width 0.17145)
		(layer "B.Cu")
		(net "ATTN_LED_DR4_N")
	)
	(segment
		(start 38.125146 -44.02455)
		(end 29.67355 -52.476146)
		(width 0.17145)
		(layer "B.Cu")
		(net "ATTN_LED_DR4_N")
	)
	(segment
		(start 225.552 -142.42161)
		(end 225.552 -143.2052)
		(width 0.17145)
		(layer "F.Cu")
		(net "ATTN_LED_DR3_N")
	)
	(segment
		(start 225.552 -141.40561)
		(end 225.552 -142.42161)
		(width 0.17145)
		(layer "F.Cu")
		(net "ATTN_LED_DR3_N")
	)
	(segment
		(start 227.203 -139.1412)
		(end 227.203 -138.16711)
		(width 0.17145)
		(layer "F.Cu")
		(net "ATTN_LED_DR3_N")
	)
	(segment
		(start 227.203 -139.1412)
		(end 227.203 -139.188952)
		(width 0.17145)
		(layer "F.Cu")
		(net "ATTN_LED_DR3_N")
	)
	(segment
		(start 225.552 -140.839952)
		(end 225.552 -141.40561)
		(width 0.17145)
		(layer "F.Cu")
		(net "ATTN_LED_DR3_N")
	)
	(segment
		(start 227.203 -138.16711)
		(end 226.949 -137.91311)
		(width 0.17145)
		(layer "F.Cu")
		(net "ATTN_LED_DR3_N")
	)
	(segment
		(start 7.030466 -286.366966)
		(end 4.045966 -286.366966)
		(width 0.17145)
		(layer "F.Cu")
		(net "ATTN_LED_DR3_N")
	)
	(segment
		(start 226.949 -137.91311)
		(end 226.3775 -137.91311)
		(width 0.17145)
		(layer "F.Cu")
		(net "ATTN_LED_DR3_N")
	)
	(segment
		(start 9.23417 -287.251648)
		(end 8.892286 -286.909764)
		(width 0.17145)
		(layer "F.Cu")
		(net "ATTN_LED_DR3_N")
	)
	(segment
		(start 227.203 -139.188952)
		(end 225.552 -140.839952)
		(width 0.17145)
		(layer "F.Cu")
		(net "ATTN_LED_DR3_N")
	)
	(segment
		(start 7.573264 -286.909764)
		(end 7.030466 -286.366966)
		(width 0.17145)
		(layer "F.Cu")
		(net "ATTN_LED_DR3_N")
	)
	(segment
		(start 3.621024 -285.942024)
		(end 2.249932 -285.942024)
		(width 0.17145)
		(layer "F.Cu")
		(net "ATTN_LED_DR3_N")
	)
	(segment
		(start 8.892286 -286.909764)
		(end 7.573264 -286.909764)
		(width 0.17145)
		(layer "F.Cu")
		(net "ATTN_LED_DR3_N")
	)
	(segment
		(start 4.045966 -286.366966)
		(end 3.621024 -285.942024)
		(width 0.17145)
		(layer "F.Cu")
		(net "ATTN_LED_DR3_N")
	)
	(segment
		(start 9.498584 -287.251648)
		(end 9.23417 -287.251648)
		(width 0.17145)
		(layer "F.Cu")
		(net "ATTN_LED_DR3_N")
	)
	(segment
		(start 225.552 -143.2052)
		(end 225.734626 -143.387826)
		(width 0.17145)
		(layer "F.Cu")
		(net "ATTN_LED_DR3_N")
	)
	(via
		(at 39.878 -243.205)
		(size 0.508)
		(drill 0.254)
		(layers "F.Cu" "B.Cu")
		(net "ATTN_LED_DR3_N")
	)
	(via
		(at 225.734626 -143.387826)
		(size 0.508)
		(drill 0.254)
		(layers "F.Cu" "B.Cu")
		(net "ATTN_LED_DR3_N")
	)
	(via
		(at 9.498584 -287.251648)
		(size 0.508)
		(drill 0.254)
		(layers "F.Cu" "B.Cu")
		(net "ATTN_LED_DR3_N")
	)
	(via
		(at 37.592 -245.491)
		(size 0.7112)
		(drill 0.3556)
		(layers "F.Cu" "B.Cu")
		(net "ATTN_LED_DR3_N")
	)
	(segment
		(start 39.878 -243.205)
		(end 37.592 -245.491)
		(width 0.17145)
		(layer "B.Cu")
		(net "ATTN_LED_DR3_N")
	)
	(segment
		(start 9.498584 -287.251648)
		(end 10.646664 -287.251648)
		(width 0.17145)
		(layer "B.Cu")
		(net "ATTN_LED_DR3_N")
	)
	(segment
		(start 10.646664 -287.251648)
		(end 31.9532 -265.945112)
		(width 0.17145)
		(layer "B.Cu")
		(net "ATTN_LED_DR3_N")
	)
	(segment
		(start 31.9532 -265.945112)
		(end 31.9532 -251.1298)
		(width 0.17145)
		(layer "B.Cu")
		(net "ATTN_LED_DR3_N")
	)
	(segment
		(start 31.9532 -251.1298)
		(end 37.592 -245.491)
		(width 0.17145)
		(layer "B.Cu")
		(net "ATTN_LED_DR3_N")
	)
	(segment
		(start 110.363 -207.772)
		(end 112.776 -205.359)
		(width 0.1524)
		(layer "In5.Cu")
		(net "ATTN_LED_DR3_N")
	)
	(segment
		(start 99.24796 -228.6508)
		(end 110.363 -217.53576)
		(width 0.1524)
		(layer "In5.Cu")
		(net "ATTN_LED_DR3_N")
	)
	(segment
		(start 39.878 -243.205)
		(end 43.27652 -243.205)
		(width 0.1524)
		(layer "In5.Cu")
		(net "ATTN_LED_DR3_N")
	)
	(segment
		(start 112.776 -205.359)
		(end 136.9314 -205.359)
		(width 0.1524)
		(layer "In5.Cu")
		(net "ATTN_LED_DR3_N")
	)
	(segment
		(start 143.9164 -212.344)
		(end 199.898 -212.344)
		(width 0.1524)
		(layer "In5.Cu")
		(net "ATTN_LED_DR3_N")
	)
	(segment
		(start 226.441 -185.801)
		(end 226.441 -174.879)
		(width 0.1524)
		(layer "In5.Cu")
		(net "ATTN_LED_DR3_N")
	)
	(segment
		(start 231.648 -148.36521)
		(end 226.670616 -143.387826)
		(width 0.1524)
		(layer "In5.Cu")
		(net "ATTN_LED_DR3_N")
	)
	(segment
		(start 43.27652 -243.205)
		(end 57.83072 -228.6508)
		(width 0.1524)
		(layer "In5.Cu")
		(net "ATTN_LED_DR3_N")
	)
	(segment
		(start 226.441 -174.879)
		(end 231.648 -169.672)
		(width 0.1524)
		(layer "In5.Cu")
		(net "ATTN_LED_DR3_N")
	)
	(segment
		(start 226.670616 -143.387826)
		(end 225.734626 -143.387826)
		(width 0.1524)
		(layer "In5.Cu")
		(net "ATTN_LED_DR3_N")
	)
	(segment
		(start 231.648 -169.672)
		(end 231.648 -148.36521)
		(width 0.1524)
		(layer "In5.Cu")
		(net "ATTN_LED_DR3_N")
	)
	(segment
		(start 110.363 -217.53576)
		(end 110.363 -207.772)
		(width 0.1524)
		(layer "In5.Cu")
		(net "ATTN_LED_DR3_N")
	)
	(segment
		(start 136.9314 -205.359)
		(end 143.9164 -212.344)
		(width 0.1524)
		(layer "In5.Cu")
		(net "ATTN_LED_DR3_N")
	)
	(segment
		(start 199.898 -212.344)
		(end 226.441 -185.801)
		(width 0.1524)
		(layer "In5.Cu")
		(net "ATTN_LED_DR3_N")
	)
	(segment
		(start 57.83072 -228.6508)
		(end 99.24796 -228.6508)
		(width 0.1524)
		(layer "In5.Cu")
		(net "ATTN_LED_DR3_N")
	)
	(segment
		(start 225.552 -245.421658)
		(end 225.552 -244.405658)
		(width 0.17145)
		(layer "F.Cu")
		(net "ATTN_LED_DR2_N")
	)
	(segment
		(start 7.046214 -332.043786)
		(end 7.62 -331.47)
		(width 0.17145)
		(layer "F.Cu")
		(net "ATTN_LED_DR2_N")
	)
	(segment
		(start 226.3775 -240.913158)
		(end 226.949 -240.913158)
		(width 0.17145)
		(layer "F.Cu")
		(net "ATTN_LED_DR2_N")
	)
	(segment
		(start 3.30835 -331.542136)
		(end 3.81 -332.043786)
		(width 0.17145)
		(layer "F.Cu")
		(net "ATTN_LED_DR2_N")
	)
	(segment
		(start 227.203 -241.167158)
		(end 227.203 -242.189)
		(width 0.17145)
		(layer "F.Cu")
		(net "ATTN_LED_DR2_N")
	)
	(segment
		(start 2.249932 -331.542136)
		(end 3.30835 -331.542136)
		(width 0.17145)
		(layer "F.Cu")
		(net "ATTN_LED_DR2_N")
	)
	(segment
		(start 225.552 -243.84)
		(end 226.1997 -243.1923)
		(width 0.17145)
		(layer "F.Cu")
		(net "ATTN_LED_DR2_N")
	)
	(segment
		(start 225.552 -244.405658)
		(end 225.552 -243.84)
		(width 0.17145)
		(layer "F.Cu")
		(net "ATTN_LED_DR2_N")
	)
	(segment
		(start 3.81 -332.043786)
		(end 7.046214 -332.043786)
		(width 0.17145)
		(layer "F.Cu")
		(net "ATTN_LED_DR2_N")
	)
	(segment
		(start 225.552 -246.205248)
		(end 225.734626 -246.387874)
		(width 0.17145)
		(layer "F.Cu")
		(net "ATTN_LED_DR2_N")
	)
	(segment
		(start 225.552 -245.421658)
		(end 225.552 -246.205248)
		(width 0.17145)
		(layer "F.Cu")
		(net "ATTN_LED_DR2_N")
	)
	(segment
		(start 227.203 -242.189)
		(end 226.1997 -243.1923)
		(width 0.17145)
		(layer "F.Cu")
		(net "ATTN_LED_DR2_N")
	)
	(segment
		(start 226.949 -240.913158)
		(end 227.203 -241.167158)
		(width 0.17145)
		(layer "F.Cu")
		(net "ATTN_LED_DR2_N")
	)
	(via
		(at 225.734626 -246.387874)
		(size 0.508)
		(drill 0.254)
		(layers "F.Cu" "B.Cu")
		(net "ATTN_LED_DR2_N")
	)
	(via
		(at 226.1997 -243.1923)
		(size 0.7112)
		(drill 0.3556)
		(layers "F.Cu" "B.Cu")
		(net "ATTN_LED_DR2_N")
	)
	(via
		(at 7.62 -331.47)
		(size 0.508)
		(drill 0.254)
		(layers "F.Cu" "B.Cu")
		(net "ATTN_LED_DR2_N")
	)
	(segment
		(start 73.377806 -291.6428)
		(end 94.12732 -291.6428)
		(width 0.1524)
		(layer "In5.Cu")
		(net "ATTN_LED_DR2_N")
	)
	(segment
		(start 57.43702 -300.8376)
		(end 64.18326 -300.8376)
		(width 0.1524)
		(layer "In5.Cu")
		(net "ATTN_LED_DR2_N")
	)
	(segment
		(start 25.54986 -314.579)
		(end 43.69562 -314.579)
		(width 0.1524)
		(layer "In5.Cu")
		(net "ATTN_LED_DR2_N")
	)
	(segment
		(start 8.853424 -331.275436)
		(end 25.54986 -314.579)
		(width 0.1524)
		(layer "In5.Cu")
		(net "ATTN_LED_DR2_N")
	)
	(segment
		(start 219.202 -288.671)
		(end 222.504 -288.671)
		(width 0.1524)
		(layer "In5.Cu")
		(net "ATTN_LED_DR2_N")
	)
	(segment
		(start 222.504 -288.671)
		(end 223.5708 -287.6042)
		(width 0.1524)
		(layer "In5.Cu")
		(net "ATTN_LED_DR2_N")
	)
	(segment
		(start 7.62 -331.47)
		(end 7.814564 -331.275436)
		(width 0.1524)
		(layer "In5.Cu")
		(net "ATTN_LED_DR2_N")
	)
	(segment
		(start 217.6018 -290.2712)
		(end 219.202 -288.671)
		(width 0.1524)
		(layer "In5.Cu")
		(net "ATTN_LED_DR2_N")
	)
	(segment
		(start 223.5708 -256.413)
		(end 222.8342 -255.6764)
		(width 0.1524)
		(layer "In5.Cu")
		(net "ATTN_LED_DR2_N")
	)
	(segment
		(start 72.75322 -292.267386)
		(end 73.377806 -291.6428)
		(width 0.1524)
		(layer "In5.Cu")
		(net "ATTN_LED_DR2_N")
	)
	(segment
		(start 223.5708 -287.6042)
		(end 223.5708 -256.413)
		(width 0.1524)
		(layer "In5.Cu")
		(net "ATTN_LED_DR2_N")
	)
	(segment
		(start 222.8342 -255.6764)
		(end 222.8342 -249.2883)
		(width 0.1524)
		(layer "In5.Cu")
		(net "ATTN_LED_DR2_N")
	)
	(segment
		(start 64.18326 -300.8376)
		(end 72.75322 -292.26764)
		(width 0.1524)
		(layer "In5.Cu")
		(net "ATTN_LED_DR2_N")
	)
	(segment
		(start 95.49892 -290.2712)
		(end 217.6018 -290.2712)
		(width 0.1524)
		(layer "In5.Cu")
		(net "ATTN_LED_DR2_N")
	)
	(segment
		(start 72.75322 -292.26764)
		(end 72.75322 -292.267386)
		(width 0.1524)
		(layer "In5.Cu")
		(net "ATTN_LED_DR2_N")
	)
	(segment
		(start 94.12732 -291.6428)
		(end 95.49892 -290.2712)
		(width 0.1524)
		(layer "In5.Cu")
		(net "ATTN_LED_DR2_N")
	)
	(segment
		(start 222.8342 -249.2883)
		(end 225.734626 -246.387874)
		(width 0.1524)
		(layer "In5.Cu")
		(net "ATTN_LED_DR2_N")
	)
	(segment
		(start 7.814564 -331.275436)
		(end 8.853424 -331.275436)
		(width 0.1524)
		(layer "In5.Cu")
		(net "ATTN_LED_DR2_N")
	)
	(segment
		(start 43.69562 -314.579)
		(end 57.43702 -300.8376)
		(width 0.1524)
		(layer "In5.Cu")
		(net "ATTN_LED_DR2_N")
	)
	(segment
		(start 23.756366 -59.55411)
		(end 23.995126 -59.79287)
		(width 0.17145)
		(layer "F.Cu")
		(net "ATTN_LED_DR14_N")
	)
	(segment
		(start 22.247606 -59.55411)
		(end 23.756366 -59.55411)
		(width 0.17145)
		(layer "F.Cu")
		(net "ATTN_LED_DR14_N")
	)
	(segment
		(start 21.231606 -59.55411)
		(end 20.3962 -59.55411)
		(width 0.17145)
		(layer "F.Cu")
		(net "ATTN_LED_DR14_N")
	)
	(segment
		(start 23.995126 -61.893196)
		(end 24.185372 -62.083442)
		(width 0.17145)
		(layer "F.Cu")
		(net "ATTN_LED_DR14_N")
	)
	(segment
		(start 23.995126 -59.79287)
		(end 23.995126 -61.893196)
		(width 0.17145)
		(layer "F.Cu")
		(net "ATTN_LED_DR14_N")
	)
	(segment
		(start 22.247606 -59.55411)
		(end 21.231606 -59.55411)
		(width 0.17145)
		(layer "F.Cu")
		(net "ATTN_LED_DR14_N")
	)
	(segment
		(start 24.185372 -62.083442)
		(end 24.823674 -62.083442)
		(width 0.17145)
		(layer "F.Cu")
		(net "ATTN_LED_DR14_N")
	)
	(via
		(at 20.3962 -59.55411)
		(size 0.508)
		(drill 0.254)
		(layers "F.Cu" "B.Cu")
		(net "ATTN_LED_DR14_N")
	)
	(via
		(at 18.7706 -68.453)
		(size 0.7112)
		(drill 0.3556)
		(layers "F.Cu" "B.Cu")
		(net "ATTN_LED_DR14_N")
	)
	(segment
		(start 5.715 -91.393518)
		(end 5.715 -149.479)
		(width 0.17145)
		(layer "B.Cu")
		(net "ATTN_LED_DR14_N")
	)
	(segment
		(start 22.8854 -64.3382)
		(end 18.7706 -68.453)
		(width 0.17145)
		(layer "B.Cu")
		(net "ATTN_LED_DR14_N")
	)
	(segment
		(start 5.715 -149.479)
		(end 3.251962 -151.942038)
		(width 0.17145)
		(layer "B.Cu")
		(net "ATTN_LED_DR14_N")
	)
	(segment
		(start 22.503384 -59.55411)
		(end 22.8854 -59.936126)
		(width 0.17145)
		(layer "B.Cu")
		(net "ATTN_LED_DR14_N")
	)
	(segment
		(start 3.251962 -151.942038)
		(end 1.868932 -151.942038)
		(width 0.17145)
		(layer "B.Cu")
		(net "ATTN_LED_DR14_N")
	)
	(segment
		(start 20.3962 -59.55411)
		(end 22.503384 -59.55411)
		(width 0.17145)
		(layer "B.Cu")
		(net "ATTN_LED_DR14_N")
	)
	(segment
		(start 18.7706 -68.453)
		(end 15.2527 -71.9709)
		(width 0.17145)
		(layer "B.Cu")
		(net "ATTN_LED_DR14_N")
	)
	(segment
		(start 15.2527 -71.9709)
		(end 15.2527 -81.855818)
		(width 0.17145)
		(layer "B.Cu")
		(net "ATTN_LED_DR14_N")
	)
	(segment
		(start 22.8854 -59.936126)
		(end 22.8854 -64.3382)
		(width 0.17145)
		(layer "B.Cu")
		(net "ATTN_LED_DR14_N")
	)
	(segment
		(start 15.2527 -81.855818)
		(end 5.715 -91.393518)
		(width 0.17145)
		(layer "B.Cu")
		(net "ATTN_LED_DR14_N")
	)
	(segment
		(start 21.231606 -162.554158)
		(end 22.247606 -162.554158)
		(width 0.17145)
		(layer "F.Cu")
		(net "ATTN_LED_DR13_N")
	)
	(segment
		(start 7.02945 -198.41845)
		(end 11.874754 -193.573146)
		(width 0.17145)
		(layer "F.Cu")
		(net "ATTN_LED_DR13_N")
	)
	(segment
		(start 24.000968 -162.808158)
		(end 24.000968 -164.838126)
		(width 0.17145)
		(layer "F.Cu")
		(net "ATTN_LED_DR13_N")
	)
	(segment
		(start 2.249932 -199.142096)
		(end 3.295904 -199.142096)
		(width 0.17145)
		(layer "F.Cu")
		(net "ATTN_LED_DR13_N")
	)
	(segment
		(start 11.874754 -184.828942)
		(end 12.065 -184.638696)
		(width 0.17145)
		(layer "F.Cu")
		(net "ATTN_LED_DR13_N")
	)
	(segment
		(start 24.000968 -164.838126)
		(end 24.246332 -165.08349)
		(width 0.17145)
		(layer "F.Cu")
		(net "ATTN_LED_DR13_N")
	)
	(segment
		(start 24.246332 -165.08349)
		(end 24.823674 -165.08349)
		(width 0.17145)
		(layer "F.Cu")
		(net "ATTN_LED_DR13_N")
	)
	(segment
		(start 12.065 -184.638696)
		(end 12.065 -167.767)
		(width 0.17145)
		(layer "F.Cu")
		(net "ATTN_LED_DR13_N")
	)
	(segment
		(start 22.247606 -162.554158)
		(end 23.746968 -162.554158)
		(width 0.17145)
		(layer "F.Cu")
		(net "ATTN_LED_DR13_N")
	)
	(segment
		(start 11.874754 -193.573146)
		(end 11.874754 -184.828942)
		(width 0.17145)
		(layer "F.Cu")
		(net "ATTN_LED_DR13_N")
	)
	(segment
		(start 4.01955 -198.41845)
		(end 7.02945 -198.41845)
		(width 0.17145)
		(layer "F.Cu")
		(net "ATTN_LED_DR13_N")
	)
	(segment
		(start 3.295904 -199.142096)
		(end 4.01955 -198.41845)
		(width 0.17145)
		(layer "F.Cu")
		(net "ATTN_LED_DR13_N")
	)
	(segment
		(start 21.231606 -162.554158)
		(end 20.3962 -162.554158)
		(width 0.17145)
		(layer "F.Cu")
		(net "ATTN_LED_DR13_N")
	)
	(segment
		(start 23.746968 -162.554158)
		(end 24.000968 -162.808158)
		(width 0.17145)
		(layer "F.Cu")
		(net "ATTN_LED_DR13_N")
	)
	(via
		(at 12.065 -167.767)
		(size 0.5588)
		(drill 0.3048)
		(layers "F.Cu" "B.Cu")
		(net "ATTN_LED_DR13_N")
	)
	(via
		(at 20.3962 -162.554158)
		(size 0.508)
		(drill 0.254)
		(layers "F.Cu" "B.Cu")
		(net "ATTN_LED_DR13_N")
	)
	(segment
		(start 18.917158 -166.6494)
		(end 14.478 -166.6494)
		(width 0.1524)
		(layer "In5.Cu")
		(net "ATTN_LED_DR13_N")
	)
	(segment
		(start 19.885152 -165.681406)
		(end 18.917158 -166.6494)
		(width 0.1524)
		(layer "In5.Cu")
		(net "ATTN_LED_DR13_N")
	)
	(segment
		(start 20.3962 -162.554158)
		(end 19.885152 -163.065206)
		(width 0.1524)
		(layer "In5.Cu")
		(net "ATTN_LED_DR13_N")
	)
	(segment
		(start 14.478 -166.6494)
		(end 13.3604 -167.767)
		(width 0.1524)
		(layer "In5.Cu")
		(net "ATTN_LED_DR13_N")
	)
	(segment
		(start 19.885152 -163.065206)
		(end 19.885152 -165.681406)
		(width 0.1524)
		(layer "In5.Cu")
		(net "ATTN_LED_DR13_N")
	)
	(segment
		(start 13.3604 -167.767)
		(end 12.065 -167.767)
		(width 0.1524)
		(layer "In5.Cu")
		(net "ATTN_LED_DR13_N")
	)
	(segment
		(start 24.000968 -266.189968)
		(end 24.000968 -267.917168)
		(width 0.17145)
		(layer "F.Cu")
		(net "ATTN_LED_DR12_N")
	)
	(segment
		(start 23.5585 -265.7475)
		(end 24.000968 -266.189968)
		(width 0.17145)
		(layer "F.Cu")
		(net "ATTN_LED_DR12_N")
	)
	(segment
		(start 24.167084 -268.083284)
		(end 24.823674 -268.083284)
		(width 0.17145)
		(layer "F.Cu")
		(net "ATTN_LED_DR12_N")
	)
	(segment
		(start 20.749006 -266.334494)
		(end 21.336 -265.7475)
		(width 0.17145)
		(layer "F.Cu")
		(net "ATTN_LED_DR12_N")
	)
	(segment
		(start 20.749006 -266.5476)
		(end 20.749006 -266.334494)
		(width 0.17145)
		(layer "F.Cu")
		(net "ATTN_LED_DR12_N")
	)
	(segment
		(start 24.000968 -267.917168)
		(end 24.167084 -268.083284)
		(width 0.17145)
		(layer "F.Cu")
		(net "ATTN_LED_DR12_N")
	)
	(segment
		(start 22.352 -265.7475)
		(end 23.5585 -265.7475)
		(width 0.17145)
		(layer "F.Cu")
		(net "ATTN_LED_DR12_N")
	)
	(segment
		(start 21.336 -265.7475)
		(end 22.352 -265.7475)
		(width 0.17145)
		(layer "F.Cu")
		(net "ATTN_LED_DR12_N")
	)
	(via
		(at 20.749006 -266.5476)
		(size 0.508)
		(drill 0.254)
		(layers "F.Cu" "B.Cu")
		(net "ATTN_LED_DR12_N")
	)
	(via
		(at 20.61845 -270.866616)
		(size 0.7112)
		(drill 0.3556)
		(layers "F.Cu" "B.Cu")
		(net "ATTN_LED_DR12_N")
	)
	(segment
		(start 20.61845 -270.866616)
		(end 20.61845 -274.134834)
		(width 0.17145)
		(layer "B.Cu")
		(net "ATTN_LED_DR12_N")
	)
	(segment
		(start 8.401558 -286.351726)
		(end 6.32714 -286.351726)
		(width 0.17145)
		(layer "B.Cu")
		(net "ATTN_LED_DR12_N")
	)
	(segment
		(start 20.61845 -274.134834)
		(end 8.401558 -286.351726)
		(width 0.17145)
		(layer "B.Cu")
		(net "ATTN_LED_DR12_N")
	)
	(segment
		(start 6.32714 -286.351726)
		(end 5.531866 -287.147)
		(width 0.17145)
		(layer "B.Cu")
		(net "ATTN_LED_DR12_N")
	)
	(segment
		(start 3.81 -287.147)
		(end 3.414776 -287.542224)
		(width 0.17145)
		(layer "B.Cu")
		(net "ATTN_LED_DR12_N")
	)
	(segment
		(start 20.749006 -266.5476)
		(end 20.61845 -266.678156)
		(width 0.17145)
		(layer "B.Cu")
		(net "ATTN_LED_DR12_N")
	)
	(segment
		(start 20.61845 -266.678156)
		(end 20.61845 -270.866616)
		(width 0.17145)
		(layer "B.Cu")
		(net "ATTN_LED_DR12_N")
	)
	(segment
		(start 5.531866 -287.147)
		(end 3.81 -287.147)
		(width 0.17145)
		(layer "B.Cu")
		(net "ATTN_LED_DR12_N")
	)
	(segment
		(start 3.414776 -287.542224)
		(end 1.868932 -287.542224)
		(width 0.17145)
		(layer "B.Cu")
		(net "ATTN_LED_DR12_N")
	)
	(segment
		(start 21.231606 -368.554)
		(end 20.3962 -368.554)
		(width 0.17145)
		(layer "F.Cu")
		(net "ATTN_LED_DR11_N")
	)
	(segment
		(start 22.247606 -368.554)
		(end 23.746968 -368.554)
		(width 0.17145)
		(layer "F.Cu")
		(net "ATTN_LED_DR11_N")
	)
	(segment
		(start 24.000968 -368.808)
		(end 24.000968 -370.837968)
		(width 0.17145)
		(layer "F.Cu")
		(net "ATTN_LED_DR11_N")
	)
	(segment
		(start 21.231606 -368.554)
		(end 22.247606 -368.554)
		(width 0.17145)
		(layer "F.Cu")
		(net "ATTN_LED_DR11_N")
	)
	(segment
		(start 24.246332 -371.083332)
		(end 24.823674 -371.083332)
		(width 0.17145)
		(layer "F.Cu")
		(net "ATTN_LED_DR11_N")
	)
	(segment
		(start 23.746968 -368.554)
		(end 24.000968 -368.808)
		(width 0.17145)
		(layer "F.Cu")
		(net "ATTN_LED_DR11_N")
	)
	(segment
		(start 24.000968 -370.837968)
		(end 24.246332 -371.083332)
		(width 0.17145)
		(layer "F.Cu")
		(net "ATTN_LED_DR11_N")
	)
	(via
		(at 16.51 -339.344)
		(size 0.7112)
		(drill 0.3556)
		(layers "F.Cu" "B.Cu")
		(net "ATTN_LED_DR11_N")
	)
	(via
		(at 20.3962 -368.554)
		(size 0.508)
		(drill 0.254)
		(layers "F.Cu" "B.Cu")
		(net "ATTN_LED_DR11_N")
	)
	(segment
		(start 1.868932 -333.142082)
		(end 3.348482 -333.142082)
		(width 0.17145)
		(layer "B.Cu")
		(net "ATTN_LED_DR11_N")
	)
	(segment
		(start 3.348482 -333.142082)
		(end 3.8608 -333.6544)
		(width 0.17145)
		(layer "B.Cu")
		(net "ATTN_LED_DR11_N")
	)
	(segment
		(start 7.112 -332.4098)
		(end 8.66775 -333.96555)
		(width 0.17145)
		(layer "B.Cu")
		(net "ATTN_LED_DR11_N")
	)
	(segment
		(start 17.7546 -338.0994)
		(end 16.51 -339.344)
		(width 0.17145)
		(layer "B.Cu")
		(net "ATTN_LED_DR11_N")
	)
	(segment
		(start 14.478 -341.376)
		(end 16.51 -339.344)
		(width 0.17145)
		(layer "B.Cu")
		(net "ATTN_LED_DR11_N")
	)
	(segment
		(start 20.720812 -368.526822)
		(end 21.360638 -367.886996)
		(width 0.17145)
		(layer "B.Cu")
		(net "ATTN_LED_DR11_N")
	)
	(segment
		(start 20.423378 -368.526822)
		(end 20.720812 -368.526822)
		(width 0.17145)
		(layer "B.Cu")
		(net "ATTN_LED_DR11_N")
	)
	(segment
		(start 20.3962 -368.554)
		(end 20.423378 -368.526822)
		(width 0.17145)
		(layer "B.Cu")
		(net "ATTN_LED_DR11_N")
	)
	(segment
		(start 4.4196 -333.6544)
		(end 5.6642 -332.4098)
		(width 0.17145)
		(layer "B.Cu")
		(net "ATTN_LED_DR11_N")
	)
	(segment
		(start 5.6642 -332.4098)
		(end 7.112 -332.4098)
		(width 0.17145)
		(layer "B.Cu")
		(net "ATTN_LED_DR11_N")
	)
	(segment
		(start 3.8608 -333.6544)
		(end 4.4196 -333.6544)
		(width 0.17145)
		(layer "B.Cu")
		(net "ATTN_LED_DR11_N")
	)
	(segment
		(start 14.478 -358.376474)
		(end 14.478 -341.376)
		(width 0.17145)
		(layer "B.Cu")
		(net "ATTN_LED_DR11_N")
	)
	(segment
		(start 21.360638 -367.886996)
		(end 21.360638 -365.259112)
		(width 0.17145)
		(layer "B.Cu")
		(net "ATTN_LED_DR11_N")
	)
	(segment
		(start 16.64335 -333.96555)
		(end 17.7546 -335.0768)
		(width 0.17145)
		(layer "B.Cu")
		(net "ATTN_LED_DR11_N")
	)
	(segment
		(start 21.360638 -365.259112)
		(end 14.478 -358.376474)
		(width 0.17145)
		(layer "B.Cu")
		(net "ATTN_LED_DR11_N")
	)
	(segment
		(start 17.7546 -335.0768)
		(end 17.7546 -338.0994)
		(width 0.17145)
		(layer "B.Cu")
		(net "ATTN_LED_DR11_N")
	)
	(segment
		(start 8.66775 -333.96555)
		(end 16.64335 -333.96555)
		(width 0.17145)
		(layer "B.Cu")
		(net "ATTN_LED_DR11_N")
	)
	(segment
		(start 22.3139 -465.9122)
		(end 22.6441 -465.582)
		(width 0.17145)
		(layer "F.Cu")
		(net "ATTN_LED_DR10_N")
	)
	(segment
		(start 26.3906 -465.0994)
		(end 26.3906 -462.3308)
		(width 0.17145)
		(layer "F.Cu")
		(net "ATTN_LED_DR10_N")
	)
	(segment
		(start 22.3139 -468.116158)
		(end 22.4028 -468.205058)
		(width 0.17145)
		(layer "F.Cu")
		(net "ATTN_LED_DR10_N")
	)
	(segment
		(start 22.3139 -467.5124)
		(end 22.3139 -466.4202)
		(width 0.17145)
		(layer "F.Cu")
		(net "ATTN_LED_DR10_N")
	)
	(segment
		(start 17.887696 -456.2348)
		(end 15.2781 -453.625204)
		(width 0.17145)
		(layer "F.Cu")
		(net "ATTN_LED_DR10_N")
	)
	(segment
		(start 22.3139 -466.4202)
		(end 22.3139 -465.9122)
		(width 0.17145)
		(layer "F.Cu")
		(net "ATTN_LED_DR10_N")
	)
	(segment
		(start 22.6441 -465.582)
		(end 25.908 -465.582)
		(width 0.17145)
		(layer "F.Cu")
		(net "ATTN_LED_DR10_N")
	)
	(segment
		(start 18.8214 -456.2348)
		(end 17.887696 -456.2348)
		(width 0.17145)
		(layer "F.Cu")
		(net "ATTN_LED_DR10_N")
	)
	(segment
		(start 15.2781 -453.625204)
		(end 15.2781 -435.1401)
		(width 0.17145)
		(layer "F.Cu")
		(net "ATTN_LED_DR10_N")
	)
	(segment
		(start 26.3906 -462.3308)
		(end 25.781 -461.7212)
		(width 0.17145)
		(layer "F.Cu")
		(net "ATTN_LED_DR10_N")
	)
	(segment
		(start 15.2781 -435.1401)
		(end 16.8656 -433.5526)
		(width 0.17145)
		(layer "F.Cu")
		(net "ATTN_LED_DR10_N")
	)
	(segment
		(start 22.4028 -468.205058)
		(end 22.4028 -469.1761)
		(width 0.17145)
		(layer "F.Cu")
		(net "ATTN_LED_DR10_N")
	)
	(segment
		(start 25.781 -461.7212)
		(end 21.7678 -461.7212)
		(width 0.17145)
		(layer "F.Cu")
		(net "ATTN_LED_DR10_N")
	)
	(segment
		(start 22.3139 -467.5124)
		(end 22.3139 -468.116158)
		(width 0.17145)
		(layer "F.Cu")
		(net "ATTN_LED_DR10_N")
	)
	(segment
		(start 21.7678 -461.7212)
		(end 21.59 -461.5434)
		(width 0.17145)
		(layer "F.Cu")
		(net "ATTN_LED_DR10_N")
	)
	(segment
		(start 25.908 -465.582)
		(end 26.3906 -465.0994)
		(width 0.17145)
		(layer "F.Cu")
		(net "ATTN_LED_DR10_N")
	)
	(via
		(at 21.59 -461.5434)
		(size 0.508)
		(drill 0.254)
		(layers "F.Cu" "B.Cu")
		(net "ATTN_LED_DR10_N")
	)
	(via
		(at 16.8656 -433.5526)
		(size 0.508)
		(drill 0.254)
		(layers "F.Cu" "B.Cu")
		(net "ATTN_LED_DR10_N")
	)
	(via
		(at 14.929358 -402.799804)
		(size 0.7112)
		(drill 0.3556)
		(layers "F.Cu" "B.Cu")
		(net "ATTN_LED_DR10_N")
	)
	(via
		(at 18.8214 -456.2348)
		(size 0.508)
		(drill 0.254)
		(layers "F.Cu" "B.Cu")
		(net "ATTN_LED_DR10_N")
	)
	(segment
		(start 6.889242 -400.685)
		(end 7.009892 -400.80565)
		(width 0.17145)
		(layer "B.Cu")
		(net "ATTN_LED_DR10_N")
	)
	(segment
		(start 15.249398 -403.119844)
		(end 15.249398 -431.936398)
		(width 0.17145)
		(layer "B.Cu")
		(net "ATTN_LED_DR10_N")
	)
	(segment
		(start 1.868932 -401.541996)
		(end 3.765804 -401.541996)
		(width 0.17145)
		(layer "B.Cu")
		(net "ATTN_LED_DR10_N")
	)
	(segment
		(start 21.59 -461.01)
		(end 18.8214 -458.2414)
		(width 0.17145)
		(layer "B.Cu")
		(net "ATTN_LED_DR10_N")
	)
	(segment
		(start 12.935204 -400.80565)
		(end 14.929358 -402.799804)
		(width 0.17145)
		(layer "B.Cu")
		(net "ATTN_LED_DR10_N")
	)
	(segment
		(start 18.8214 -458.2414)
		(end 18.8214 -456.2348)
		(width 0.17145)
		(layer "B.Cu")
		(net "ATTN_LED_DR10_N")
	)
	(segment
		(start 5.08 -400.685)
		(end 6.889242 -400.685)
		(width 0.17145)
		(layer "B.Cu")
		(net "ATTN_LED_DR10_N")
	)
	(segment
		(start 15.249398 -431.936398)
		(end 16.8656 -433.5526)
		(width 0.17145)
		(layer "B.Cu")
		(net "ATTN_LED_DR10_N")
	)
	(segment
		(start 3.765804 -401.541996)
		(end 4.0132 -401.2946)
		(width 0.17145)
		(layer "B.Cu")
		(net "ATTN_LED_DR10_N")
	)
	(segment
		(start 4.4704 -401.2946)
		(end 5.08 -400.685)
		(width 0.17145)
		(layer "B.Cu")
		(net "ATTN_LED_DR10_N")
	)
	(segment
		(start 21.59 -461.5434)
		(end 21.59 -461.01)
		(width 0.17145)
		(layer "B.Cu")
		(net "ATTN_LED_DR10_N")
	)
	(segment
		(start 7.009892 -400.80565)
		(end 12.935204 -400.80565)
		(width 0.17145)
		(layer "B.Cu")
		(net "ATTN_LED_DR10_N")
	)
	(segment
		(start 14.929358 -402.799804)
		(end 15.249398 -403.119844)
		(width 0.17145)
		(layer "B.Cu")
		(net "ATTN_LED_DR10_N")
	)
	(segment
		(start 4.0132 -401.2946)
		(end 4.4704 -401.2946)
		(width 0.17145)
		(layer "B.Cu")
		(net "ATTN_LED_DR10_N")
	)
	(segment
		(start 226.05238 -346.71762)
		(end 226.0092 -346.7608)
		(width 0.17145)
		(layer "F.Cu")
		(net "ATTN_LED_DR1_N")
	)
	(segment
		(start 10.922 -394.9446)
		(end 10.88517 -394.9446)
		(width 0.17145)
		(layer "F.Cu")
		(net "ATTN_LED_DR1_N")
	)
	(segment
		(start 226.92233 -345.836748)
		(end 226.05238 -346.706698)
		(width 0.17145)
		(layer "F.Cu")
		(net "ATTN_LED_DR1_N")
	)
	(segment
		(start 227.203 -345.567)
		(end 226.933252 -345.836748)
		(width 0.17145)
		(layer "F.Cu")
		(net "ATTN_LED_DR1_N")
	)
	(segment
		(start 10.922 -394.9446)
		(end 10.922 -387.604)
		(width 0.17145)
		(layer "F.Cu")
		(net "ATTN_LED_DR1_N")
	)
	(segment
		(start 226.933252 -345.836748)
		(end 226.92233 -345.836748)
		(width 0.17145)
		(layer "F.Cu")
		(net "ATTN_LED_DR1_N")
	)
	(segment
		(start 225.409252 -348.836996)
		(end 225.409252 -347.9038)
		(width 0.17145)
		(layer "F.Cu")
		(net "ATTN_LED_DR1_N")
	)
	(segment
		(start 6.845554 -400.443446)
		(end 3.911854 -400.443446)
		(width 0.17145)
		(layer "F.Cu")
		(net "ATTN_LED_DR1_N")
	)
	(segment
		(start 3.911854 -400.443446)
		(end 3.410204 -399.941796)
		(width 0.17145)
		(layer "F.Cu")
		(net "ATTN_LED_DR1_N")
	)
	(segment
		(start 226.3775 -343.912952)
		(end 226.996752 -343.912952)
		(width 0.17145)
		(layer "F.Cu")
		(net "ATTN_LED_DR1_N")
	)
	(segment
		(start 226.0092 -346.7608)
		(end 225.409252 -346.7608)
		(width 0.17145)
		(layer "F.Cu")
		(net "ATTN_LED_DR1_N")
	)
	(segment
		(start 226.996752 -343.912952)
		(end 227.203 -344.1192)
		(width 0.17145)
		(layer "F.Cu")
		(net "ATTN_LED_DR1_N")
	)
	(segment
		(start 3.410204 -399.941796)
		(end 2.249932 -399.941796)
		(width 0.17145)
		(layer "F.Cu")
		(net "ATTN_LED_DR1_N")
	)
	(segment
		(start 225.409252 -347.9038)
		(end 225.409252 -346.7608)
		(width 0.17145)
		(layer "F.Cu")
		(net "ATTN_LED_DR1_N")
	)
	(segment
		(start 227.203 -344.1192)
		(end 227.203 -345.567)
		(width 0.17145)
		(layer "F.Cu")
		(net "ATTN_LED_DR1_N")
	)
	(segment
		(start 10.922 -396.367)
		(end 6.845554 -400.443446)
		(width 0.17145)
		(layer "F.Cu")
		(net "ATTN_LED_DR1_N")
	)
	(segment
		(start 226.05238 -346.706698)
		(end 226.05238 -346.71762)
		(width 0.17145)
		(layer "F.Cu")
		(net "ATTN_LED_DR1_N")
	)
	(segment
		(start 10.922 -394.9446)
		(end 10.922 -396.367)
		(width 0.17145)
		(layer "F.Cu")
		(net "ATTN_LED_DR1_N")
	)
	(via
		(at 10.88517 -394.9446)
		(size 0.7112)
		(drill 0.3556)
		(layers "F.Cu" "B.Cu")
		(net "ATTN_LED_DR1_N")
	)
	(via
		(at 10.922 -387.604)
		(size 0.508)
		(drill 0.254)
		(layers "F.Cu" "B.Cu")
		(net "ATTN_LED_DR1_N")
	)
	(via
		(at 225.409252 -348.836996)
		(size 0.508)
		(drill 0.254)
		(layers "F.Cu" "B.Cu")
		(net "ATTN_LED_DR1_N")
	)
	(segment
		(start 225.167698 -347.763846)
		(end 222.132652 -344.7288)
		(width 0.1524)
		(layer "In5.Cu")
		(net "ATTN_LED_DR1_N")
	)
	(segment
		(start 222.132652 -344.7288)
		(end 125.66396 -344.7288)
		(width 0.1524)
		(layer "In5.Cu")
		(net "ATTN_LED_DR1_N")
	)
	(segment
		(start 225.409252 -348.836996)
		(end 225.167698 -348.595442)
		(width 0.1524)
		(layer "In5.Cu")
		(net "ATTN_LED_DR1_N")
	)
	(segment
		(start 125.66396 -344.7288)
		(end 76.742798 -393.649962)
		(width 0.1524)
		(layer "In5.Cu")
		(net "ATTN_LED_DR1_N")
	)
	(segment
		(start 10.922 -387.73862)
		(end 10.922 -387.604)
		(width 0.1524)
		(layer "In5.Cu")
		(net "ATTN_LED_DR1_N")
	)
	(segment
		(start 76.742798 -393.649962)
		(end 35.408362 -393.649962)
		(width 0.1524)
		(layer "In5.Cu")
		(net "ATTN_LED_DR1_N")
	)
	(segment
		(start 31.242 -389.4836)
		(end 21.81098 -389.4836)
		(width 0.1524)
		(layer "In5.Cu")
		(net "ATTN_LED_DR1_N")
	)
	(segment
		(start 225.167698 -348.595442)
		(end 225.167698 -347.763846)
		(width 0.1524)
		(layer "In5.Cu")
		(net "ATTN_LED_DR1_N")
	)
	(segment
		(start 35.408362 -393.649962)
		(end 31.242 -389.4836)
		(width 0.1524)
		(layer "In5.Cu")
		(net "ATTN_LED_DR1_N")
	)
	(segment
		(start 20.97278 -388.6454)
		(end 11.82878 -388.6454)
		(width 0.1524)
		(layer "In5.Cu")
		(net "ATTN_LED_DR1_N")
	)
	(segment
		(start 11.82878 -388.6454)
		(end 10.922 -387.73862)
		(width 0.1524)
		(layer "In5.Cu")
		(net "ATTN_LED_DR1_N")
	)
	(segment
		(start 21.81098 -389.4836)
		(end 20.97278 -388.6454)
		(width 0.1524)
		(layer "In5.Cu")
		(net "ATTN_LED_DR1_N")
	)
	(segment
		(start 225.552 -450.4055)
		(end 225.552 -451.4215)
		(width 0.17145)
		(layer "F.Cu")
		(net "ATTN_LED_DR0_N")
	)
	(segment
		(start 225.552 -449.915026)
		(end 225.552 -450.4055)
		(width 0.17145)
		(layer "F.Cu")
		(net "ATTN_LED_DR0_N")
	)
	(segment
		(start 225.552 -451.4215)
		(end 225.552 -452.20509)
		(width 0.17145)
		(layer "F.Cu")
		(net "ATTN_LED_DR0_N")
	)
	(segment
		(start 227.203 -448.264026)
		(end 225.552 -449.915026)
		(width 0.17145)
		(layer "F.Cu")
		(net "ATTN_LED_DR0_N")
	)
	(segment
		(start 6.432296 -434.086)
		(end 5.968746 -433.62245)
		(width 0.17145)
		(layer "F.Cu")
		(net "ATTN_LED_DR0_N")
	)
	(segment
		(start 3.300222 -434.341778)
		(end 2.249932 -434.341778)
		(width 0.17145)
		(layer "F.Cu")
		(net "ATTN_LED_DR0_N")
	)
	(segment
		(start 226.3775 -446.913)
		(end 226.949 -446.913)
		(width 0.17145)
		(layer "F.Cu")
		(net "ATTN_LED_DR0_N")
	)
	(segment
		(start 227.203 -447.167)
		(end 227.203 -448.264026)
		(width 0.17145)
		(layer "F.Cu")
		(net "ATTN_LED_DR0_N")
	)
	(segment
		(start 5.968746 -433.62245)
		(end 4.01955 -433.62245)
		(width 0.17145)
		(layer "F.Cu")
		(net "ATTN_LED_DR0_N")
	)
	(segment
		(start 225.552 -452.20509)
		(end 225.734626 -452.387716)
		(width 0.17145)
		(layer "F.Cu")
		(net "ATTN_LED_DR0_N")
	)
	(segment
		(start 4.01955 -433.62245)
		(end 3.300222 -434.341778)
		(width 0.17145)
		(layer "F.Cu")
		(net "ATTN_LED_DR0_N")
	)
	(segment
		(start 226.949 -446.913)
		(end 227.203 -447.167)
		(width 0.17145)
		(layer "F.Cu")
		(net "ATTN_LED_DR0_N")
	)
	(segment
		(start 8.692896 -434.086)
		(end 6.432296 -434.086)
		(width 0.17145)
		(layer "F.Cu")
		(net "ATTN_LED_DR0_N")
	)
	(via
		(at 8.692896 -434.086)
		(size 0.508)
		(drill 0.254)
		(layers "F.Cu" "B.Cu")
		(net "ATTN_LED_DR0_N")
	)
	(via
		(at 11.532108 -434.926486)
		(size 0.7112)
		(drill 0.3556)
		(layers "F.Cu" "B.Cu")
		(net "ATTN_LED_DR0_N")
	)
	(via
		(at 35.76955 -439.37555)
		(size 0.508)
		(drill 0.254)
		(layers "F.Cu" "B.Cu")
		(net "ATTN_LED_DR0_N")
	)
	(via
		(at 225.734626 -452.387716)
		(size 0.508)
		(drill 0.254)
		(layers "F.Cu" "B.Cu")
		(net "ATTN_LED_DR0_N")
	)
	(segment
		(start 20.731988 -437.926988)
		(end 20.73275 -437.92775)
		(width 0.17145)
		(layer "B.Cu")
		(net "ATTN_LED_DR0_N")
	)
	(segment
		(start 24.707596 -438.7469)
		(end 25.977342 -440.016646)
		(width 0.17145)
		(layer "B.Cu")
		(net "ATTN_LED_DR0_N")
	)
	(segment
		(start 10.691622 -434.086)
		(end 11.532108 -434.926486)
		(width 0.17145)
		(layer "B.Cu")
		(net "ATTN_LED_DR0_N")
	)
	(segment
		(start 31.686754 -439.37555)
		(end 35.76955 -439.37555)
		(width 0.17145)
		(layer "B.Cu")
		(net "ATTN_LED_DR0_N")
	)
	(segment
		(start 20.73275 -437.92775)
		(end 20.745958 -437.92775)
		(width 0.17145)
		(layer "B.Cu")
		(net "ATTN_LED_DR0_N")
	)
	(segment
		(start 20.745958 -437.92775)
		(end 21.565108 -438.7469)
		(width 0.17145)
		(layer "B.Cu")
		(net "ATTN_LED_DR0_N")
	)
	(segment
		(start 11.532108 -434.926486)
		(end 14.53261 -437.926988)
		(width 0.17145)
		(layer "B.Cu")
		(net "ATTN_LED_DR0_N")
	)
	(segment
		(start 31.045658 -440.016646)
		(end 31.686754 -439.37555)
		(width 0.17145)
		(layer "B.Cu")
		(net "ATTN_LED_DR0_N")
	)
	(segment
		(start 21.565108 -438.7469)
		(end 24.707596 -438.7469)
		(width 0.17145)
		(layer "B.Cu")
		(net "ATTN_LED_DR0_N")
	)
	(segment
		(start 8.692896 -434.086)
		(end 10.691622 -434.086)
		(width 0.17145)
		(layer "B.Cu")
		(net "ATTN_LED_DR0_N")
	)
	(segment
		(start 25.977342 -440.016646)
		(end 31.045658 -440.016646)
		(width 0.17145)
		(layer "B.Cu")
		(net "ATTN_LED_DR0_N")
	)
	(segment
		(start 14.53261 -437.926988)
		(end 20.731988 -437.926988)
		(width 0.17145)
		(layer "B.Cu")
		(net "ATTN_LED_DR0_N")
	)
	(segment
		(start 38.62578 -438.3786)
		(end 37.68598 -439.3184)
		(width 0.1524)
		(layer "In5.Cu")
		(net "ATTN_LED_DR0_N")
	)
	(segment
		(start 186.51982 -444.4492)
		(end 172.37202 -430.3014)
		(width 0.1524)
		(layer "In5.Cu")
		(net "ATTN_LED_DR0_N")
	)
	(segment
		(start 37.68598 -439.3184)
		(end 35.8267 -439.3184)
		(width 0.1524)
		(layer "In5.Cu")
		(net "ATTN_LED_DR0_N")
	)
	(segment
		(start 76.0603 -441.452)
		(end 67.47764 -441.452)
		(width 0.1524)
		(layer "In5.Cu")
		(net "ATTN_LED_DR0_N")
	)
	(segment
		(start 53.354986 -438.3786)
		(end 38.62578 -438.3786)
		(width 0.1524)
		(layer "In5.Cu")
		(net "ATTN_LED_DR0_N")
	)
	(segment
		(start 106.51998 -444.6524)
		(end 92.666058 -444.6524)
		(width 0.1524)
		(layer "In5.Cu")
		(net "ATTN_LED_DR0_N")
	)
	(segment
		(start 216.11082 -444.4492)
		(end 186.51982 -444.4492)
		(width 0.1524)
		(layer "In5.Cu")
		(net "ATTN_LED_DR0_N")
	)
	(segment
		(start 223.45142 -451.7898)
		(end 216.11082 -444.4492)
		(width 0.1524)
		(layer "In5.Cu")
		(net "ATTN_LED_DR0_N")
	)
	(segment
		(start 64.86144 -438.8358)
		(end 53.812186 -438.8358)
		(width 0.1524)
		(layer "In5.Cu")
		(net "ATTN_LED_DR0_N")
	)
	(segment
		(start 85.968078 -446.489582)
		(end 84.130896 -444.6524)
		(width 0.1524)
		(layer "In5.Cu")
		(net "ATTN_LED_DR0_N")
	)
	(segment
		(start 67.47764 -441.452)
		(end 64.86144 -438.8358)
		(width 0.1524)
		(layer "In5.Cu")
		(net "ATTN_LED_DR0_N")
	)
	(segment
		(start 90.828876 -446.489582)
		(end 85.968078 -446.489582)
		(width 0.1524)
		(layer "In5.Cu")
		(net "ATTN_LED_DR0_N")
	)
	(segment
		(start 120.87098 -430.3014)
		(end 106.51998 -444.6524)
		(width 0.1524)
		(layer "In5.Cu")
		(net "ATTN_LED_DR0_N")
	)
	(segment
		(start 79.2607 -444.6524)
		(end 76.0603 -441.452)
		(width 0.1524)
		(layer "In5.Cu")
		(net "ATTN_LED_DR0_N")
	)
	(segment
		(start 225.13671 -451.7898)
		(end 223.45142 -451.7898)
		(width 0.1524)
		(layer "In5.Cu")
		(net "ATTN_LED_DR0_N")
	)
	(segment
		(start 172.37202 -430.3014)
		(end 120.87098 -430.3014)
		(width 0.1524)
		(layer "In5.Cu")
		(net "ATTN_LED_DR0_N")
	)
	(segment
		(start 225.734626 -452.387716)
		(end 225.13671 -451.7898)
		(width 0.1524)
		(layer "In5.Cu")
		(net "ATTN_LED_DR0_N")
	)
	(segment
		(start 35.8267 -439.3184)
		(end 35.76955 -439.37555)
		(width 0.1524)
		(layer "In5.Cu")
		(net "ATTN_LED_DR0_N")
	)
	(segment
		(start 92.666058 -444.6524)
		(end 90.828876 -446.489582)
		(width 0.1524)
		(layer "In5.Cu")
		(net "ATTN_LED_DR0_N")
	)
	(segment
		(start 84.130896 -444.6524)
		(end 79.2607 -444.6524)
		(width 0.1524)
		(layer "In5.Cu")
		(net "ATTN_LED_DR0_N")
	)
	(segment
		(start 53.812186 -438.8358)
		(end 53.354986 -438.3786)
		(width 0.1524)
		(layer "In5.Cu")
		(net "ATTN_LED_DR0_N")
	)
	(segment
		(start 3.707384 -233.19994)
		(end 3.707384 -233.282236)
		(width 0.17145)
		(layer "F.Cu")
		(net "TRAY_ID_R")
	)
	(segment
		(start 3.249676 -232.742232)
		(end 3.707384 -233.19994)
		(width 0.17145)
		(layer "F.Cu")
		(net "TRAY_ID_R")
	)
	(segment
		(start 3.707384 -233.282236)
		(end 4.105148 -233.68)
		(width 0.17145)
		(layer "F.Cu")
		(net "TRAY_ID_R")
	)
	(segment
		(start 7.62 -235.966)
		(end 7.62 -251.714)
		(width 0.17145)
		(layer "F.Cu")
		(net "TRAY_ID_R")
	)
	(segment
		(start 2.249932 -232.742232)
		(end 3.249676 -232.742232)
		(width 0.17145)
		(layer "F.Cu")
		(net "TRAY_ID_R")
	)
	(segment
		(start 5.334 -233.68)
		(end 7.62 -235.966)
		(width 0.17145)
		(layer "F.Cu")
		(net "TRAY_ID_R")
	)
	(segment
		(start 4.105148 -233.68)
		(end 5.334 -233.68)
		(width 0.17145)
		(layer "F.Cu")
		(net "TRAY_ID_R")
	)
	(segment
		(start 11.43 -269.4305)
		(end 11.43 -268.478)
		(width 0.17145)
		(layer "F.Cu")
		(net "TRAY_ID_R")
	)
	(via
		(at 7.62 -251.714)
		(size 0.508)
		(drill 0.254)
		(layers "F.Cu" "B.Cu")
		(net "TRAY_ID_R")
	)
	(via
		(at 11.43 -268.478)
		(size 0.5588)
		(drill 0.3048)
		(layers "F.Cu" "B.Cu")
		(net "TRAY_ID_R")
	)
	(segment
		(start 5.969 -267.716)
		(end 10.668 -267.716)
		(width 0.1524)
		(layer "In5.Cu")
		(net "TRAY_ID_R")
	)
	(segment
		(start 7.62 -253.238)
		(end 3.302 -257.556)
		(width 0.1524)
		(layer "In5.Cu")
		(net "TRAY_ID_R")
	)
	(segment
		(start 7.62 -251.714)
		(end 7.62 -253.238)
		(width 0.1524)
		(layer "In5.Cu")
		(net "TRAY_ID_R")
	)
	(segment
		(start 10.668 -267.716)
		(end 11.43 -268.478)
		(width 0.1524)
		(layer "In5.Cu")
		(net "TRAY_ID_R")
	)
	(segment
		(start 3.302 -257.556)
		(end 3.302 -265.049)
		(width 0.1524)
		(layer "In5.Cu")
		(net "TRAY_ID_R")
	)
	(segment
		(start 3.302 -265.049)
		(end 5.969 -267.716)
		(width 0.1524)
		(layer "In5.Cu")
		(net "TRAY_ID_R")
	)
	(segment
		(start 12.192 -477.7105)
		(end 12.192 -476.885)
		(width 0.17145)
		(layer "F.Cu")
		(net "SELF_TRAY_PRESENT_R")
	)
	(via
		(at 12.192 -476.885)
		(size 0.508)
		(drill 0.254)
		(layers "F.Cu" "B.Cu")
		(net "SELF_TRAY_PRESENT_R")
	)
	(via
		(at 12.7254 -475.6912)
		(size 0.7112)
		(drill 0.3556)
		(layers "F.Cu" "B.Cu")
		(net "SELF_TRAY_PRESENT_R")
	)
	(segment
		(start 11.134344 -457.00315)
		(end 12.614148 -458.482954)
		(width 0.17145)
		(layer "B.Cu")
		(net "SELF_TRAY_PRESENT_R")
	)
	(segment
		(start 5.818124 -455.941938)
		(end 6.879336 -457.00315)
		(width 0.17145)
		(layer "B.Cu")
		(net "SELF_TRAY_PRESENT_R")
	)
	(segment
		(start 1.868932 -455.941938)
		(end 5.818124 -455.941938)
		(width 0.17145)
		(layer "B.Cu")
		(net "SELF_TRAY_PRESENT_R")
	)
	(segment
		(start 12.614148 -474.5228)
		(end 12.7254 -474.634052)
		(width 0.17145)
		(layer "B.Cu")
		(net "SELF_TRAY_PRESENT_R")
	)
	(segment
		(start 12.614148 -458.482954)
		(end 12.614148 -474.5228)
		(width 0.17145)
		(layer "B.Cu")
		(net "SELF_TRAY_PRESENT_R")
	)
	(segment
		(start 12.7254 -476.3516)
		(end 12.7254 -475.6912)
		(width 0.17145)
		(layer "B.Cu")
		(net "SELF_TRAY_PRESENT_R")
	)
	(segment
		(start 12.7254 -474.634052)
		(end 12.7254 -475.6912)
		(width 0.17145)
		(layer "B.Cu")
		(net "SELF_TRAY_PRESENT_R")
	)
	(segment
		(start 12.192 -476.885)
		(end 12.7254 -476.3516)
		(width 0.17145)
		(layer "B.Cu")
		(net "SELF_TRAY_PRESENT_R")
	)
	(segment
		(start 6.879336 -457.00315)
		(end 11.134344 -457.00315)
		(width 0.17145)
		(layer "B.Cu")
		(net "SELF_TRAY_PRESENT_R")
	)
	(segment
		(start 10.414 -269.4305)
		(end 10.414 -268.605)
		(width 0.17145)
		(layer "F.Cu")
		(net "SD_LATCH_RELEASE_R")
	)
	(segment
		(start 3.545078 -233.542078)
		(end 4.23545 -234.23245)
		(width 0.17145)
		(layer "F.Cu")
		(net "SD_LATCH_RELEASE_R")
	)
	(segment
		(start 4.23545 -234.23245)
		(end 5.105146 -234.23245)
		(width 0.17145)
		(layer "F.Cu")
		(net "SD_LATCH_RELEASE_R")
	)
	(segment
		(start 5.105146 -234.23245)
		(end 7.06755 -236.194854)
		(width 0.17145)
		(layer "F.Cu")
		(net "SD_LATCH_RELEASE_R")
	)
	(segment
		(start 2.249932 -233.542078)
		(end 3.545078 -233.542078)
		(width 0.17145)
		(layer "F.Cu")
		(net "SD_LATCH_RELEASE_R")
	)
	(segment
		(start 7.06755 -236.194854)
		(end 7.06755 -252.73)
		(width 0.17145)
		(layer "F.Cu")
		(net "SD_LATCH_RELEASE_R")
	)
	(via
		(at 10.414 -268.605)
		(size 0.508)
		(drill 0.254)
		(layers "F.Cu" "B.Cu")
		(net "SD_LATCH_RELEASE_R")
	)
	(via
		(at 7.06755 -252.73)
		(size 0.5588)
		(drill 0.3048)
		(layers "F.Cu" "B.Cu")
		(net "SD_LATCH_RELEASE_R")
	)
	(segment
		(start 2.667 -257.13055)
		(end 2.667 -265.176)
		(width 0.1524)
		(layer "In5.Cu")
		(net "SD_LATCH_RELEASE_R")
	)
	(segment
		(start 6.096 -268.605)
		(end 10.414 -268.605)
		(width 0.1524)
		(layer "In5.Cu")
		(net "SD_LATCH_RELEASE_R")
	)
	(segment
		(start 7.06755 -252.73)
		(end 2.667 -257.13055)
		(width 0.1524)
		(layer "In5.Cu")
		(net "SD_LATCH_RELEASE_R")
	)
	(segment
		(start 2.667 -265.176)
		(end 6.096 -268.605)
		(width 0.1524)
		(layer "In5.Cu")
		(net "SD_LATCH_RELEASE_R")
	)
	(segment
		(start 250.418092 -423.824908)
		(end 248.412 -425.831)
		(width 0.17145)
		(layer "F.Cu")
		(net "N70930468")
	)
	(segment
		(start 248.412 -425.831)
		(end 246.253 -425.831)
		(width 0.17145)
		(layer "F.Cu")
		(net "N70930468")
	)
	(segment
		(start 253.212092 -423.824908)
		(end 250.418092 -423.824908)
		(width 0.17145)
		(layer "F.Cu")
		(net "N70930468")
	)
	(segment
		(start 256.474976 -423.189908)
		(end 253.847092 -423.189908)
		(width 0.17145)
		(layer "F.Cu")
		(net "N70930468")
	)
	(segment
		(start 253.847092 -423.189908)
		(end 253.212092 -423.824908)
		(width 0.17145)
		(layer "F.Cu")
		(net "N70930468")
	)
	(segment
		(start 252.222 -416.433)
		(end 253.085092 -415.569908)
		(width 0.17145)
		(layer "F.Cu")
		(net "N70929042")
	)
	(segment
		(start 248.793 -416.433)
		(end 252.222 -416.433)
		(width 0.17145)
		(layer "F.Cu")
		(net "N70929042")
	)
	(segment
		(start 253.085092 -415.569908)
		(end 256.474976 -415.569908)
		(width 0.17145)
		(layer "F.Cu")
		(net "N70929042")
	)
	(segment
		(start 247.904 -415.544)
		(end 248.793 -416.433)
		(width 0.17145)
		(layer "F.Cu")
		(net "N70929042")
	)
	(segment
		(start 246.126 -416.941)
		(end 247.142 -416.941)
		(width 0.17145)
		(layer "F.Cu")
		(net "N70914768")
	)
	(via
		(at 247.142 -416.941)
		(size 0.508)
		(drill 0.254)
		(layers "F.Cu" "B.Cu")
		(net "N70914768")
	)
	(segment
		(start 250.342908 -416.941)
		(end 250.444 -416.839908)
		(width 0.17145)
		(layer "B.Cu")
		(net "N70914768")
	)
	(segment
		(start 247.142 -416.941)
		(end 250.342908 -416.941)
		(width 0.17145)
		(layer "B.Cu")
		(net "N70914768")
	)
	(segment
		(start 250.444 -416.839908)
		(end 256.093976 -416.839908)
		(width 0.17145)
		(layer "B.Cu")
		(net "N70914768")
	)
	(segment
		(start 233.0704 -451.485)
		(end 232.1814 -452.374)
		(width 0.17145)
		(layer "F.Cu")
		(net "DRV_ACT_0")
	)
	(segment
		(start 230.443532 -452.374)
		(end 231.072182 -452.374)
		(width 0.17145)
		(layer "F.Cu")
		(net "DRV_ACT_0")
	)
	(segment
		(start 229.230174 -452.693532)
		(end 230.124 -452.693532)
		(width 0.17145)
		(layer "F.Cu")
		(net "DRV_ACT_0")
	)
	(segment
		(start 233.6165 -452.628)
		(end 233.6165 -451.485)
		(width 0.17145)
		(layer "F.Cu")
		(net "DRV_ACT_0")
	)
	(segment
		(start 232.1814 -452.374)
		(end 231.072182 -452.374)
		(width 0.17145)
		(layer "F.Cu")
		(net "DRV_ACT_0")
	)
	(segment
		(start 233.6165 -451.485)
		(end 233.0704 -451.485)
		(width 0.17145)
		(layer "F.Cu")
		(net "DRV_ACT_0")
	)
	(segment
		(start 230.124 -452.693532)
		(end 230.443532 -452.374)
		(width 0.17145)
		(layer "F.Cu")
		(net "DRV_ACT_0")
	)
	(via
		(at 231.072182 -452.374)
		(size 0.7112)
		(drill 0.3556)
		(layers "F.Cu" "B.Cu")
		(net "DRV_ACT_0")
	)
	(segment
		(start 35.65525 -37.7825)
		(end 35.65525 -35.97275)
		(width 0.17145)
		(layer "F.Cu")
		(net "ATTN_LED_DR9_R")
	)
	(segment
		(start 35.65525 -35.97275)
		(end 35.941 -35.687)
		(width 0.17145)
		(layer "F.Cu")
		(net "ATTN_LED_DR9_R")
	)
	(segment
		(start 37.1856 -35.4965)
		(end 36.1315 -35.4965)
		(width 0.17145)
		(layer "F.Cu")
		(net "ATTN_LED_DR9_R")
	)
	(segment
		(start 36.1315 -35.4965)
		(end 35.941 -35.687)
		(width 0.17145)
		(layer "F.Cu")
		(net "ATTN_LED_DR9_R")
	)
	(via
		(at 35.941 -35.687)
		(size 0.7112)
		(drill 0.3556)
		(layers "F.Cu" "B.Cu")
		(net "ATTN_LED_DR9_R")
	)
	(segment
		(start 32.86125 -138.96975)
		(end 32.86125 -141.2875)
		(width 0.17145)
		(layer "F.Cu")
		(net "ATTN_LED_DR8_R")
	)
	(segment
		(start 38.1 -137.4775)
		(end 35.895534 -137.4775)
		(width 0.17145)
		(layer "F.Cu")
		(net "ATTN_LED_DR8_R")
	)
	(segment
		(start 34.3535 -137.4775)
		(end 32.86125 -138.96975)
		(width 0.17145)
		(layer "F.Cu")
		(net "ATTN_LED_DR8_R")
	)
	(segment
		(start 35.895534 -137.4775)
		(end 34.3535 -137.4775)
		(width 0.17145)
		(layer "F.Cu")
		(net "ATTN_LED_DR8_R")
	)
	(via
		(at 35.895534 -137.4775)
		(size 0.7112)
		(drill 0.3556)
		(layers "F.Cu" "B.Cu")
		(net "ATTN_LED_DR8_R")
	)
	(segment
		(start 53.918358 -244.088158)
		(end 53.9242 -244.094)
		(width 0.17145)
		(layer "F.Cu")
		(net "ATTN_LED_DR7_R")
	)
	(segment
		(start 54.76875 -243.75745)
		(end 54.76875 -241.992658)
		(width 0.17145)
		(layer "F.Cu")
		(net "ATTN_LED_DR7_R")
	)
	(segment
		(start 54.4322 -244.094)
		(end 54.76875 -243.75745)
		(width 0.17145)
		(layer "F.Cu")
		(net "ATTN_LED_DR7_R")
	)
	(segment
		(start 53.9242 -244.094)
		(end 54.4322 -244.094)
		(width 0.17145)
		(layer "F.Cu")
		(net "ATTN_LED_DR7_R")
	)
	(segment
		(start 52.6669 -244.088158)
		(end 53.918358 -244.088158)
		(width 0.17145)
		(layer "F.Cu")
		(net "ATTN_LED_DR7_R")
	)
	(via
		(at 53.9242 -244.094)
		(size 0.7112)
		(drill 0.3556)
		(layers "F.Cu" "B.Cu")
		(net "ATTN_LED_DR7_R")
	)
	(segment
		(start 37.007292 -343.484708)
		(end 36.67125 -343.82075)
		(width 0.17145)
		(layer "F.Cu")
		(net "ATTN_LED_DR6_R")
	)
	(segment
		(start 36.67125 -343.82075)
		(end 36.67125 -344.727276)
		(width 0.17145)
		(layer "F.Cu")
		(net "ATTN_LED_DR6_R")
	)
	(segment
		(start 36.67125 -344.727276)
		(end 36.67125 -346.52839)
		(width 0.17145)
		(layer "F.Cu")
		(net "ATTN_LED_DR6_R")
	)
	(segment
		(start 38.407086 -343.484708)
		(end 37.007292 -343.484708)
		(width 0.17145)
		(layer "F.Cu")
		(net "ATTN_LED_DR6_R")
	)
	(via
		(at 36.67125 -344.727276)
		(size 0.7112)
		(drill 0.3556)
		(layers "F.Cu" "B.Cu")
		(net "ATTN_LED_DR6_R")
	)
	(segment
		(start 57.957974 -450.1134)
		(end 58.532776 -450.1134)
		(width 0.17145)
		(layer "F.Cu")
		(net "ATTN_LED_DR5_R")
	)
	(segment
		(start 58.83275 -449.813426)
		(end 58.83275 -447.9925)
		(width 0.17145)
		(layer "F.Cu")
		(net "ATTN_LED_DR5_R")
	)
	(segment
		(start 58.532776 -450.1134)
		(end 58.83275 -449.813426)
		(width 0.17145)
		(layer "F.Cu")
		(net "ATTN_LED_DR5_R")
	)
	(segment
		(start 55.7403 -450.1134)
		(end 57.957974 -450.1134)
		(width 0.17145)
		(layer "F.Cu")
		(net "ATTN_LED_DR5_R")
	)
	(via
		(at 57.957974 -450.1134)
		(size 0.7112)
		(drill 0.3556)
		(layers "F.Cu" "B.Cu")
		(net "ATTN_LED_DR5_R")
	)
	(segment
		(start 224.79 -37.846)
		(end 225.1075 -38.1635)
		(width 0.17145)
		(layer "F.Cu")
		(net "ATTN_LED_DR4_R")
	)
	(segment
		(start 223.529144 -38.090856)
		(end 223.774 -37.846)
		(width 0.17145)
		(layer "F.Cu")
		(net "ATTN_LED_DR4_R")
	)
	(segment
		(start 225.1075 -38.1635)
		(end 225.1075 -39.878)
		(width 0.17145)
		(layer "F.Cu")
		(net "ATTN_LED_DR4_R")
	)
	(segment
		(start 224.386648 -37.846)
		(end 224.79 -37.846)
		(width 0.17145)
		(layer "F.Cu")
		(net "ATTN_LED_DR4_R")
	)
	(segment
		(start 223.774 -37.846)
		(end 224.386648 -37.846)
		(width 0.17145)
		(layer "F.Cu")
		(net "ATTN_LED_DR4_R")
	)
	(segment
		(start 223.529144 -39.601394)
		(end 223.529144 -38.090856)
		(width 0.17145)
		(layer "F.Cu")
		(net "ATTN_LED_DR4_R")
	)
	(via
		(at 224.386648 -37.846)
		(size 0.7112)
		(drill 0.3556)
		(layers "F.Cu" "B.Cu")
		(net "ATTN_LED_DR4_R")
	)
	(segment
		(start 224.663 -139.69111)
		(end 224.409 -139.43711)
		(width 0.17145)
		(layer "F.Cu")
		(net "ATTN_LED_DR3_R")
	)
	(segment
		(start 223.10725 -139.72286)
		(end 223.10725 -141.15161)
		(width 0.17145)
		(layer "F.Cu")
		(net "ATTN_LED_DR3_R")
	)
	(segment
		(start 224.663 -141.40561)
		(end 224.663 -139.69111)
		(width 0.17145)
		(layer "F.Cu")
		(net "ATTN_LED_DR3_R")
	)
	(segment
		(start 224.409 -139.43711)
		(end 223.901 -139.43711)
		(width 0.17145)
		(layer "F.Cu")
		(net "ATTN_LED_DR3_R")
	)
	(segment
		(start 223.393 -139.43711)
		(end 223.10725 -139.72286)
		(width 0.17145)
		(layer "F.Cu")
		(net "ATTN_LED_DR3_R")
	)
	(segment
		(start 223.901 -139.43711)
		(end 223.393 -139.43711)
		(width 0.17145)
		(layer "F.Cu")
		(net "ATTN_LED_DR3_R")
	)
	(via
		(at 223.901 -139.43711)
		(size 0.7112)
		(drill 0.3556)
		(layers "F.Cu" "B.Cu")
		(net "ATTN_LED_DR3_R")
	)
	(segment
		(start 224.663 -242.691158)
		(end 224.409 -242.437158)
		(width 0.17145)
		(layer "F.Cu")
		(net "ATTN_LED_DR2_R")
	)
	(segment
		(start 223.393 -242.437158)
		(end 223.10725 -242.722908)
		(width 0.17145)
		(layer "F.Cu")
		(net "ATTN_LED_DR2_R")
	)
	(segment
		(start 223.10725 -242.722908)
		(end 223.10725 -244.151658)
		(width 0.17145)
		(layer "F.Cu")
		(net "ATTN_LED_DR2_R")
	)
	(segment
		(start 224.663 -244.405658)
		(end 224.663 -242.691158)
		(width 0.17145)
		(layer "F.Cu")
		(net "ATTN_LED_DR2_R")
	)
	(segment
		(start 223.901 -242.437158)
		(end 223.393 -242.437158)
		(width 0.17145)
		(layer "F.Cu")
		(net "ATTN_LED_DR2_R")
	)
	(segment
		(start 224.409 -242.437158)
		(end 223.901 -242.437158)
		(width 0.17145)
		(layer "F.Cu")
		(net "ATTN_LED_DR2_R")
	)
	(via
		(at 223.901 -242.437158)
		(size 0.7112)
		(drill 0.3556)
		(layers "F.Cu" "B.Cu")
		(net "ATTN_LED_DR2_R")
	)
	(segment
		(start 22.247606 -58.66511)
		(end 22.247606 -57.380886)
		(width 0.17145)
		(layer "F.Cu")
		(net "ATTN_LED_DR14_R")
	)
	(segment
		(start 21.41855 -56.429402)
		(end 21.993606 -56.429402)
		(width 0.17145)
		(layer "F.Cu")
		(net "ATTN_LED_DR14_R")
	)
	(segment
		(start 20.499832 -56.987186)
		(end 20.860766 -56.987186)
		(width 0.17145)
		(layer "F.Cu")
		(net "ATTN_LED_DR14_R")
	)
	(segment
		(start 21.993606 -56.429402)
		(end 22.247606 -56.683402)
		(width 0.17145)
		(layer "F.Cu")
		(net "ATTN_LED_DR14_R")
	)
	(segment
		(start 20.860766 -56.987186)
		(end 21.41855 -56.429402)
		(width 0.17145)
		(layer "F.Cu")
		(net "ATTN_LED_DR14_R")
	)
	(segment
		(start 22.247606 -56.683402)
		(end 22.247606 -57.380886)
		(width 0.17145)
		(layer "F.Cu")
		(net "ATTN_LED_DR14_R")
	)
	(via
		(at 22.247606 -57.380886)
		(size 0.7112)
		(drill 0.3556)
		(layers "F.Cu" "B.Cu")
		(net "ATTN_LED_DR14_R")
	)
	(segment
		(start 20.499832 -159.987234)
		(end 20.860766 -159.987234)
		(width 0.17145)
		(layer "F.Cu")
		(net "ATTN_LED_DR13_R")
	)
	(segment
		(start 21.41855 -159.42945)
		(end 21.993606 -159.42945)
		(width 0.17145)
		(layer "F.Cu")
		(net "ATTN_LED_DR13_R")
	)
	(segment
		(start 22.247606 -161.665158)
		(end 22.247606 -160.380934)
		(width 0.17145)
		(layer "F.Cu")
		(net "ATTN_LED_DR13_R")
	)
	(segment
		(start 22.247606 -159.68345)
		(end 22.247606 -160.380934)
		(width 0.17145)
		(layer "F.Cu")
		(net "ATTN_LED_DR13_R")
	)
	(segment
		(start 20.860766 -159.987234)
		(end 21.41855 -159.42945)
		(width 0.17145)
		(layer "F.Cu")
		(net "ATTN_LED_DR13_R")
	)
	(segment
		(start 21.993606 -159.42945)
		(end 22.247606 -159.68345)
		(width 0.17145)
		(layer "F.Cu")
		(net "ATTN_LED_DR13_R")
	)
	(via
		(at 22.247606 -160.380934)
		(size 0.7112)
		(drill 0.3556)
		(layers "F.Cu" "B.Cu")
		(net "ATTN_LED_DR13_R")
	)
	(segment
		(start 22.352 -262.763)
		(end 22.098 -262.509)
		(width 0.17145)
		(layer "F.Cu")
		(net "ATTN_LED_DR12_R")
	)
	(segment
		(start 22.098 -262.509)
		(end 20.97786 -262.509)
		(width 0.17145)
		(layer "F.Cu")
		(net "ATTN_LED_DR12_R")
	)
	(segment
		(start 22.352 -263.526778)
		(end 22.352 -264.8585)
		(width 0.17145)
		(layer "F.Cu")
		(net "ATTN_LED_DR12_R")
	)
	(segment
		(start 22.352 -263.526778)
		(end 22.352 -262.763)
		(width 0.17145)
		(layer "F.Cu")
		(net "ATTN_LED_DR12_R")
	)
	(segment
		(start 20.97786 -262.509)
		(end 20.499832 -262.987028)
		(width 0.17145)
		(layer "F.Cu")
		(net "ATTN_LED_DR12_R")
	)
	(via
		(at 22.352 -263.526778)
		(size 0.7112)
		(drill 0.3556)
		(layers "F.Cu" "B.Cu")
		(net "ATTN_LED_DR12_R")
	)
	(segment
		(start 21.336 -365.633)
		(end 20.981924 -365.987076)
		(width 0.17145)
		(layer "F.Cu")
		(net "ATTN_LED_DR11_R")
	)
	(segment
		(start 22.03323 -365.633)
		(end 21.336 -365.633)
		(width 0.17145)
		(layer "F.Cu")
		(net "ATTN_LED_DR11_R")
	)
	(segment
		(start 20.981924 -365.987076)
		(end 20.499832 -365.987076)
		(width 0.17145)
		(layer "F.Cu")
		(net "ATTN_LED_DR11_R")
	)
	(segment
		(start 22.247606 -367.665)
		(end 22.247606 -366.380776)
		(width 0.17145)
		(layer "F.Cu")
		(net "ATTN_LED_DR11_R")
	)
	(segment
		(start 22.247606 -365.847376)
		(end 22.03323 -365.633)
		(width 0.17145)
		(layer "F.Cu")
		(net "ATTN_LED_DR11_R")
	)
	(segment
		(start 22.247606 -366.380776)
		(end 22.247606 -365.847376)
		(width 0.17145)
		(layer "F.Cu")
		(net "ATTN_LED_DR11_R")
	)
	(via
		(at 22.247606 -366.380776)
		(size 0.7112)
		(drill 0.3556)
		(layers "F.Cu" "B.Cu")
		(net "ATTN_LED_DR11_R")
	)
	(segment
		(start 21.0566 -467.5124)
		(end 20.8534 -467.7156)
		(width 0.17145)
		(layer "F.Cu")
		(net "ATTN_LED_DR10_R")
	)
	(segment
		(start 21.4249 -467.5124)
		(end 21.0566 -467.5124)
		(width 0.17145)
		(layer "F.Cu")
		(net "ATTN_LED_DR10_R")
	)
	(segment
		(start 16.5735 -470.4461)
		(end 16.18615 -470.4461)
		(width 0.17145)
		(layer "F.Cu")
		(net "ATTN_LED_DR10_R")
	)
	(segment
		(start 18.791936 -468.227664)
		(end 16.5735 -470.4461)
		(width 0.17145)
		(layer "F.Cu")
		(net "ATTN_LED_DR10_R")
	)
	(segment
		(start 20.8534 -467.7156)
		(end 20.193 -467.7156)
		(width 0.17145)
		(layer "F.Cu")
		(net "ATTN_LED_DR10_R")
	)
	(segment
		(start 20.193 -467.7156)
		(end 19.680936 -468.227664)
		(width 0.17145)
		(layer "F.Cu")
		(net "ATTN_LED_DR10_R")
	)
	(segment
		(start 19.680936 -468.227664)
		(end 18.791936 -468.227664)
		(width 0.17145)
		(layer "F.Cu")
		(net "ATTN_LED_DR10_R")
	)
	(via
		(at 20.193 -467.7156)
		(size 0.7112)
		(drill 0.3556)
		(layers "F.Cu" "B.Cu")
		(net "ATTN_LED_DR10_R")
	)
	(segment
		(start 223.901 -345.436952)
		(end 223.393 -345.436952)
		(width 0.17145)
		(layer "F.Cu")
		(net "ATTN_LED_DR1_R")
	)
	(segment
		(start 223.393 -345.436952)
		(end 223.10725 -345.722702)
		(width 0.17145)
		(layer "F.Cu")
		(net "ATTN_LED_DR1_R")
	)
	(segment
		(start 224.520252 -345.548204)
		(end 224.409 -345.436952)
		(width 0.17145)
		(layer "F.Cu")
		(net "ATTN_LED_DR1_R")
	)
	(segment
		(start 224.520252 -346.7608)
		(end 224.520252 -345.548204)
		(width 0.17145)
		(layer "F.Cu")
		(net "ATTN_LED_DR1_R")
	)
	(segment
		(start 223.10725 -345.722702)
		(end 223.10725 -347.151452)
		(width 0.17145)
		(layer "F.Cu")
		(net "ATTN_LED_DR1_R")
	)
	(segment
		(start 224.409 -345.436952)
		(end 223.901 -345.436952)
		(width 0.17145)
		(layer "F.Cu")
		(net "ATTN_LED_DR1_R")
	)
	(via
		(at 223.901 -345.436952)
		(size 0.7112)
		(drill 0.3556)
		(layers "F.Cu" "B.Cu")
		(net "ATTN_LED_DR1_R")
	)
	(segment
		(start 223.10725 -448.72275)
		(end 223.10725 -450.1515)
		(width 0.17145)
		(layer "F.Cu")
		(net "ATTN_LED_DR0_R")
	)
	(segment
		(start 224.663 -450.4055)
		(end 224.663 -448.691)
		(width 0.17145)
		(layer "F.Cu")
		(net "ATTN_LED_DR0_R")
	)
	(segment
		(start 224.409 -448.437)
		(end 223.901 -448.437)
		(width 0.17145)
		(layer "F.Cu")
		(net "ATTN_LED_DR0_R")
	)
	(segment
		(start 224.663 -448.691)
		(end 224.409 -448.437)
		(width 0.17145)
		(layer "F.Cu")
		(net "ATTN_LED_DR0_R")
	)
	(segment
		(start 223.393 -448.437)
		(end 223.10725 -448.72275)
		(width 0.17145)
		(layer "F.Cu")
		(net "ATTN_LED_DR0_R")
	)
	(segment
		(start 223.901 -448.437)
		(end 223.393 -448.437)
		(width 0.17145)
		(layer "F.Cu")
		(net "ATTN_LED_DR0_R")
	)
	(via
		(at 223.901 -448.437)
		(size 0.7112)
		(drill 0.3556)
		(layers "F.Cu" "B.Cu")
		(net "ATTN_LED_DR0_R")
	)
	(segment
		(start 90.55862 -26.5811)
		(end 90.55862 -28.05938)
		(width 0.17145)
		(layer "F.Cu")
		(net "VOL_SEN_SDA")
	)
	(segment
		(start 90.55862 -28.05938)
		(end 90.17 -28.448)
		(width 0.17145)
		(layer "F.Cu")
		(net "VOL_SEN_SDA")
	)
	(segment
		(start 89.535 -29.083)
		(end 90.17 -28.448)
		(width 0.17145)
		(layer "F.Cu")
		(net "VOL_SEN_SDA")
	)
	(segment
		(start 89.535 -31.4325)
		(end 89.535 -29.083)
		(width 0.17145)
		(layer "F.Cu")
		(net "VOL_SEN_SDA")
	)
	(via
		(at 90.17 -28.448)
		(size 0.7112)
		(drill 0.3556)
		(layers "F.Cu" "B.Cu")
		(net "VOL_SEN_SDA")
	)
	(segment
		(start 88.519 -31.4325)
		(end 88.519 -30.099)
		(width 0.17145)
		(layer "F.Cu")
		(net "VOL_SEN_SCL")
	)
	(segment
		(start 88.519 -29.099256)
		(end 88.519 -30.099)
		(width 0.17145)
		(layer "F.Cu")
		(net "VOL_SEN_SCL")
	)
	(segment
		(start 90.05951 -26.5811)
		(end 90.05951 -27.558746)
		(width 0.17145)
		(layer "F.Cu")
		(net "VOL_SEN_SCL")
	)
	(segment
		(start 90.05951 -27.558746)
		(end 88.519 -29.099256)
		(width 0.17145)
		(layer "F.Cu")
		(net "VOL_SEN_SCL")
	)
	(via
		(at 88.519 -30.099)
		(size 0.7112)
		(drill 0.3556)
		(layers "F.Cu" "B.Cu")
		(net "VOL_SEN_SCL")
	)
	(segment
		(start 90.932 -17.9705)
		(end 90.932 -19.304)
		(width 0.17145)
		(layer "F.Cu")
		(net "VOL_SEN_ALERT")
	)
	(segment
		(start 90.55862 -19.67738)
		(end 90.932 -19.304)
		(width 0.17145)
		(layer "F.Cu")
		(net "VOL_SEN_ALERT")
	)
	(segment
		(start 90.55862 -22.4409)
		(end 90.55862 -19.67738)
		(width 0.17145)
		(layer "F.Cu")
		(net "VOL_SEN_ALERT")
	)
	(segment
		(start 89.535 -19.1135)
		(end 88.519 -19.1135)
		(width 0.17145)
		(layer "F.Cu")
		(net "VOL_SEN_ADDR")
	)
	(segment
		(start 89.535 -20.93849)
		(end 90.05951 -21.463)
		(width 0.17145)
		(layer "F.Cu")
		(net "VOL_SEN_ADDR")
	)
	(segment
		(start 89.535 -19.1135)
		(end 89.535 -20.701)
		(width 0.17145)
		(layer "F.Cu")
		(net "VOL_SEN_ADDR")
	)
	(segment
		(start 89.535 -20.701)
		(end 89.535 -20.93849)
		(width 0.17145)
		(layer "F.Cu")
		(net "VOL_SEN_ADDR")
	)
	(segment
		(start 90.05951 -21.463)
		(end 90.05951 -22.4409)
		(width 0.17145)
		(layer "F.Cu")
		(net "VOL_SEN_ADDR")
	)
	(via
		(at 89.535 -20.701)
		(size 0.7112)
		(drill 0.3556)
		(layers "F.Cu" "B.Cu")
		(net "VOL_SEN_ADDR")
	)
	(segment
		(start 93.72981 -107.94619)
		(end 93.72981 -106.02341)
		(width 0.3048)
		(layer "F.Cu")
		(net "VDD_DIFF_4")
	)
	(segment
		(start 101.3079 -101.1301)
		(end 101.981 -100.457)
		(width 0.508)
		(layer "F.Cu")
		(net "VDD_DIFF_4")
	)
	(segment
		(start 99.222814 -101.34981)
		(end 98.40341 -101.34981)
		(width 0.3048)
		(layer "F.Cu")
		(net "VDD_DIFF_4")
	)
	(segment
		(start 93.599 -94.2975)
		(end 92.7481 -94.2975)
		(width 0.508)
		(layer "F.Cu")
		(net "VDD_DIFF_4")
	)
	(segment
		(start 93.599 -109.0295)
		(end 93.599 -108.077)
		(width 0.3048)
		(layer "F.Cu")
		(net "VDD_DIFF_4")
	)
	(segment
		(start 78.5622 -99.8347)
		(end 79.375 -99.8347)
		(width 0.508)
		(layer "F.Cu")
		(net "VDD_DIFF_4")
	)
	(segment
		(start 93.72981 -95.25381)
		(end 93.72981 -97.17659)
		(width 0.3048)
		(layer "F.Cu")
		(net "VDD_DIFF_4")
	)
	(segment
		(start 93.599 -109.0295)
		(end 92.648786 -109.0295)
		(width 0.508)
		(layer "F.Cu")
		(net "VDD_DIFF_4")
	)
	(segment
		(start 92.7481 -94.2975)
		(end 92.7354 -94.2848)
		(width 0.508)
		(layer "F.Cu")
		(net "VDD_DIFF_4")
	)
	(segment
		(start 100.4824 -101.1301)
		(end 101.3079 -101.1301)
		(width 0.508)
		(layer "F.Cu")
		(net "VDD_DIFF_4")
	)
	(segment
		(start 100.4824 -101.1301)
		(end 99.442524 -101.1301)
		(width 0.3048)
		(layer "F.Cu")
		(net "VDD_DIFF_4")
	)
	(segment
		(start 99.442524 -101.1301)
		(end 99.222814 -101.34981)
		(width 0.3048)
		(layer "F.Cu")
		(net "VDD_DIFF_4")
	)
	(segment
		(start 93.599 -108.077)
		(end 93.72981 -107.94619)
		(width 0.3048)
		(layer "F.Cu")
		(net "VDD_DIFF_4")
	)
	(segment
		(start 93.599 -94.2975)
		(end 93.599 -95.123)
		(width 0.3048)
		(layer "F.Cu")
		(net "VDD_DIFF_4")
	)
	(segment
		(start 93.599 -95.123)
		(end 93.72981 -95.25381)
		(width 0.3048)
		(layer "F.Cu")
		(net "VDD_DIFF_4")
	)
	(segment
		(start 85.0265 -98.806)
		(end 84.201 -98.806)
		(width 0.508)
		(layer "F.Cu")
		(net "VDD_DIFF_4")
	)
	(segment
		(start 92.648786 -109.0295)
		(end 92.648532 -109.029246)
		(width 0.508)
		(layer "F.Cu")
		(net "VDD_DIFF_4")
	)
	(segment
		(start 84.0105 -95.758)
		(end 83.185 -95.758)
		(width 0.508)
		(layer "F.Cu")
		(net "VDD_DIFF_4")
	)
	(via
		(at 92.648532 -109.029246)
		(size 0.508)
		(drill 0.254)
		(layers "F.Cu" "B.Cu")
		(net "VDD_DIFF_4")
	)
	(via
		(at 80.518 -108.585)
		(size 0.508)
		(drill 0.254)
		(layers "F.Cu" "B.Cu")
		(net "VDD_DIFF_4")
	)
	(via
		(at 92.7354 -94.2848)
		(size 0.508)
		(drill 0.254)
		(layers "F.Cu" "B.Cu")
		(net "VDD_DIFF_4")
	)
	(via
		(at 81.661 -103.759)
		(size 0.508)
		(drill 0.254)
		(layers "F.Cu" "B.Cu")
		(net "VDD_DIFF_4")
	)
	(via
		(at 101.981 -100.457)
		(size 0.5588)
		(drill 0.3048)
		(layers "F.Cu" "B.Cu")
		(net "VDD_DIFF_4")
	)
	(via
		(at 79.5528 -108.585)
		(size 0.508)
		(drill 0.254)
		(layers "F.Cu" "B.Cu")
		(net "VDD_DIFF_4")
	)
	(via
		(at 81.661 -105.918)
		(size 0.508)
		(drill 0.254)
		(layers "F.Cu" "B.Cu")
		(net "VDD_DIFF_4")
	)
	(via
		(at 81.661 -106.934)
		(size 0.508)
		(drill 0.254)
		(layers "F.Cu" "B.Cu")
		(net "VDD_DIFF_4")
	)
	(via
		(at 81.6356 -102.7176)
		(size 0.508)
		(drill 0.254)
		(layers "F.Cu" "B.Cu")
		(net "VDD_DIFF_4")
	)
	(via
		(at 79.375 -99.8347)
		(size 0.508)
		(drill 0.254)
		(layers "F.Cu" "B.Cu")
		(net "VDD_DIFF_4")
	)
	(via
		(at 84.201 -98.806)
		(size 0.508)
		(drill 0.254)
		(layers "F.Cu" "B.Cu")
		(net "VDD_DIFF_4")
	)
	(via
		(at 81.661 -108.0008)
		(size 0.508)
		(drill 0.254)
		(layers "F.Cu" "B.Cu")
		(net "VDD_DIFF_4")
	)
	(via
		(at 80.0354 -102.4636)
		(size 0.7112)
		(drill 0.3556)
		(layers "F.Cu" "B.Cu")
		(net "VDD_DIFF_4")
	)
	(via
		(at 83.185 -95.758)
		(size 0.508)
		(drill 0.254)
		(layers "F.Cu" "B.Cu")
		(net "VDD_DIFF_4")
	)
	(via
		(at 80.01 -104.648)
		(size 0.508)
		(drill 0.254)
		(layers "F.Cu" "B.Cu")
		(net "VDD_DIFF_4")
	)
	(segment
		(start 99.76231 -210.56981)
		(end 99.949 -210.7565)
		(width 0.3048)
		(layer "F.Cu")
		(net "VDD_DIFF_3")
	)
	(segment
		(start 98.40341 -210.56981)
		(end 99.76231 -210.56981)
		(width 0.3048)
		(layer "F.Cu")
		(net "VDD_DIFF_3")
	)
	(segment
		(start 93.72981 -217.16619)
		(end 93.72981 -215.24341)
		(width 0.3048)
		(layer "F.Cu")
		(net "VDD_DIFF_3")
	)
	(segment
		(start 92.583 -218.059)
		(end 92.6465 -217.9955)
		(width 0.508)
		(layer "F.Cu")
		(net "VDD_DIFF_3")
	)
	(segment
		(start 93.599 -217.297)
		(end 93.72981 -217.16619)
		(width 0.3048)
		(layer "F.Cu")
		(net "VDD_DIFF_3")
	)
	(segment
		(start 91.948 -204.1525)
		(end 91.948 -204.724)
		(width 0.3048)
		(layer "F.Cu")
		(net "VDD_DIFF_3")
	)
	(segment
		(start 91.948 -204.724)
		(end 92.583 -205.359)
		(width 0.3048)
		(layer "F.Cu")
		(net "VDD_DIFF_3")
	)
	(segment
		(start 101.981 -210.82)
		(end 100.965 -210.82)
		(width 0.508)
		(layer "F.Cu")
		(net "VDD_DIFF_3")
	)
	(segment
		(start 78.7527 -208.9277)
		(end 79.248 -209.423)
		(width 0.508)
		(layer "F.Cu")
		(net "VDD_DIFF_3")
	)
	(segment
		(start 93.599 -217.9955)
		(end 93.599 -217.297)
		(width 0.3048)
		(layer "F.Cu")
		(net "VDD_DIFF_3")
	)
	(segment
		(start 78.3844 -208.9277)
		(end 78.7527 -208.9277)
		(width 0.508)
		(layer "F.Cu")
		(net "VDD_DIFF_3")
	)
	(segment
		(start 91.6432 -218.059)
		(end 92.583 -218.059)
		(width 0.508)
		(layer "F.Cu")
		(net "VDD_DIFF_3")
	)
	(segment
		(start 84.0105 -204.978)
		(end 83.185 -204.978)
		(width 0.508)
		(layer "F.Cu")
		(net "VDD_DIFF_3")
	)
	(segment
		(start 93.72981 -205.61681)
		(end 93.72981 -206.39659)
		(width 0.3048)
		(layer "F.Cu")
		(net "VDD_DIFF_3")
	)
	(segment
		(start 91.1733 -204.1525)
		(end 91.1352 -204.1144)
		(width 0.508)
		(layer "F.Cu")
		(net "VDD_DIFF_3")
	)
	(segment
		(start 91.948 -204.1525)
		(end 91.1733 -204.1525)
		(width 0.508)
		(layer "F.Cu")
		(net "VDD_DIFF_3")
	)
	(segment
		(start 85.0265 -208.026)
		(end 84.201 -208.026)
		(width 0.508)
		(layer "F.Cu")
		(net "VDD_DIFF_3")
	)
	(segment
		(start 100.965 -210.82)
		(end 100.9015 -210.7565)
		(width 0.508)
		(layer "F.Cu")
		(net "VDD_DIFF_3")
	)
	(segment
		(start 92.583 -205.359)
		(end 93.472 -205.359)
		(width 0.3048)
		(layer "F.Cu")
		(net "VDD_DIFF_3")
	)
	(segment
		(start 92.6465 -217.9955)
		(end 93.599 -217.9955)
		(width 0.508)
		(layer "F.Cu")
		(net "VDD_DIFF_3")
	)
	(segment
		(start 100.9015 -210.7565)
		(end 99.949 -210.7565)
		(width 0.508)
		(layer "F.Cu")
		(net "VDD_DIFF_3")
	)
	(segment
		(start 93.472 -205.359)
		(end 93.72981 -205.61681)
		(width 0.3048)
		(layer "F.Cu")
		(net "VDD_DIFF_3")
	)
	(via
		(at 91.1352 -204.1144)
		(size 0.508)
		(drill 0.254)
		(layers "F.Cu" "B.Cu")
		(net "VDD_DIFF_3")
	)
	(via
		(at 79.5528 -217.9066)
		(size 0.508)
		(drill 0.254)
		(layers "F.Cu" "B.Cu")
		(net "VDD_DIFF_3")
	)
	(via
		(at 81.661 -216.154)
		(size 0.508)
		(drill 0.254)
		(layers "F.Cu" "B.Cu")
		(net "VDD_DIFF_3")
	)
	(via
		(at 91.6432 -218.059)
		(size 0.508)
		(drill 0.254)
		(layers "F.Cu" "B.Cu")
		(net "VDD_DIFF_3")
	)
	(via
		(at 80.518 -217.9066)
		(size 0.508)
		(drill 0.254)
		(layers "F.Cu" "B.Cu")
		(net "VDD_DIFF_3")
	)
	(via
		(at 81.661 -212.979)
		(size 0.508)
		(drill 0.254)
		(layers "F.Cu" "B.Cu")
		(net "VDD_DIFF_3")
	)
	(via
		(at 81.661 -217.2208)
		(size 0.508)
		(drill 0.254)
		(layers "F.Cu" "B.Cu")
		(net "VDD_DIFF_3")
	)
	(via
		(at 79.248 -209.423)
		(size 0.508)
		(drill 0.254)
		(layers "F.Cu" "B.Cu")
		(net "VDD_DIFF_3")
	)
	(via
		(at 79.756 -211.836)
		(size 0.7112)
		(drill 0.3556)
		(layers "F.Cu" "B.Cu")
		(net "VDD_DIFF_3")
	)
	(via
		(at 81.661 -215.138)
		(size 0.508)
		(drill 0.254)
		(layers "F.Cu" "B.Cu")
		(net "VDD_DIFF_3")
	)
	(via
		(at 83.185 -204.978)
		(size 0.508)
		(drill 0.254)
		(layers "F.Cu" "B.Cu")
		(net "VDD_DIFF_3")
	)
	(via
		(at 84.201 -208.026)
		(size 0.508)
		(drill 0.254)
		(layers "F.Cu" "B.Cu")
		(net "VDD_DIFF_3")
	)
	(via
		(at 101.981 -210.82)
		(size 0.5588)
		(drill 0.3048)
		(layers "F.Cu" "B.Cu")
		(net "VDD_DIFF_3")
	)
	(via
		(at 80.01 -213.868)
		(size 0.508)
		(drill 0.254)
		(layers "F.Cu" "B.Cu")
		(net "VDD_DIFF_3")
	)
	(via
		(at 81.6356 -211.9376)
		(size 0.508)
		(drill 0.254)
		(layers "F.Cu" "B.Cu")
		(net "VDD_DIFF_3")
	)
	(segment
		(start 93.599 -312.3565)
		(end 92.7735 -312.3565)
		(width 0.508)
		(layer "F.Cu")
		(net "VDD_DIFF_2")
	)
	(segment
		(start 93.72981 -300.75759)
		(end 93.72981 -299.46981)
		(width 0.3048)
		(layer "F.Cu")
		(net "VDD_DIFF_2")
	)
	(segment
		(start 100.4824 -304.4825)
		(end 99.6315 -304.4825)
		(width 0.3048)
		(layer "F.Cu")
		(net "VDD_DIFF_2")
	)
	(segment
		(start 93.72981 -299.46981)
		(end 93.345 -299.085)
		(width 0.3048)
		(layer "F.Cu")
		(net "VDD_DIFF_2")
	)
	(segment
		(start 93.345 -299.085)
		(end 93.345 -298.3865)
		(width 0.3048)
		(layer "F.Cu")
		(net "VDD_DIFF_2")
	)
	(segment
		(start 78.5622 -303.276)
		(end 79.375 -303.276)
		(width 0.508)
		(layer "F.Cu")
		(net "VDD_DIFF_2")
	)
	(segment
		(start 92.7735 -312.3565)
		(end 92.7608 -312.3692)
		(width 0.508)
		(layer "F.Cu")
		(net "VDD_DIFF_2")
	)
	(segment
		(start 84.0105 -299.339)
		(end 83.185 -299.339)
		(width 0.508)
		(layer "F.Cu")
		(net "VDD_DIFF_2")
	)
	(segment
		(start 101.5365 -304.4825)
		(end 102.108 -303.911)
		(width 0.508)
		(layer "F.Cu")
		(net "VDD_DIFF_2")
	)
	(segment
		(start 93.599 -312.3565)
		(end 93.599 -311.658)
		(width 0.3048)
		(layer "F.Cu")
		(net "VDD_DIFF_2")
	)
	(segment
		(start 92.5703 -298.3865)
		(end 92.5322 -298.4246)
		(width 0.508)
		(layer "F.Cu")
		(net "VDD_DIFF_2")
	)
	(segment
		(start 93.599 -311.658)
		(end 93.72981 -311.52719)
		(width 0.3048)
		(layer "F.Cu")
		(net "VDD_DIFF_2")
	)
	(segment
		(start 93.345 -298.3865)
		(end 92.5703 -298.3865)
		(width 0.508)
		(layer "F.Cu")
		(net "VDD_DIFF_2")
	)
	(segment
		(start 99.18319 -304.93081)
		(end 98.40341 -304.93081)
		(width 0.3048)
		(layer "F.Cu")
		(net "VDD_DIFF_2")
	)
	(segment
		(start 99.6315 -304.4825)
		(end 99.18319 -304.93081)
		(width 0.3048)
		(layer "F.Cu")
		(net "VDD_DIFF_2")
	)
	(segment
		(start 93.72981 -311.52719)
		(end 93.72981 -309.60441)
		(width 0.3048)
		(layer "F.Cu")
		(net "VDD_DIFF_2")
	)
	(segment
		(start 100.4824 -304.4825)
		(end 101.5365 -304.4825)
		(width 0.508)
		(layer "F.Cu")
		(net "VDD_DIFF_2")
	)
	(segment
		(start 85.0265 -302.387)
		(end 84.201 -302.387)
		(width 0.508)
		(layer "F.Cu")
		(net "VDD_DIFF_2")
	)
	(via
		(at 81.6864 -311.5564)
		(size 0.508)
		(drill 0.254)
		(layers "F.Cu" "B.Cu")
		(net "VDD_DIFF_2")
	)
	(via
		(at 102.108 -303.911)
		(size 0.5588)
		(drill 0.3048)
		(layers "F.Cu" "B.Cu")
		(net "VDD_DIFF_2")
	)
	(via
		(at 80.518 -312.1152)
		(size 0.508)
		(drill 0.254)
		(layers "F.Cu" "B.Cu")
		(net "VDD_DIFF_2")
	)
	(via
		(at 81.661 -307.34)
		(size 0.508)
		(drill 0.254)
		(layers "F.Cu" "B.Cu")
		(net "VDD_DIFF_2")
	)
	(via
		(at 81.661 -309.499)
		(size 0.508)
		(drill 0.254)
		(layers "F.Cu" "B.Cu")
		(net "VDD_DIFF_2")
	)
	(via
		(at 79.866998 -308.199028)
		(size 0.508)
		(drill 0.254)
		(layers "F.Cu" "B.Cu")
		(net "VDD_DIFF_2")
	)
	(via
		(at 79.375 -303.276)
		(size 0.508)
		(drill 0.254)
		(layers "F.Cu" "B.Cu")
		(net "VDD_DIFF_2")
	)
	(via
		(at 83.185 -299.339)
		(size 0.508)
		(drill 0.254)
		(layers "F.Cu" "B.Cu")
		(net "VDD_DIFF_2")
	)
	(via
		(at 79.9084 -306.0192)
		(size 0.7112)
		(drill 0.3556)
		(layers "F.Cu" "B.Cu")
		(net "VDD_DIFF_2")
	)
	(via
		(at 81.6356 -306.2986)
		(size 0.508)
		(drill 0.254)
		(layers "F.Cu" "B.Cu")
		(net "VDD_DIFF_2")
	)
	(via
		(at 79.5528 -312.1152)
		(size 0.508)
		(drill 0.254)
		(layers "F.Cu" "B.Cu")
		(net "VDD_DIFF_2")
	)
	(via
		(at 92.7608 -312.3692)
		(size 0.508)
		(drill 0.254)
		(layers "F.Cu" "B.Cu")
		(net "VDD_DIFF_2")
	)
	(via
		(at 81.661 -310.515)
		(size 0.508)
		(drill 0.254)
		(layers "F.Cu" "B.Cu")
		(net "VDD_DIFF_2")
	)
	(via
		(at 92.5322 -298.4246)
		(size 0.508)
		(drill 0.254)
		(layers "F.Cu" "B.Cu")
		(net "VDD_DIFF_2")
	)
	(via
		(at 84.201 -302.387)
		(size 0.508)
		(drill 0.254)
		(layers "F.Cu" "B.Cu")
		(net "VDD_DIFF_2")
	)
	(segment
		(start 99.18319 -431.54981)
		(end 98.40341 -431.54981)
		(width 0.3048)
		(layer "F.Cu")
		(net "VDD_DIFF_1")
	)
	(segment
		(start 93.72981 -427.37659)
		(end 93.72981 -426.33519)
		(width 0.3048)
		(layer "F.Cu")
		(net "VDD_DIFF_1")
	)
	(segment
		(start 78.8162 -429.895)
		(end 79.629 -429.895)
		(width 0.508)
		(layer "F.Cu")
		(net "VDD_DIFF_1")
	)
	(segment
		(start 92.9005 -438.8485)
		(end 92.8878 -438.8358)
		(width 0.508)
		(layer "F.Cu")
		(net "VDD_DIFF_1")
	)
	(segment
		(start 101.5365 -431.1015)
		(end 100.5078 -431.1015)
		(width 0.508)
		(layer "F.Cu")
		(net "VDD_DIFF_1")
	)
	(segment
		(start 93.72981 -426.33519)
		(end 94.615 -425.45)
		(width 0.3048)
		(layer "F.Cu")
		(net "VDD_DIFF_1")
	)
	(segment
		(start 85.0265 -429.514)
		(end 84.201 -429.514)
		(width 0.508)
		(layer "F.Cu")
		(net "VDD_DIFF_1")
	)
	(segment
		(start 84.0105 -425.958)
		(end 83.185 -425.958)
		(width 0.508)
		(layer "F.Cu")
		(net "VDD_DIFF_1")
	)
	(segment
		(start 100.5078 -431.1015)
		(end 99.6315 -431.1015)
		(width 0.3048)
		(layer "F.Cu")
		(net "VDD_DIFF_1")
	)
	(segment
		(start 94.615 -425.45)
		(end 94.615 -425.1325)
		(width 0.3048)
		(layer "F.Cu")
		(net "VDD_DIFF_1")
	)
	(segment
		(start 99.6315 -431.1015)
		(end 99.18319 -431.54981)
		(width 0.3048)
		(layer "F.Cu")
		(net "VDD_DIFF_1")
	)
	(segment
		(start 94.615 -425.1325)
		(end 93.7641 -425.1325)
		(width 0.508)
		(layer "F.Cu")
		(net "VDD_DIFF_1")
	)
	(segment
		(start 93.726 -438.8485)
		(end 92.9005 -438.8485)
		(width 0.508)
		(layer "F.Cu")
		(net "VDD_DIFF_1")
	)
	(segment
		(start 102.108 -430.53)
		(end 101.5365 -431.1015)
		(width 0.508)
		(layer "F.Cu")
		(net "VDD_DIFF_1")
	)
	(segment
		(start 93.72981 -436.22341)
		(end 93.72981 -438.84469)
		(width 0.3048)
		(layer "F.Cu")
		(net "VDD_DIFF_1")
	)
	(segment
		(start 93.7641 -425.1325)
		(end 93.7514 -425.1198)
		(width 0.508)
		(layer "F.Cu")
		(net "VDD_DIFF_1")
	)
	(segment
		(start 93.72981 -438.84469)
		(end 93.726 -438.8485)
		(width 0.3048)
		(layer "F.Cu")
		(net "VDD_DIFF_1")
	)
	(via
		(at 92.8878 -438.8358)
		(size 0.508)
		(drill 0.254)
		(layers "F.Cu" "B.Cu")
		(net "VDD_DIFF_1")
	)
	(via
		(at 81.661 -438.2008)
		(size 0.508)
		(drill 0.254)
		(layers "F.Cu" "B.Cu")
		(net "VDD_DIFF_1")
	)
	(via
		(at 93.7514 -425.1198)
		(size 0.508)
		(drill 0.254)
		(layers "F.Cu" "B.Cu")
		(net "VDD_DIFF_1")
	)
	(via
		(at 79.5528 -438.7342)
		(size 0.508)
		(drill 0.254)
		(layers "F.Cu" "B.Cu")
		(net "VDD_DIFF_1")
	)
	(via
		(at 80.518 -438.7342)
		(size 0.508)
		(drill 0.254)
		(layers "F.Cu" "B.Cu")
		(net "VDD_DIFF_1")
	)
	(via
		(at 81.661 -437.134)
		(size 0.508)
		(drill 0.254)
		(layers "F.Cu" "B.Cu")
		(net "VDD_DIFF_1")
	)
	(via
		(at 81.6356 -432.9176)
		(size 0.508)
		(drill 0.254)
		(layers "F.Cu" "B.Cu")
		(net "VDD_DIFF_1")
	)
	(via
		(at 79.629 -429.895)
		(size 0.508)
		(drill 0.254)
		(layers "F.Cu" "B.Cu")
		(net "VDD_DIFF_1")
	)
	(via
		(at 83.185 -425.958)
		(size 0.508)
		(drill 0.254)
		(layers "F.Cu" "B.Cu")
		(net "VDD_DIFF_1")
	)
	(via
		(at 81.661 -433.959)
		(size 0.508)
		(drill 0.254)
		(layers "F.Cu" "B.Cu")
		(net "VDD_DIFF_1")
	)
	(via
		(at 102.108 -430.53)
		(size 0.5588)
		(drill 0.3048)
		(layers "F.Cu" "B.Cu")
		(net "VDD_DIFF_1")
	)
	(via
		(at 80.01 -434.848)
		(size 0.508)
		(drill 0.254)
		(layers "F.Cu" "B.Cu")
		(net "VDD_DIFF_1")
	)
	(via
		(at 81.661 -436.118)
		(size 0.508)
		(drill 0.254)
		(layers "F.Cu" "B.Cu")
		(net "VDD_DIFF_1")
	)
	(via
		(at 84.201 -429.514)
		(size 0.508)
		(drill 0.254)
		(layers "F.Cu" "B.Cu")
		(net "VDD_DIFF_1")
	)
	(via
		(at 80.0608 -433.0446)
		(size 0.7112)
		(drill 0.3556)
		(layers "F.Cu" "B.Cu")
		(net "VDD_DIFF_1")
	)
	(segment
		(start 11.07313 -325.6661)
		(end 11.07313 -300.692312)
		(width 0.17145)
		(layer "F.Cu")
		(net "TRAY_ID")
	)
	(segment
		(start 240.538 -420.243)
		(end 249.809 -420.243)
		(width 0.17145)
		(layer "F.Cu")
		(net "TRAY_ID")
	)
	(segment
		(start 9.913112 -332.859888)
		(end 9.913112 -326.826118)
		(width 0.17145)
		(layer "F.Cu")
		(net "TRAY_ID")
	)
	(segment
		(start 9.779 -332.994)
		(end 9.913112 -332.859888)
		(width 0.17145)
		(layer "F.Cu")
		(net "TRAY_ID")
	)
	(segment
		(start 249.809 -420.243)
		(end 251.485908 -421.919908)
		(width 0.17145)
		(layer "F.Cu")
		(net "TRAY_ID")
	)
	(segment
		(start 12.326112 -274.327112)
		(end 11.43 -273.431)
		(width 0.17145)
		(layer "F.Cu")
		(net "TRAY_ID")
	)
	(segment
		(start 9.913112 -326.826118)
		(end 11.07313 -325.6661)
		(width 0.17145)
		(layer "F.Cu")
		(net "TRAY_ID")
	)
	(segment
		(start 251.485908 -421.919908)
		(end 256.474976 -421.919908)
		(width 0.17145)
		(layer "F.Cu")
		(net "TRAY_ID")
	)
	(segment
		(start 11.43 -273.431)
		(end 11.43 -270.3195)
		(width 0.17145)
		(layer "F.Cu")
		(net "TRAY_ID")
	)
	(segment
		(start 12.326112 -299.43933)
		(end 12.326112 -274.327112)
		(width 0.17145)
		(layer "F.Cu")
		(net "TRAY_ID")
	)
	(segment
		(start 11.07313 -300.692312)
		(end 12.326112 -299.43933)
		(width 0.17145)
		(layer "F.Cu")
		(net "TRAY_ID")
	)
	(via
		(at 9.779 -332.994)
		(size 0.508)
		(drill 0.254)
		(layers "F.Cu" "B.Cu")
		(net "TRAY_ID")
	)
	(via
		(at 240.538 -420.243)
		(size 0.508)
		(drill 0.254)
		(layers "F.Cu" "B.Cu")
		(net "TRAY_ID")
	)
	(via
		(at 11.43 -273.431)
		(size 0.7112)
		(drill 0.3556)
		(layers "F.Cu" "B.Cu")
		(net "TRAY_ID")
	)
	(segment
		(start 236.1692 -341.5792)
		(end 220.472 -325.882)
		(width 0.1524)
		(layer "In5.Cu")
		(net "TRAY_ID")
	)
	(segment
		(start 240.538 -420.243)
		(end 236.1692 -415.8742)
		(width 0.1524)
		(layer "In5.Cu")
		(net "TRAY_ID")
	)
	(segment
		(start 236.1692 -415.8742)
		(end 236.1692 -341.5792)
		(width 0.1524)
		(layer "In5.Cu")
		(net "TRAY_ID")
	)
	(segment
		(start 74.041 -293.243)
		(end 64.77 -302.514)
		(width 0.1524)
		(layer "In5.Cu")
		(net "TRAY_ID")
	)
	(segment
		(start 25.908 -316.484)
		(end 19.431 -322.961)
		(width 0.1524)
		(layer "In5.Cu")
		(net "TRAY_ID")
	)
	(segment
		(start 220.472 -303.149)
		(end 210.566 -293.243)
		(width 0.1524)
		(layer "In5.Cu")
		(net "TRAY_ID")
	)
	(segment
		(start 210.566 -293.243)
		(end 74.041 -293.243)
		(width 0.1524)
		(layer "In5.Cu")
		(net "TRAY_ID")
	)
	(segment
		(start 58.039 -302.514)
		(end 44.069 -316.484)
		(width 0.1524)
		(layer "In5.Cu")
		(net "TRAY_ID")
	)
	(segment
		(start 19.431 -322.961)
		(end 19.431 -324.95617)
		(width 0.1524)
		(layer "In5.Cu")
		(net "TRAY_ID")
	)
	(segment
		(start 44.069 -316.484)
		(end 25.908 -316.484)
		(width 0.1524)
		(layer "In5.Cu")
		(net "TRAY_ID")
	)
	(segment
		(start 64.77 -302.514)
		(end 58.039 -302.514)
		(width 0.1524)
		(layer "In5.Cu")
		(net "TRAY_ID")
	)
	(segment
		(start 19.431 -324.95617)
		(end 11.39317 -332.994)
		(width 0.1524)
		(layer "In5.Cu")
		(net "TRAY_ID")
	)
	(segment
		(start 220.472 -325.882)
		(end 220.472 -303.149)
		(width 0.1524)
		(layer "In5.Cu")
		(net "TRAY_ID")
	)
	(segment
		(start 11.39317 -332.994)
		(end 9.779 -332.994)
		(width 0.1524)
		(layer "In5.Cu")
		(net "TRAY_ID")
	)
	(segment
		(start 27.059636 -379.975364)
		(end 26.416 -380.619)
		(width 0.17145)
		(layer "F.Cu")
		(net "TMP4_SDA")
	)
	(segment
		(start 25.6032 -379.8062)
		(end 26.416 -380.619)
		(width 0.17145)
		(layer "F.Cu")
		(net "TMP4_SDA")
	)
	(segment
		(start 24.4475 -380.238)
		(end 24.8793 -379.8062)
		(width 0.17145)
		(layer "F.Cu")
		(net "TMP4_SDA")
	)
	(segment
		(start 24.8793 -379.8062)
		(end 25.6032 -379.8062)
		(width 0.17145)
		(layer "F.Cu")
		(net "TMP4_SDA")
	)
	(segment
		(start 28.945078 -379.975364)
		(end 27.059636 -379.975364)
		(width 0.17145)
		(layer "F.Cu")
		(net "TMP4_SDA")
	)
	(via
		(at 26.416 -380.619)
		(size 0.7112)
		(drill 0.3556)
		(layers "F.Cu" "B.Cu")
		(net "TMP4_SDA")
	)
	(segment
		(start 24.73325 -379.25375)
		(end 25.74925 -379.25375)
		(width 0.17145)
		(layer "F.Cu")
		(net "TMP4_SCL")
	)
	(segment
		(start 24.4475 -378.968)
		(end 24.73325 -379.25375)
		(width 0.17145)
		(layer "F.Cu")
		(net "TMP4_SCL")
	)
	(segment
		(start 25.74925 -379.25375)
		(end 26.416 -378.587)
		(width 0.17145)
		(layer "F.Cu")
		(net "TMP4_SCL")
	)
	(segment
		(start 28.945078 -379.325124)
		(end 27.154124 -379.325124)
		(width 0.17145)
		(layer "F.Cu")
		(net "TMP4_SCL")
	)
	(segment
		(start 27.154124 -379.325124)
		(end 26.416 -378.587)
		(width 0.17145)
		(layer "F.Cu")
		(net "TMP4_SCL")
	)
	(via
		(at 26.416 -378.587)
		(size 0.7112)
		(drill 0.3556)
		(layers "F.Cu" "B.Cu")
		(net "TMP4_SCL")
	)
	(segment
		(start 206.61376 -49.92624)
		(end 207.34909 -49.92624)
		(width 0.17145)
		(layer "F.Cu")
		(net "TMP3_SDA")
	)
	(segment
		(start 204.257402 -49.933098)
		(end 205.127098 -49.933098)
		(width 0.17145)
		(layer "F.Cu")
		(net "TMP3_SDA")
	)
	(segment
		(start 205.127098 -49.933098)
		(end 205.867 -50.673)
		(width 0.17145)
		(layer "F.Cu")
		(net "TMP3_SDA")
	)
	(segment
		(start 203.8985 -50.292)
		(end 204.257402 -49.933098)
		(width 0.17145)
		(layer "F.Cu")
		(net "TMP3_SDA")
	)
	(segment
		(start 207.398112 -49.975262)
		(end 208.4451 -49.975262)
		(width 0.17145)
		(layer "F.Cu")
		(net "TMP3_SDA")
	)
	(segment
		(start 205.867 -50.673)
		(end 206.61376 -49.92624)
		(width 0.17145)
		(layer "F.Cu")
		(net "TMP3_SDA")
	)
	(segment
		(start 207.34909 -49.92624)
		(end 207.398112 -49.975262)
		(width 0.17145)
		(layer "F.Cu")
		(net "TMP3_SDA")
	)
	(via
		(at 205.867 -50.673)
		(size 0.7112)
		(drill 0.3556)
		(layers "F.Cu" "B.Cu")
		(net "TMP3_SDA")
	)
	(segment
		(start 207.34909 -49.37379)
		(end 207.397858 -49.325022)
		(width 0.17145)
		(layer "F.Cu")
		(net "TMP3_SCL")
	)
	(segment
		(start 205.867 -48.641)
		(end 206.59979 -49.37379)
		(width 0.17145)
		(layer "F.Cu")
		(net "TMP3_SCL")
	)
	(segment
		(start 203.8985 -49.022)
		(end 204.257148 -49.380648)
		(width 0.17145)
		(layer "F.Cu")
		(net "TMP3_SCL")
	)
	(segment
		(start 204.257148 -49.380648)
		(end 205.127352 -49.380648)
		(width 0.17145)
		(layer "F.Cu")
		(net "TMP3_SCL")
	)
	(segment
		(start 207.397858 -49.325022)
		(end 208.4451 -49.325022)
		(width 0.17145)
		(layer "F.Cu")
		(net "TMP3_SCL")
	)
	(segment
		(start 206.59979 -49.37379)
		(end 207.34909 -49.37379)
		(width 0.17145)
		(layer "F.Cu")
		(net "TMP3_SCL")
	)
	(segment
		(start 205.127352 -49.380648)
		(end 205.867 -48.641)
		(width 0.17145)
		(layer "F.Cu")
		(net "TMP3_SCL")
	)
	(via
		(at 205.867 -48.641)
		(size 0.7112)
		(drill 0.3556)
		(layers "F.Cu" "B.Cu")
		(net "TMP3_SCL")
	)
	(segment
		(start 207.34909 -459.926436)
		(end 206.569564 -459.926436)
		(width 0.17145)
		(layer "F.Cu")
		(net "TMP2_SDA")
	)
	(segment
		(start 204.257402 -459.889098)
		(end 203.8985 -460.248)
		(width 0.17145)
		(layer "F.Cu")
		(net "TMP2_SDA")
	)
	(segment
		(start 205.127098 -459.889098)
		(end 204.257402 -459.889098)
		(width 0.17145)
		(layer "F.Cu")
		(net "TMP2_SDA")
	)
	(segment
		(start 208.4451 -459.975458)
		(end 207.398112 -459.975458)
		(width 0.17145)
		(layer "F.Cu")
		(net "TMP2_SDA")
	)
	(segment
		(start 207.398112 -459.975458)
		(end 207.34909 -459.926436)
		(width 0.17145)
		(layer "F.Cu")
		(net "TMP2_SDA")
	)
	(segment
		(start 206.569564 -459.926436)
		(end 205.867 -460.629)
		(width 0.17145)
		(layer "F.Cu")
		(net "TMP2_SDA")
	)
	(segment
		(start 205.867 -460.629)
		(end 205.127098 -459.889098)
		(width 0.17145)
		(layer "F.Cu")
		(net "TMP2_SDA")
	)
	(via
		(at 205.867 -460.629)
		(size 0.7112)
		(drill 0.3556)
		(layers "F.Cu" "B.Cu")
		(net "TMP2_SDA")
	)
	(segment
		(start 204.257148 -459.336648)
		(end 205.127352 -459.336648)
		(width 0.17145)
		(layer "F.Cu")
		(net "TMP2_SCL")
	)
	(segment
		(start 206.643986 -459.373986)
		(end 207.34909 -459.373986)
		(width 0.17145)
		(layer "F.Cu")
		(net "TMP2_SCL")
	)
	(segment
		(start 205.127352 -459.336648)
		(end 205.867 -458.597)
		(width 0.17145)
		(layer "F.Cu")
		(net "TMP2_SCL")
	)
	(segment
		(start 205.867 -458.597)
		(end 206.643986 -459.373986)
		(width 0.17145)
		(layer "F.Cu")
		(net "TMP2_SCL")
	)
	(segment
		(start 203.8985 -458.978)
		(end 204.257148 -459.336648)
		(width 0.17145)
		(layer "F.Cu")
		(net "TMP2_SCL")
	)
	(segment
		(start 207.34909 -459.373986)
		(end 207.397858 -459.325218)
		(width 0.17145)
		(layer "F.Cu")
		(net "TMP2_SCL")
	)
	(segment
		(start 207.397858 -459.325218)
		(end 208.4451 -459.325218)
		(width 0.17145)
		(layer "F.Cu")
		(net "TMP2_SCL")
	)
	(via
		(at 205.867 -458.597)
		(size 0.7112)
		(drill 0.3556)
		(layers "F.Cu" "B.Cu")
		(net "TMP2_SCL")
	)
	(segment
		(start 23.0378 -87.6935)
		(end 23.1648 -87.5665)
		(width 0.17145)
		(layer "F.Cu")
		(net "SW_SSD9_R")
	)
	(segment
		(start 23.0378 -88.7984)
		(end 23.6474 -88.7984)
		(width 0.17145)
		(layer "F.Cu")
		(net "SW_SSD9_R")
	)
	(segment
		(start 23.7998 -88.646)
		(end 24.3713 -88.646)
		(width 0.17145)
		(layer "F.Cu")
		(net "SW_SSD9_R")
	)
	(segment
		(start 23.6474 -88.7984)
		(end 23.7998 -88.646)
		(width 0.17145)
		(layer "F.Cu")
		(net "SW_SSD9_R")
	)
	(segment
		(start 24.3078 -89.2937)
		(end 24.3713 -89.2302)
		(width 0.17145)
		(layer "F.Cu")
		(net "SW_SSD9_R")
	)
	(segment
		(start 24.3713 -89.2302)
		(end 24.3713 -88.646)
		(width 0.17145)
		(layer "F.Cu")
		(net "SW_SSD9_R")
	)
	(segment
		(start 21.5138 -90.678)
		(end 21.9583 -90.2335)
		(width 0.17145)
		(layer "F.Cu")
		(net "SW_SSD9_R")
	)
	(segment
		(start 24.3078 -90.2335)
		(end 24.3078 -89.2937)
		(width 0.17145)
		(layer "F.Cu")
		(net "SW_SSD9_R")
	)
	(segment
		(start 23.0378 -88.7984)
		(end 23.0378 -87.6935)
		(width 0.17145)
		(layer "F.Cu")
		(net "SW_SSD9_R")
	)
	(segment
		(start 21.9583 -90.2335)
		(end 24.3078 -90.2335)
		(width 0.17145)
		(layer "F.Cu")
		(net "SW_SSD9_R")
	)
	(via
		(at 23.0378 -88.7984)
		(size 0.7112)
		(drill 0.3556)
		(layers "F.Cu" "B.Cu")
		(net "SW_SSD9_R")
	)
	(segment
		(start 26.162 -86.995)
		(end 25.8445 -86.6775)
		(width 0.17145)
		(layer "F.Cu")
		(net "SW_SSD9_N")
	)
	(segment
		(start 21.5138 -86.995)
		(end 21.8313 -86.6775)
		(width 0.17145)
		(layer "F.Cu")
		(net "SW_SSD9_N")
	)
	(segment
		(start 25.3238 -86.6775)
		(end 24.3078 -86.6775)
		(width 0.17145)
		(layer "F.Cu")
		(net "SW_SSD9_N")
	)
	(segment
		(start 27.2288 -86.995)
		(end 26.162 -86.995)
		(width 0.17145)
		(layer "F.Cu")
		(net "SW_SSD9_N")
	)
	(segment
		(start 21.5138 -88.392)
		(end 21.5138 -86.995)
		(width 0.17145)
		(layer "F.Cu")
		(net "SW_SSD9_N")
	)
	(segment
		(start 24.3078 -86.6775)
		(end 23.1648 -86.6775)
		(width 0.17145)
		(layer "F.Cu")
		(net "SW_SSD9_N")
	)
	(segment
		(start 25.8445 -86.6775)
		(end 25.3238 -86.6775)
		(width 0.17145)
		(layer "F.Cu")
		(net "SW_SSD9_N")
	)
	(segment
		(start 23.1648 -86.6775)
		(end 21.8313 -86.6775)
		(width 0.17145)
		(layer "F.Cu")
		(net "SW_SSD9_N")
	)
	(via
		(at 21.8313 -86.6775)
		(size 0.7112)
		(drill 0.3556)
		(layers "F.Cu" "B.Cu")
		(net "SW_SSD9_N")
	)
	(segment
		(start 23.0378 -191.7954)
		(end 23.6474 -191.7954)
		(width 0.17145)
		(layer "F.Cu")
		(net "SW_SSD8_R")
	)
	(segment
		(start 24.3713 -191.643)
		(end 24.3713 -193.167)
		(width 0.17145)
		(layer "F.Cu")
		(net "SW_SSD8_R")
	)
	(segment
		(start 21.5138 -193.675)
		(end 23.8633 -193.675)
		(width 0.17145)
		(layer "F.Cu")
		(net "SW_SSD8_R")
	)
	(segment
		(start 23.0378 -191.7954)
		(end 23.0378 -190.6905)
		(width 0.17145)
		(layer "F.Cu")
		(net "SW_SSD8_R")
	)
	(segment
		(start 23.8633 -193.675)
		(end 24.3078 -193.2305)
		(width 0.17145)
		(layer "F.Cu")
		(net "SW_SSD8_R")
	)
	(segment
		(start 24.3713 -193.167)
		(end 24.3078 -193.2305)
		(width 0.17145)
		(layer "F.Cu")
		(net "SW_SSD8_R")
	)
	(segment
		(start 23.7998 -191.643)
		(end 24.3713 -191.643)
		(width 0.17145)
		(layer "F.Cu")
		(net "SW_SSD8_R")
	)
	(segment
		(start 23.6474 -191.7954)
		(end 23.7998 -191.643)
		(width 0.17145)
		(layer "F.Cu")
		(net "SW_SSD8_R")
	)
	(segment
		(start 23.0378 -190.6905)
		(end 23.1648 -190.5635)
		(width 0.17145)
		(layer "F.Cu")
		(net "SW_SSD8_R")
	)
	(via
		(at 23.0378 -191.7954)
		(size 0.7112)
		(drill 0.3556)
		(layers "F.Cu" "B.Cu")
		(net "SW_SSD8_R")
	)
	(segment
		(start 23.1648 -189.6745)
		(end 21.8313 -189.6745)
		(width 0.17145)
		(layer "F.Cu")
		(net "SW_SSD8_N")
	)
	(segment
		(start 21.5138 -191.389)
		(end 21.5138 -189.992)
		(width 0.17145)
		(layer "F.Cu")
		(net "SW_SSD8_N")
	)
	(segment
		(start 27.2288 -189.992)
		(end 26.1874 -189.992)
		(width 0.17145)
		(layer "F.Cu")
		(net "SW_SSD8_N")
	)
	(segment
		(start 25.3238 -189.6745)
		(end 24.3078 -189.6745)
		(width 0.17145)
		(layer "F.Cu")
		(net "SW_SSD8_N")
	)
	(segment
		(start 26.1874 -189.992)
		(end 25.8699 -189.6745)
		(width 0.17145)
		(layer "F.Cu")
		(net "SW_SSD8_N")
	)
	(segment
		(start 24.3078 -189.6745)
		(end 23.1648 -189.6745)
		(width 0.17145)
		(layer "F.Cu")
		(net "SW_SSD8_N")
	)
	(segment
		(start 25.8699 -189.6745)
		(end 25.3238 -189.6745)
		(width 0.17145)
		(layer "F.Cu")
		(net "SW_SSD8_N")
	)
	(segment
		(start 21.5138 -189.992)
		(end 21.8313 -189.6745)
		(width 0.17145)
		(layer "F.Cu")
		(net "SW_SSD8_N")
	)
	(via
		(at 21.8313 -189.6745)
		(size 0.7112)
		(drill 0.3556)
		(layers "F.Cu" "B.Cu")
		(net "SW_SSD8_N")
	)
	(segment
		(start 23.0378 -294.894)
		(end 23.0378 -293.7891)
		(width 0.17145)
		(layer "F.Cu")
		(net "SW_SSD7_R")
	)
	(segment
		(start 23.0378 -293.7891)
		(end 23.1648 -293.6621)
		(width 0.17145)
		(layer "F.Cu")
		(net "SW_SSD7_R")
	)
	(segment
		(start 24.3078 -296.3291)
		(end 24.3078 -295.3893)
		(width 0.17145)
		(layer "F.Cu")
		(net "SW_SSD7_R")
	)
	(segment
		(start 23.0378 -294.894)
		(end 23.6474 -294.894)
		(width 0.17145)
		(layer "F.Cu")
		(net "SW_SSD7_R")
	)
	(segment
		(start 21.5138 -296.7736)
		(end 23.8633 -296.7736)
		(width 0.17145)
		(layer "F.Cu")
		(net "SW_SSD7_R")
	)
	(segment
		(start 23.8633 -296.7736)
		(end 24.3078 -296.3291)
		(width 0.17145)
		(layer "F.Cu")
		(net "SW_SSD7_R")
	)
	(segment
		(start 24.3078 -295.3893)
		(end 24.3713 -295.3258)
		(width 0.17145)
		(layer "F.Cu")
		(net "SW_SSD7_R")
	)
	(segment
		(start 24.3713 -295.3258)
		(end 24.3713 -294.7416)
		(width 0.17145)
		(layer "F.Cu")
		(net "SW_SSD7_R")
	)
	(segment
		(start 23.7998 -294.7416)
		(end 24.3713 -294.7416)
		(width 0.17145)
		(layer "F.Cu")
		(net "SW_SSD7_R")
	)
	(segment
		(start 23.6474 -294.894)
		(end 23.7998 -294.7416)
		(width 0.17145)
		(layer "F.Cu")
		(net "SW_SSD7_R")
	)
	(via
		(at 23.0378 -294.894)
		(size 0.7112)
		(drill 0.3556)
		(layers "F.Cu" "B.Cu")
		(net "SW_SSD7_R")
	)
	(segment
		(start 26.1366 -293.0906)
		(end 25.8191 -292.7731)
		(width 0.17145)
		(layer "F.Cu")
		(net "SW_SSD7_N")
	)
	(segment
		(start 23.1648 -292.7731)
		(end 21.8313 -292.7731)
		(width 0.17145)
		(layer "F.Cu")
		(net "SW_SSD7_N")
	)
	(segment
		(start 25.8191 -292.7731)
		(end 25.3238 -292.7731)
		(width 0.17145)
		(layer "F.Cu")
		(net "SW_SSD7_N")
	)
	(segment
		(start 21.5138 -294.4876)
		(end 21.5138 -293.0906)
		(width 0.17145)
		(layer "F.Cu")
		(net "SW_SSD7_N")
	)
	(segment
		(start 24.3078 -292.7731)
		(end 23.1648 -292.7731)
		(width 0.17145)
		(layer "F.Cu")
		(net "SW_SSD7_N")
	)
	(segment
		(start 21.5138 -293.0906)
		(end 21.8313 -292.7731)
		(width 0.17145)
		(layer "F.Cu")
		(net "SW_SSD7_N")
	)
	(segment
		(start 27.2288 -293.0906)
		(end 26.1366 -293.0906)
		(width 0.17145)
		(layer "F.Cu")
		(net "SW_SSD7_N")
	)
	(segment
		(start 25.3238 -292.7731)
		(end 24.3078 -292.7731)
		(width 0.17145)
		(layer "F.Cu")
		(net "SW_SSD7_N")
	)
	(via
		(at 21.8313 -292.7731)
		(size 0.7112)
		(drill 0.3556)
		(layers "F.Cu" "B.Cu")
		(net "SW_SSD7_N")
	)
	(segment
		(start 22.0472 -397.383)
		(end 22.4917 -396.9385)
		(width 0.17145)
		(layer "F.Cu")
		(net "SW_SSD6_R")
	)
	(segment
		(start 22.987 -394.2715)
		(end 22.86 -394.3985)
		(width 0.17145)
		(layer "F.Cu")
		(net "SW_SSD6_R")
	)
	(segment
		(start 21.336 -397.383)
		(end 22.0472 -397.383)
		(width 0.17145)
		(layer "F.Cu")
		(net "SW_SSD6_R")
	)
	(segment
		(start 24.1935 -395.351)
		(end 23.622 -395.351)
		(width 0.17145)
		(layer "F.Cu")
		(net "SW_SSD6_R")
	)
	(segment
		(start 23.622 -395.351)
		(end 23.4696 -395.5034)
		(width 0.17145)
		(layer "F.Cu")
		(net "SW_SSD6_R")
	)
	(segment
		(start 22.86 -394.3985)
		(end 22.86 -395.4272)
		(width 0.17145)
		(layer "F.Cu")
		(net "SW_SSD6_R")
	)
	(segment
		(start 22.86 -395.4272)
		(end 22.9362 -395.5034)
		(width 0.17145)
		(layer "F.Cu")
		(net "SW_SSD6_R")
	)
	(segment
		(start 24.1935 -396.875)
		(end 24.1935 -395.351)
		(width 0.17145)
		(layer "F.Cu")
		(net "SW_SSD6_R")
	)
	(segment
		(start 24.13 -396.9385)
		(end 24.1935 -396.875)
		(width 0.17145)
		(layer "F.Cu")
		(net "SW_SSD6_R")
	)
	(segment
		(start 23.4696 -395.5034)
		(end 22.9362 -395.5034)
		(width 0.17145)
		(layer "F.Cu")
		(net "SW_SSD6_R")
	)
	(segment
		(start 22.4917 -396.9385)
		(end 24.13 -396.9385)
		(width 0.17145)
		(layer "F.Cu")
		(net "SW_SSD6_R")
	)
	(via
		(at 22.9362 -395.5034)
		(size 0.7112)
		(drill 0.3556)
		(layers "F.Cu" "B.Cu")
		(net "SW_SSD6_R")
	)
	(segment
		(start 26.1366 -394.2842)
		(end 26.5938 -394.7414)
		(width 0.17145)
		(layer "F.Cu")
		(net "SW_SSD6_N")
	)
	(segment
		(start 26.1366 -393.954)
		(end 26.1366 -394.2842)
		(width 0.17145)
		(layer "F.Cu")
		(net "SW_SSD6_N")
	)
	(segment
		(start 26.5938 -394.7414)
		(end 27.1018 -394.7414)
		(width 0.17145)
		(layer "F.Cu")
		(net "SW_SSD6_N")
	)
	(segment
		(start 25.5651 -393.3825)
		(end 26.1366 -393.954)
		(width 0.17145)
		(layer "F.Cu")
		(net "SW_SSD6_N")
	)
	(segment
		(start 22.987 -393.3825)
		(end 21.6535 -393.3825)
		(width 0.17145)
		(layer "F.Cu")
		(net "SW_SSD6_N")
	)
	(segment
		(start 24.13 -393.3825)
		(end 22.987 -393.3825)
		(width 0.17145)
		(layer "F.Cu")
		(net "SW_SSD6_N")
	)
	(segment
		(start 21.336 -395.097)
		(end 21.336 -393.7)
		(width 0.17145)
		(layer "F.Cu")
		(net "SW_SSD6_N")
	)
	(segment
		(start 25.146 -393.3825)
		(end 25.5651 -393.3825)
		(width 0.17145)
		(layer "F.Cu")
		(net "SW_SSD6_N")
	)
	(segment
		(start 21.336 -393.7)
		(end 21.6535 -393.3825)
		(width 0.17145)
		(layer "F.Cu")
		(net "SW_SSD6_N")
	)
	(segment
		(start 25.146 -393.3825)
		(end 24.13 -393.3825)
		(width 0.17145)
		(layer "F.Cu")
		(net "SW_SSD6_N")
	)
	(via
		(at 21.6535 -393.3825)
		(size 0.7112)
		(drill 0.3556)
		(layers "F.Cu" "B.Cu")
		(net "SW_SSD6_N")
	)
	(segment
		(start 15.367 -493.0394)
		(end 15.367 -491.9345)
		(width 0.17145)
		(layer "F.Cu")
		(net "SW_SSD5_R")
	)
	(segment
		(start 16.129 -492.887)
		(end 16.7005 -492.887)
		(width 0.17145)
		(layer "F.Cu")
		(net "SW_SSD5_R")
	)
	(segment
		(start 16.7005 -494.411)
		(end 16.7005 -492.887)
		(width 0.17145)
		(layer "F.Cu")
		(net "SW_SSD5_R")
	)
	(segment
		(start 15.367 -491.9345)
		(end 15.494 -491.8075)
		(width 0.17145)
		(layer "F.Cu")
		(net "SW_SSD5_R")
	)
	(segment
		(start 16.637 -494.4745)
		(end 16.7005 -494.411)
		(width 0.17145)
		(layer "F.Cu")
		(net "SW_SSD5_R")
	)
	(segment
		(start 13.843 -494.919)
		(end 16.1925 -494.919)
		(width 0.17145)
		(layer "F.Cu")
		(net "SW_SSD5_R")
	)
	(segment
		(start 15.367 -493.0394)
		(end 15.9766 -493.0394)
		(width 0.17145)
		(layer "F.Cu")
		(net "SW_SSD5_R")
	)
	(segment
		(start 15.9766 -493.0394)
		(end 16.129 -492.887)
		(width 0.17145)
		(layer "F.Cu")
		(net "SW_SSD5_R")
	)
	(segment
		(start 16.1925 -494.919)
		(end 16.637 -494.4745)
		(width 0.17145)
		(layer "F.Cu")
		(net "SW_SSD5_R")
	)
	(via
		(at 15.367 -493.0394)
		(size 0.7112)
		(drill 0.3556)
		(layers "F.Cu" "B.Cu")
		(net "SW_SSD5_R")
	)
	(segment
		(start 13.843 -492.633)
		(end 13.843 -491.236)
		(width 0.17145)
		(layer "F.Cu")
		(net "SW_SSD5_N")
	)
	(segment
		(start 16.637 -490.9185)
		(end 17.653 -490.9185)
		(width 0.17145)
		(layer "F.Cu")
		(net "SW_SSD5_N")
	)
	(segment
		(start 13.843 -491.236)
		(end 14.1605 -490.9185)
		(width 0.17145)
		(layer "F.Cu")
		(net "SW_SSD5_N")
	)
	(segment
		(start 20.193 -491.236)
		(end 19.05 -491.236)
		(width 0.17145)
		(layer "F.Cu")
		(net "SW_SSD5_N")
	)
	(segment
		(start 15.494 -490.9185)
		(end 16.637 -490.9185)
		(width 0.17145)
		(layer "F.Cu")
		(net "SW_SSD5_N")
	)
	(segment
		(start 19.05 -491.236)
		(end 18.7325 -490.9185)
		(width 0.17145)
		(layer "F.Cu")
		(net "SW_SSD5_N")
	)
	(segment
		(start 18.7325 -490.9185)
		(end 17.653 -490.9185)
		(width 0.17145)
		(layer "F.Cu")
		(net "SW_SSD5_N")
	)
	(segment
		(start 14.1605 -490.9185)
		(end 15.494 -490.9185)
		(width 0.17145)
		(layer "F.Cu")
		(net "SW_SSD5_N")
	)
	(via
		(at 14.1605 -490.9185)
		(size 0.7112)
		(drill 0.3556)
		(layers "F.Cu" "B.Cu")
		(net "SW_SSD5_N")
	)
	(segment
		(start 208.153 -87.5665)
		(end 208.026 -87.6935)
		(width 0.17145)
		(layer "F.Cu")
		(net "SW_SSD4_R")
	)
	(segment
		(start 208.6356 -88.7984)
		(end 208.788 -88.646)
		(width 0.17145)
		(layer "F.Cu")
		(net "SW_SSD4_R")
	)
	(segment
		(start 209.3595 -90.17)
		(end 209.296 -90.2335)
		(width 0.17145)
		(layer "F.Cu")
		(net "SW_SSD4_R")
	)
	(segment
		(start 208.8515 -90.678)
		(end 209.296 -90.2335)
		(width 0.17145)
		(layer "F.Cu")
		(net "SW_SSD4_R")
	)
	(segment
		(start 208.026 -88.7984)
		(end 208.6356 -88.7984)
		(width 0.17145)
		(layer "F.Cu")
		(net "SW_SSD4_R")
	)
	(segment
		(start 209.3595 -88.646)
		(end 209.3595 -90.17)
		(width 0.17145)
		(layer "F.Cu")
		(net "SW_SSD4_R")
	)
	(segment
		(start 206.502 -90.678)
		(end 208.8515 -90.678)
		(width 0.17145)
		(layer "F.Cu")
		(net "SW_SSD4_R")
	)
	(segment
		(start 208.026 -87.6935)
		(end 208.026 -88.7984)
		(width 0.17145)
		(layer "F.Cu")
		(net "SW_SSD4_R")
	)
	(segment
		(start 208.788 -88.646)
		(end 209.3595 -88.646)
		(width 0.17145)
		(layer "F.Cu")
		(net "SW_SSD4_R")
	)
	(via
		(at 208.026 -88.7984)
		(size 0.7112)
		(drill 0.3556)
		(layers "F.Cu" "B.Cu")
		(net "SW_SSD4_R")
	)
	(segment
		(start 210.312 -86.6775)
		(end 210.8327 -86.6775)
		(width 0.17145)
		(layer "F.Cu")
		(net "SW_SSD4_N")
	)
	(segment
		(start 208.153 -86.6775)
		(end 206.8195 -86.6775)
		(width 0.17145)
		(layer "F.Cu")
		(net "SW_SSD4_N")
	)
	(segment
		(start 209.296 -86.6775)
		(end 210.312 -86.6775)
		(width 0.17145)
		(layer "F.Cu")
		(net "SW_SSD4_N")
	)
	(segment
		(start 211.1502 -86.995)
		(end 212.217 -86.995)
		(width 0.17145)
		(layer "F.Cu")
		(net "SW_SSD4_N")
	)
	(segment
		(start 206.502 -86.995)
		(end 206.8195 -86.6775)
		(width 0.17145)
		(layer "F.Cu")
		(net "SW_SSD4_N")
	)
	(segment
		(start 206.502 -88.392)
		(end 206.502 -86.995)
		(width 0.17145)
		(layer "F.Cu")
		(net "SW_SSD4_N")
	)
	(segment
		(start 210.8327 -86.6775)
		(end 211.1502 -86.995)
		(width 0.17145)
		(layer "F.Cu")
		(net "SW_SSD4_N")
	)
	(segment
		(start 208.153 -86.6775)
		(end 209.296 -86.6775)
		(width 0.17145)
		(layer "F.Cu")
		(net "SW_SSD4_N")
	)
	(via
		(at 206.8195 -86.6775)
		(size 0.7112)
		(drill 0.3556)
		(layers "F.Cu" "B.Cu")
		(net "SW_SSD4_N")
	)
	(segment
		(start 209.3595 -193.167)
		(end 209.296 -193.2305)
		(width 0.17145)
		(layer "F.Cu")
		(net "SW_SSD3_R")
	)
	(segment
		(start 208.026 -191.7954)
		(end 208.6356 -191.7954)
		(width 0.17145)
		(layer "F.Cu")
		(net "SW_SSD3_R")
	)
	(segment
		(start 208.8515 -193.675)
		(end 209.296 -193.2305)
		(width 0.17145)
		(layer "F.Cu")
		(net "SW_SSD3_R")
	)
	(segment
		(start 208.153 -190.5635)
		(end 208.026 -190.6905)
		(width 0.17145)
		(layer "F.Cu")
		(net "SW_SSD3_R")
	)
	(segment
		(start 208.026 -190.6905)
		(end 208.026 -191.7954)
		(width 0.17145)
		(layer "F.Cu")
		(net "SW_SSD3_R")
	)
	(segment
		(start 208.6356 -191.7954)
		(end 208.788 -191.643)
		(width 0.17145)
		(layer "F.Cu")
		(net "SW_SSD3_R")
	)
	(segment
		(start 209.3595 -191.643)
		(end 209.3595 -193.167)
		(width 0.17145)
		(layer "F.Cu")
		(net "SW_SSD3_R")
	)
	(segment
		(start 208.788 -191.643)
		(end 209.3595 -191.643)
		(width 0.17145)
		(layer "F.Cu")
		(net "SW_SSD3_R")
	)
	(segment
		(start 206.502 -193.675)
		(end 208.8515 -193.675)
		(width 0.17145)
		(layer "F.Cu")
		(net "SW_SSD3_R")
	)
	(via
		(at 208.026 -191.7954)
		(size 0.7112)
		(drill 0.3556)
		(layers "F.Cu" "B.Cu")
		(net "SW_SSD3_R")
	)
	(segment
		(start 206.502 -191.389)
		(end 206.502 -189.992)
		(width 0.17145)
		(layer "F.Cu")
		(net "SW_SSD3_N")
	)
	(segment
		(start 206.502 -189.992)
		(end 206.8195 -189.6745)
		(width 0.17145)
		(layer "F.Cu")
		(net "SW_SSD3_N")
	)
	(segment
		(start 209.296 -189.6745)
		(end 210.312 -189.6745)
		(width 0.17145)
		(layer "F.Cu")
		(net "SW_SSD3_N")
	)
	(segment
		(start 208.153 -189.6745)
		(end 206.8195 -189.6745)
		(width 0.17145)
		(layer "F.Cu")
		(net "SW_SSD3_N")
	)
	(segment
		(start 211.1502 -189.992)
		(end 212.217 -189.992)
		(width 0.17145)
		(layer "F.Cu")
		(net "SW_SSD3_N")
	)
	(segment
		(start 208.153 -189.6745)
		(end 209.296 -189.6745)
		(width 0.17145)
		(layer "F.Cu")
		(net "SW_SSD3_N")
	)
	(segment
		(start 210.312 -189.6745)
		(end 210.8327 -189.6745)
		(width 0.17145)
		(layer "F.Cu")
		(net "SW_SSD3_N")
	)
	(segment
		(start 210.8327 -189.6745)
		(end 211.1502 -189.992)
		(width 0.17145)
		(layer "F.Cu")
		(net "SW_SSD3_N")
	)
	(via
		(at 206.8195 -189.6745)
		(size 0.7112)
		(drill 0.3556)
		(layers "F.Cu" "B.Cu")
		(net "SW_SSD3_N")
	)
	(segment
		(start 208.153 -293.5605)
		(end 208.026 -293.6875)
		(width 0.17145)
		(layer "F.Cu")
		(net "SW_SSD2_R")
	)
	(segment
		(start 208.026 -294.7924)
		(end 208.6356 -294.7924)
		(width 0.17145)
		(layer "F.Cu")
		(net "SW_SSD2_R")
	)
	(segment
		(start 208.8515 -296.672)
		(end 209.296 -296.2275)
		(width 0.17145)
		(layer "F.Cu")
		(net "SW_SSD2_R")
	)
	(segment
		(start 208.026 -293.6875)
		(end 208.026 -294.7924)
		(width 0.17145)
		(layer "F.Cu")
		(net "SW_SSD2_R")
	)
	(segment
		(start 208.788 -294.64)
		(end 209.3595 -294.64)
		(width 0.17145)
		(layer "F.Cu")
		(net "SW_SSD2_R")
	)
	(segment
		(start 209.3595 -296.164)
		(end 209.296 -296.2275)
		(width 0.17145)
		(layer "F.Cu")
		(net "SW_SSD2_R")
	)
	(segment
		(start 206.502 -296.672)
		(end 208.8515 -296.672)
		(width 0.17145)
		(layer "F.Cu")
		(net "SW_SSD2_R")
	)
	(segment
		(start 208.6356 -294.7924)
		(end 208.788 -294.64)
		(width 0.17145)
		(layer "F.Cu")
		(net "SW_SSD2_R")
	)
	(segment
		(start 209.3595 -294.64)
		(end 209.3595 -296.164)
		(width 0.17145)
		(layer "F.Cu")
		(net "SW_SSD2_R")
	)
	(via
		(at 208.026 -294.7924)
		(size 0.7112)
		(drill 0.3556)
		(layers "F.Cu" "B.Cu")
		(net "SW_SSD2_R")
	)
	(segment
		(start 208.153 -292.6715)
		(end 209.296 -292.6715)
		(width 0.17145)
		(layer "F.Cu")
		(net "SW_SSD2_N")
	)
	(segment
		(start 206.502 -292.989)
		(end 206.8195 -292.6715)
		(width 0.17145)
		(layer "F.Cu")
		(net "SW_SSD2_N")
	)
	(segment
		(start 210.312 -292.6715)
		(end 210.8327 -292.6715)
		(width 0.17145)
		(layer "F.Cu")
		(net "SW_SSD2_N")
	)
	(segment
		(start 206.502 -294.386)
		(end 206.502 -292.989)
		(width 0.17145)
		(layer "F.Cu")
		(net "SW_SSD2_N")
	)
	(segment
		(start 210.8327 -292.6715)
		(end 211.1502 -292.989)
		(width 0.17145)
		(layer "F.Cu")
		(net "SW_SSD2_N")
	)
	(segment
		(start 211.1502 -292.989)
		(end 212.217 -292.989)
		(width 0.17145)
		(layer "F.Cu")
		(net "SW_SSD2_N")
	)
	(segment
		(start 208.153 -292.6715)
		(end 206.8195 -292.6715)
		(width 0.17145)
		(layer "F.Cu")
		(net "SW_SSD2_N")
	)
	(segment
		(start 209.296 -292.6715)
		(end 210.312 -292.6715)
		(width 0.17145)
		(layer "F.Cu")
		(net "SW_SSD2_N")
	)
	(via
		(at 206.8195 -292.6715)
		(size 0.7112)
		(drill 0.3556)
		(layers "F.Cu" "B.Cu")
		(net "SW_SSD2_N")
	)
	(segment
		(start 50.6984 -13.1826)
		(end 50.546 -13.335)
		(width 0.17145)
		(layer "F.Cu")
		(net "SW_SSD14_R")
	)
	(segment
		(start 51.181 -14.4145)
		(end 51.308 -14.2875)
		(width 0.17145)
		(layer "F.Cu")
		(net "SW_SSD14_R")
	)
	(segment
		(start 50.4825 -11.303)
		(end 50.038 -11.7475)
		(width 0.17145)
		(layer "F.Cu")
		(net "SW_SSD14_R")
	)
	(segment
		(start 51.2064 -13.1826)
		(end 50.6984 -13.1826)
		(width 0.17145)
		(layer "F.Cu")
		(net "SW_SSD14_R")
	)
	(segment
		(start 50.038 -11.7475)
		(end 49.9745 -11.811)
		(width 0.17145)
		(layer "F.Cu")
		(net "SW_SSD14_R")
	)
	(segment
		(start 51.308 -14.2875)
		(end 51.308 -13.2842)
		(width 0.17145)
		(layer "F.Cu")
		(net "SW_SSD14_R")
	)
	(segment
		(start 51.308 -13.2842)
		(end 51.2064 -13.1826)
		(width 0.17145)
		(layer "F.Cu")
		(net "SW_SSD14_R")
	)
	(segment
		(start 49.9745 -11.811)
		(end 49.9745 -13.335)
		(width 0.17145)
		(layer "F.Cu")
		(net "SW_SSD14_R")
	)
	(segment
		(start 50.546 -13.335)
		(end 49.9745 -13.335)
		(width 0.17145)
		(layer "F.Cu")
		(net "SW_SSD14_R")
	)
	(segment
		(start 52.832 -11.303)
		(end 50.4825 -11.303)
		(width 0.17145)
		(layer "F.Cu")
		(net "SW_SSD14_R")
	)
	(via
		(at 51.2064 -13.1826)
		(size 0.7112)
		(drill 0.3556)
		(layers "F.Cu" "B.Cu")
		(net "SW_SSD14_R")
	)
	(segment
		(start 52.832 -13.589)
		(end 52.832 -14.986)
		(width 0.17145)
		(layer "F.Cu")
		(net "SW_SSD14_N")
	)
	(segment
		(start 49.022 -15.3035)
		(end 48.4505 -15.3035)
		(width 0.17145)
		(layer "F.Cu")
		(net "SW_SSD14_N")
	)
	(segment
		(start 48.133 -14.986)
		(end 47.117 -14.986)
		(width 0.17145)
		(layer "F.Cu")
		(net "SW_SSD14_N")
	)
	(segment
		(start 50.038 -15.3035)
		(end 49.022 -15.3035)
		(width 0.17145)
		(layer "F.Cu")
		(net "SW_SSD14_N")
	)
	(segment
		(start 51.181 -15.3035)
		(end 50.038 -15.3035)
		(width 0.17145)
		(layer "F.Cu")
		(net "SW_SSD14_N")
	)
	(segment
		(start 52.832 -14.986)
		(end 52.5145 -15.3035)
		(width 0.17145)
		(layer "F.Cu")
		(net "SW_SSD14_N")
	)
	(segment
		(start 52.5145 -15.3035)
		(end 51.181 -15.3035)
		(width 0.17145)
		(layer "F.Cu")
		(net "SW_SSD14_N")
	)
	(segment
		(start 48.4505 -15.3035)
		(end 48.133 -14.986)
		(width 0.17145)
		(layer "F.Cu")
		(net "SW_SSD14_N")
	)
	(via
		(at 52.5145 -15.3035)
		(size 0.7112)
		(drill 0.3556)
		(layers "F.Cu" "B.Cu")
		(net "SW_SSD14_N")
	)
	(segment
		(start 38.2016 -108.3564)
		(end 37.6301 -108.3564)
		(width 0.17145)
		(layer "F.Cu")
		(net "SW_SSD13_R")
	)
	(segment
		(start 40.4876 -106.3244)
		(end 38.1381 -106.3244)
		(width 0.17145)
		(layer "F.Cu")
		(net "SW_SSD13_R")
	)
	(segment
		(start 37.6301 -107.7214)
		(end 37.6301 -108.3564)
		(width 0.17145)
		(layer "F.Cu")
		(net "SW_SSD13_R")
	)
	(segment
		(start 37.6936 -107.6579)
		(end 37.6301 -107.7214)
		(width 0.17145)
		(layer "F.Cu")
		(net "SW_SSD13_R")
	)
	(segment
		(start 38.9636 -108.204)
		(end 38.354 -108.204)
		(width 0.17145)
		(layer "F.Cu")
		(net "SW_SSD13_R")
	)
	(segment
		(start 38.354 -108.204)
		(end 38.2016 -108.3564)
		(width 0.17145)
		(layer "F.Cu")
		(net "SW_SSD13_R")
	)
	(segment
		(start 37.6936 -106.7689)
		(end 37.6936 -107.6579)
		(width 0.17145)
		(layer "F.Cu")
		(net "SW_SSD13_R")
	)
	(segment
		(start 38.9636 -108.204)
		(end 38.9636 -109.3089)
		(width 0.17145)
		(layer "F.Cu")
		(net "SW_SSD13_R")
	)
	(segment
		(start 38.9636 -109.3089)
		(end 38.8366 -109.4359)
		(width 0.17145)
		(layer "F.Cu")
		(net "SW_SSD13_R")
	)
	(segment
		(start 38.1381 -106.3244)
		(end 37.6936 -106.7689)
		(width 0.17145)
		(layer "F.Cu")
		(net "SW_SSD13_R")
	)
	(via
		(at 38.9636 -108.204)
		(size 0.7112)
		(drill 0.3556)
		(layers "F.Cu" "B.Cu")
		(net "SW_SSD13_R")
	)
	(segment
		(start 36.1061 -110.3249)
		(end 35.7886 -110.0074)
		(width 0.17145)
		(layer "F.Cu")
		(net "SW_SSD13_N")
	)
	(segment
		(start 40.4876 -108.6104)
		(end 40.4876 -110.0074)
		(width 0.17145)
		(layer "F.Cu")
		(net "SW_SSD13_N")
	)
	(segment
		(start 38.8366 -110.3249)
		(end 37.6936 -110.3249)
		(width 0.17145)
		(layer "F.Cu")
		(net "SW_SSD13_N")
	)
	(segment
		(start 37.6936 -110.3249)
		(end 36.6776 -110.3249)
		(width 0.17145)
		(layer "F.Cu")
		(net "SW_SSD13_N")
	)
	(segment
		(start 40.1701 -110.3249)
		(end 38.8366 -110.3249)
		(width 0.17145)
		(layer "F.Cu")
		(net "SW_SSD13_N")
	)
	(segment
		(start 35.7886 -110.0074)
		(end 34.7726 -110.0074)
		(width 0.17145)
		(layer "F.Cu")
		(net "SW_SSD13_N")
	)
	(segment
		(start 36.6776 -110.3249)
		(end 36.1061 -110.3249)
		(width 0.17145)
		(layer "F.Cu")
		(net "SW_SSD13_N")
	)
	(segment
		(start 40.4876 -110.0074)
		(end 40.1701 -110.3249)
		(width 0.17145)
		(layer "F.Cu")
		(net "SW_SSD13_N")
	)
	(via
		(at 40.1701 -110.3249)
		(size 0.7112)
		(drill 0.3556)
		(layers "F.Cu" "B.Cu")
		(net "SW_SSD13_N")
	)
	(segment
		(start 38.9636 -211.0994)
		(end 38.9636 -212.3059)
		(width 0.17145)
		(layer "F.Cu")
		(net "SW_SSD12_R")
	)
	(segment
		(start 38.2016 -211.3534)
		(end 38.4556 -211.0994)
		(width 0.17145)
		(layer "F.Cu")
		(net "SW_SSD12_R")
	)
	(segment
		(start 40.4876 -209.3214)
		(end 38.1381 -209.3214)
		(width 0.17145)
		(layer "F.Cu")
		(net "SW_SSD12_R")
	)
	(segment
		(start 38.4556 -211.0994)
		(end 38.9636 -211.0994)
		(width 0.17145)
		(layer "F.Cu")
		(net "SW_SSD12_R")
	)
	(segment
		(start 37.6301 -211.3534)
		(end 38.2016 -211.3534)
		(width 0.17145)
		(layer "F.Cu")
		(net "SW_SSD12_R")
	)
	(segment
		(start 38.1381 -209.3214)
		(end 37.6936 -209.7659)
		(width 0.17145)
		(layer "F.Cu")
		(net "SW_SSD12_R")
	)
	(segment
		(start 37.6301 -209.8294)
		(end 37.6301 -211.3534)
		(width 0.17145)
		(layer "F.Cu")
		(net "SW_SSD12_R")
	)
	(segment
		(start 37.6936 -209.7659)
		(end 37.6301 -209.8294)
		(width 0.17145)
		(layer "F.Cu")
		(net "SW_SSD12_R")
	)
	(segment
		(start 38.9636 -212.3059)
		(end 38.8366 -212.4329)
		(width 0.17145)
		(layer "F.Cu")
		(net "SW_SSD12_R")
	)
	(via
		(at 38.9636 -211.0994)
		(size 0.7112)
		(drill 0.3556)
		(layers "F.Cu" "B.Cu")
		(net "SW_SSD12_R")
	)
	(segment
		(start 36.1061 -213.3219)
		(end 35.7886 -213.0044)
		(width 0.17145)
		(layer "F.Cu")
		(net "SW_SSD12_N")
	)
	(segment
		(start 40.1701 -213.3219)
		(end 38.8366 -213.3219)
		(width 0.17145)
		(layer "F.Cu")
		(net "SW_SSD12_N")
	)
	(segment
		(start 35.7886 -213.0044)
		(end 34.7726 -213.0044)
		(width 0.17145)
		(layer "F.Cu")
		(net "SW_SSD12_N")
	)
	(segment
		(start 40.4876 -211.6074)
		(end 40.4876 -213.0044)
		(width 0.17145)
		(layer "F.Cu")
		(net "SW_SSD12_N")
	)
	(segment
		(start 40.4876 -213.0044)
		(end 40.1701 -213.3219)
		(width 0.17145)
		(layer "F.Cu")
		(net "SW_SSD12_N")
	)
	(segment
		(start 37.6936 -213.3219)
		(end 36.6776 -213.3219)
		(width 0.17145)
		(layer "F.Cu")
		(net "SW_SSD12_N")
	)
	(segment
		(start 36.6776 -213.3219)
		(end 36.1061 -213.3219)
		(width 0.17145)
		(layer "F.Cu")
		(net "SW_SSD12_N")
	)
	(segment
		(start 38.8366 -213.3219)
		(end 37.6936 -213.3219)
		(width 0.17145)
		(layer "F.Cu")
		(net "SW_SSD12_N")
	)
	(via
		(at 40.1701 -213.3219)
		(size 0.7112)
		(drill 0.3556)
		(layers "F.Cu" "B.Cu")
		(net "SW_SSD12_N")
	)
	(segment
		(start 37.7698 -312.7629)
		(end 37.7698 -312.9153)
		(width 0.17145)
		(layer "F.Cu")
		(net "SW_SSD11_R")
	)
	(segment
		(start 38.2143 -312.3184)
		(end 37.7698 -312.7629)
		(width 0.17145)
		(layer "F.Cu")
		(net "SW_SSD11_R")
	)
	(segment
		(start 38.4302 -314.198)
		(end 38.2778 -314.3504)
		(width 0.17145)
		(layer "F.Cu")
		(net "SW_SSD11_R")
	)
	(segment
		(start 40.5638 -312.3184)
		(end 38.2143 -312.3184)
		(width 0.17145)
		(layer "F.Cu")
		(net "SW_SSD11_R")
	)
	(segment
		(start 39.0398 -315.3029)
		(end 38.9128 -315.4299)
		(width 0.17145)
		(layer "F.Cu")
		(net "SW_SSD11_R")
	)
	(segment
		(start 38.2778 -314.3504)
		(end 37.7063 -314.3504)
		(width 0.17145)
		(layer "F.Cu")
		(net "SW_SSD11_R")
	)
	(segment
		(start 37.7698 -312.9153)
		(end 37.7063 -312.9788)
		(width 0.17145)
		(layer "F.Cu")
		(net "SW_SSD11_R")
	)
	(segment
		(start 37.7063 -312.9788)
		(end 37.7063 -314.3504)
		(width 0.17145)
		(layer "F.Cu")
		(net "SW_SSD11_R")
	)
	(segment
		(start 39.0398 -314.198)
		(end 38.4302 -314.198)
		(width 0.17145)
		(layer "F.Cu")
		(net "SW_SSD11_R")
	)
	(segment
		(start 39.0398 -314.198)
		(end 39.0398 -315.3029)
		(width 0.17145)
		(layer "F.Cu")
		(net "SW_SSD11_R")
	)
	(via
		(at 39.0398 -314.198)
		(size 0.7112)
		(drill 0.3556)
		(layers "F.Cu" "B.Cu")
		(net "SW_SSD11_R")
	)
	(segment
		(start 37.7698 -316.3189)
		(end 36.7538 -316.3189)
		(width 0.17145)
		(layer "F.Cu")
		(net "SW_SSD11_N")
	)
	(segment
		(start 40.5638 -316.0014)
		(end 40.2463 -316.3189)
		(width 0.17145)
		(layer "F.Cu")
		(net "SW_SSD11_N")
	)
	(segment
		(start 40.5638 -314.6044)
		(end 40.5638 -316.0014)
		(width 0.17145)
		(layer "F.Cu")
		(net "SW_SSD11_N")
	)
	(segment
		(start 35.8394 -316.0014)
		(end 36.1569 -316.3189)
		(width 0.17145)
		(layer "F.Cu")
		(net "SW_SSD11_N")
	)
	(segment
		(start 40.2463 -316.3189)
		(end 38.9128 -316.3189)
		(width 0.17145)
		(layer "F.Cu")
		(net "SW_SSD11_N")
	)
	(segment
		(start 38.9128 -316.3189)
		(end 37.7698 -316.3189)
		(width 0.17145)
		(layer "F.Cu")
		(net "SW_SSD11_N")
	)
	(segment
		(start 34.8488 -316.0014)
		(end 35.8394 -316.0014)
		(width 0.17145)
		(layer "F.Cu")
		(net "SW_SSD11_N")
	)
	(segment
		(start 36.1569 -316.3189)
		(end 36.7538 -316.3189)
		(width 0.17145)
		(layer "F.Cu")
		(net "SW_SSD11_N")
	)
	(via
		(at 40.2463 -316.3189)
		(size 0.7112)
		(drill 0.3556)
		(layers "F.Cu" "B.Cu")
		(net "SW_SSD11_N")
	)
	(segment
		(start 39.3446 -417.195)
		(end 38.735 -417.195)
		(width 0.17145)
		(layer "F.Cu")
		(net "SW_SSD10_R")
	)
	(segment
		(start 39.4335 -415.7599)
		(end 38.0746 -415.7599)
		(width 0.17145)
		(layer "F.Cu")
		(net "SW_SSD10_R")
	)
	(segment
		(start 39.878 -415.3154)
		(end 39.4335 -415.7599)
		(width 0.17145)
		(layer "F.Cu")
		(net "SW_SSD10_R")
	)
	(segment
		(start 38.0111 -415.8234)
		(end 38.0746 -415.7599)
		(width 0.17145)
		(layer "F.Cu")
		(net "SW_SSD10_R")
	)
	(segment
		(start 38.5826 -417.3474)
		(end 38.0111 -417.3474)
		(width 0.17145)
		(layer "F.Cu")
		(net "SW_SSD10_R")
	)
	(segment
		(start 39.3446 -418.2999)
		(end 39.2176 -418.4269)
		(width 0.17145)
		(layer "F.Cu")
		(net "SW_SSD10_R")
	)
	(segment
		(start 38.735 -417.195)
		(end 38.5826 -417.3474)
		(width 0.17145)
		(layer "F.Cu")
		(net "SW_SSD10_R")
	)
	(segment
		(start 39.3446 -417.195)
		(end 39.3446 -418.2999)
		(width 0.17145)
		(layer "F.Cu")
		(net "SW_SSD10_R")
	)
	(segment
		(start 38.0111 -417.3474)
		(end 38.0111 -415.8234)
		(width 0.17145)
		(layer "F.Cu")
		(net "SW_SSD10_R")
	)
	(segment
		(start 40.8686 -415.3154)
		(end 39.878 -415.3154)
		(width 0.17145)
		(layer "F.Cu")
		(net "SW_SSD10_R")
	)
	(via
		(at 39.3446 -417.195)
		(size 0.7112)
		(drill 0.3556)
		(layers "F.Cu" "B.Cu")
		(net "SW_SSD10_R")
	)
	(segment
		(start 35.1536 -418.9984)
		(end 36.0426 -418.9984)
		(width 0.17145)
		(layer "F.Cu")
		(net "SW_SSD10_N")
	)
	(segment
		(start 39.2176 -419.3159)
		(end 38.0746 -419.3159)
		(width 0.17145)
		(layer "F.Cu")
		(net "SW_SSD10_N")
	)
	(segment
		(start 38.0746 -419.3159)
		(end 37.0586 -419.3159)
		(width 0.17145)
		(layer "F.Cu")
		(net "SW_SSD10_N")
	)
	(segment
		(start 40.5511 -419.3159)
		(end 39.2176 -419.3159)
		(width 0.17145)
		(layer "F.Cu")
		(net "SW_SSD10_N")
	)
	(segment
		(start 40.8686 -418.9984)
		(end 40.5511 -419.3159)
		(width 0.17145)
		(layer "F.Cu")
		(net "SW_SSD10_N")
	)
	(segment
		(start 40.8686 -417.6014)
		(end 40.8686 -418.9984)
		(width 0.17145)
		(layer "F.Cu")
		(net "SW_SSD10_N")
	)
	(segment
		(start 36.0426 -418.9984)
		(end 36.3601 -419.3159)
		(width 0.17145)
		(layer "F.Cu")
		(net "SW_SSD10_N")
	)
	(segment
		(start 36.3601 -419.3159)
		(end 37.0586 -419.3159)
		(width 0.17145)
		(layer "F.Cu")
		(net "SW_SSD10_N")
	)
	(via
		(at 40.5511 -419.3159)
		(size 0.7112)
		(drill 0.3556)
		(layers "F.Cu" "B.Cu")
		(net "SW_SSD10_N")
	)
	(segment
		(start 208.6356 -397.891)
		(end 208.1784 -397.891)
		(width 0.17145)
		(layer "F.Cu")
		(net "SW_SSD1_R")
	)
	(segment
		(start 206.502 -399.669)
		(end 208.8515 -399.669)
		(width 0.17145)
		(layer "F.Cu")
		(net "SW_SSD1_R")
	)
	(segment
		(start 209.3595 -397.637)
		(end 209.3595 -399.161)
		(width 0.17145)
		(layer "F.Cu")
		(net "SW_SSD1_R")
	)
	(segment
		(start 208.8515 -399.669)
		(end 209.296 -399.2245)
		(width 0.17145)
		(layer "F.Cu")
		(net "SW_SSD1_R")
	)
	(segment
		(start 208.8896 -397.637)
		(end 208.6356 -397.891)
		(width 0.17145)
		(layer "F.Cu")
		(net "SW_SSD1_R")
	)
	(segment
		(start 209.3595 -399.161)
		(end 209.296 -399.2245)
		(width 0.17145)
		(layer "F.Cu")
		(net "SW_SSD1_R")
	)
	(segment
		(start 208.0768 -396.6337)
		(end 208.0768 -397.7894)
		(width 0.17145)
		(layer "F.Cu")
		(net "SW_SSD1_R")
	)
	(segment
		(start 208.1784 -397.891)
		(end 208.0768 -397.7894)
		(width 0.17145)
		(layer "F.Cu")
		(net "SW_SSD1_R")
	)
	(segment
		(start 209.3595 -397.637)
		(end 208.8896 -397.637)
		(width 0.17145)
		(layer "F.Cu")
		(net "SW_SSD1_R")
	)
	(segment
		(start 208.153 -396.5575)
		(end 208.0768 -396.6337)
		(width 0.17145)
		(layer "F.Cu")
		(net "SW_SSD1_R")
	)
	(via
		(at 208.0768 -397.7894)
		(size 0.7112)
		(drill 0.3556)
		(layers "F.Cu" "B.Cu")
		(net "SW_SSD1_R")
	)
	(segment
		(start 208.153 -395.6685)
		(end 206.8195 -395.6685)
		(width 0.17145)
		(layer "F.Cu")
		(net "SW_SSD1_N")
	)
	(segment
		(start 210.312 -395.6685)
		(end 210.8073 -395.6685)
		(width 0.17145)
		(layer "F.Cu")
		(net "SW_SSD1_N")
	)
	(segment
		(start 211.1248 -395.986)
		(end 212.217 -395.986)
		(width 0.17145)
		(layer "F.Cu")
		(net "SW_SSD1_N")
	)
	(segment
		(start 209.296 -395.6685)
		(end 210.312 -395.6685)
		(width 0.17145)
		(layer "F.Cu")
		(net "SW_SSD1_N")
	)
	(segment
		(start 206.502 -397.383)
		(end 206.502 -395.986)
		(width 0.17145)
		(layer "F.Cu")
		(net "SW_SSD1_N")
	)
	(segment
		(start 208.153 -395.6685)
		(end 209.296 -395.6685)
		(width 0.17145)
		(layer "F.Cu")
		(net "SW_SSD1_N")
	)
	(segment
		(start 206.502 -395.986)
		(end 206.8195 -395.6685)
		(width 0.17145)
		(layer "F.Cu")
		(net "SW_SSD1_N")
	)
	(segment
		(start 210.8073 -395.6685)
		(end 211.1248 -395.986)
		(width 0.17145)
		(layer "F.Cu")
		(net "SW_SSD1_N")
	)
	(via
		(at 206.8195 -395.6685)
		(size 0.7112)
		(drill 0.3556)
		(layers "F.Cu" "B.Cu")
		(net "SW_SSD1_N")
	)
	(segment
		(start 199.857106 -492.634778)
		(end 200.428606 -492.634778)
		(width 0.17145)
		(layer "F.Cu")
		(net "SW_SSD0_R")
	)
	(segment
		(start 199.120506 -492.787178)
		(end 199.704706 -492.787178)
		(width 0.17145)
		(layer "F.Cu")
		(net "SW_SSD0_R")
	)
	(segment
		(start 197.571106 -494.666778)
		(end 199.920606 -494.666778)
		(width 0.17145)
		(layer "F.Cu")
		(net "SW_SSD0_R")
	)
	(segment
		(start 199.704706 -492.787178)
		(end 199.857106 -492.634778)
		(width 0.17145)
		(layer "F.Cu")
		(net "SW_SSD0_R")
	)
	(segment
		(start 199.920606 -494.666778)
		(end 200.365106 -494.222278)
		(width 0.17145)
		(layer "F.Cu")
		(net "SW_SSD0_R")
	)
	(segment
		(start 200.428606 -492.634778)
		(end 200.428606 -494.158778)
		(width 0.17145)
		(layer "F.Cu")
		(net "SW_SSD0_R")
	)
	(segment
		(start 200.428606 -494.158778)
		(end 200.365106 -494.222278)
		(width 0.17145)
		(layer "F.Cu")
		(net "SW_SSD0_R")
	)
	(segment
		(start 199.120506 -492.787178)
		(end 199.120506 -491.656878)
		(width 0.17145)
		(layer "F.Cu")
		(net "SW_SSD0_R")
	)
	(segment
		(start 199.120506 -491.656878)
		(end 199.222106 -491.555278)
		(width 0.17145)
		(layer "F.Cu")
		(net "SW_SSD0_R")
	)
	(via
		(at 199.120506 -492.787178)
		(size 0.7112)
		(drill 0.3556)
		(layers "F.Cu" "B.Cu")
		(net "SW_SSD0_R")
	)
	(segment
		(start 199.222106 -490.666278)
		(end 200.365106 -490.666278)
		(width 0.17145)
		(layer "F.Cu")
		(net "SW_SSD0_N")
	)
	(segment
		(start 197.888606 -490.666278)
		(end 199.222106 -490.666278)
		(width 0.17145)
		(layer "F.Cu")
		(net "SW_SSD0_N")
	)
	(segment
		(start 197.571106 -490.983778)
		(end 197.888606 -490.666278)
		(width 0.17145)
		(layer "F.Cu")
		(net "SW_SSD0_N")
	)
	(segment
		(start 197.571106 -492.380778)
		(end 197.571106 -490.983778)
		(width 0.17145)
		(layer "F.Cu")
		(net "SW_SSD0_N")
	)
	(segment
		(start 202.600306 -491.263178)
		(end 202.003406 -490.666278)
		(width 0.17145)
		(layer "F.Cu")
		(net "SW_SSD0_N")
	)
	(segment
		(start 203.819506 -491.263178)
		(end 202.600306 -491.263178)
		(width 0.17145)
		(layer "F.Cu")
		(net "SW_SSD0_N")
	)
	(segment
		(start 202.003406 -490.666278)
		(end 201.381106 -490.666278)
		(width 0.17145)
		(layer "F.Cu")
		(net "SW_SSD0_N")
	)
	(segment
		(start 200.365106 -490.666278)
		(end 201.381106 -490.666278)
		(width 0.17145)
		(layer "F.Cu")
		(net "SW_SSD0_N")
	)
	(via
		(at 197.888606 -490.666278)
		(size 0.7112)
		(drill 0.3556)
		(layers "F.Cu" "B.Cu")
		(net "SW_SSD0_N")
	)
	(segment
		(start 22.86 -94.6785)
		(end 24.003 -94.6785)
		(width 0.17145)
		(layer "F.Cu")
		(net "SSD9_PWREN")
	)
	(segment
		(start 24.003 -94.6785)
		(end 26.0985 -94.6785)
		(width 0.17145)
		(layer "F.Cu")
		(net "SSD9_PWREN")
	)
	(segment
		(start 13.224764 -94.144846)
		(end 8.675624 -98.693986)
		(width 0.17145)
		(layer "F.Cu")
		(net "SSD9_PWREN")
	)
	(segment
		(start 21.69795 -95.95485)
		(end 21.69795 -95.428054)
		(width 0.17145)
		(layer "F.Cu")
		(net "SSD9_PWREN")
	)
	(segment
		(start 3.756914 -165.738302)
		(end 3.560826 -165.542214)
		(width 0.17145)
		(layer "F.Cu")
		(net "SSD9_PWREN")
	)
	(segment
		(start 26.416 -93.26245)
		(end 25.29205 -92.1385)
		(width 0.17145)
		(layer "F.Cu")
		(net "SSD9_PWREN")
	)
	(segment
		(start 22.447504 -94.6785)
		(end 22.86 -94.6785)
		(width 0.17145)
		(layer "F.Cu")
		(net "SSD9_PWREN")
	)
	(segment
		(start 20.727416 -95.95485)
		(end 21.69795 -95.95485)
		(width 0.17145)
		(layer "F.Cu")
		(net "SSD9_PWREN")
	)
	(segment
		(start 8.675624 -98.693986)
		(end 8.675624 -163.663376)
		(width 0.17145)
		(layer "F.Cu")
		(net "SSD9_PWREN")
	)
	(segment
		(start 19.98345 -96.698816)
		(end 20.727416 -95.95485)
		(width 0.17145)
		(layer "F.Cu")
		(net "SSD9_PWREN")
	)
	(segment
		(start 26.0985 -94.6785)
		(end 26.416 -94.361)
		(width 0.17145)
		(layer "F.Cu")
		(net "SSD9_PWREN")
	)
	(segment
		(start 21.69795 -95.428054)
		(end 22.447504 -94.6785)
		(width 0.17145)
		(layer "F.Cu")
		(net "SSD9_PWREN")
	)
	(segment
		(start 8.675624 -163.663376)
		(end 6.600698 -165.738302)
		(width 0.17145)
		(layer "F.Cu")
		(net "SSD9_PWREN")
	)
	(segment
		(start 26.416 -94.361)
		(end 26.416 -93.26245)
		(width 0.17145)
		(layer "F.Cu")
		(net "SSD9_PWREN")
	)
	(segment
		(start 3.560826 -165.542214)
		(end 2.249932 -165.542214)
		(width 0.17145)
		(layer "F.Cu")
		(net "SSD9_PWREN")
	)
	(segment
		(start 6.600698 -165.738302)
		(end 3.756914 -165.738302)
		(width 0.17145)
		(layer "F.Cu")
		(net "SSD9_PWREN")
	)
	(via
		(at 13.224764 -94.144846)
		(size 0.508)
		(drill 0.254)
		(layers "F.Cu" "B.Cu")
		(net "SSD9_PWREN")
	)
	(via
		(at 19.98345 -96.698816)
		(size 0.5588)
		(drill 0.3048)
		(layers "F.Cu" "B.Cu")
		(net "SSD9_PWREN")
	)
	(segment
		(start 15.778734 -96.698816)
		(end 19.98345 -96.698816)
		(width 0.17145)
		(layer "B.Cu")
		(net "SSD9_PWREN")
	)
	(segment
		(start 13.224764 -94.144846)
		(end 15.778734 -96.698816)
		(width 0.17145)
		(layer "B.Cu")
		(net "SSD9_PWREN")
	)
	(segment
		(start 3.79857 -190.15583)
		(end 5.75437 -190.15583)
		(width 0.17145)
		(layer "F.Cu")
		(net "SSD9_PERST_N")
	)
	(segment
		(start 43.474386 -63.789814)
		(end 43.9166 -63.3476)
		(width 0.17145)
		(layer "F.Cu")
		(net "SSD9_PERST_N")
	)
	(segment
		(start 5.75437 -190.15583)
		(end 10.033 -185.8772)
		(width 0.17145)
		(layer "F.Cu")
		(net "SSD9_PERST_N")
	)
	(segment
		(start 29.864304 -65.532)
		(end 34.9758 -65.532)
		(width 0.17145)
		(layer "F.Cu")
		(net "SSD9_PERST_N")
	)
	(segment
		(start 2.249932 -190.342012)
		(end 3.612388 -190.342012)
		(width 0.17145)
		(layer "F.Cu")
		(net "SSD9_PERST_N")
	)
	(segment
		(start 17.023588 -93.778832)
		(end 17.023588 -78.372716)
		(width 0.17145)
		(layer "F.Cu")
		(net "SSD9_PERST_N")
	)
	(segment
		(start 17.023588 -78.372716)
		(end 27.122628 -68.273676)
		(width 0.17145)
		(layer "F.Cu")
		(net "SSD9_PERST_N")
	)
	(segment
		(start 42.39006 -62.989968)
		(end 43.558968 -62.989968)
		(width 0.17145)
		(layer "F.Cu")
		(net "SSD9_PERST_N")
	)
	(segment
		(start 10.033 -185.8772)
		(end 10.033 -166.151306)
		(width 0.17145)
		(layer "F.Cu")
		(net "SSD9_PERST_N")
	)
	(segment
		(start 10.927842 -165.256464)
		(end 10.927842 -99.874578)
		(width 0.17145)
		(layer "F.Cu")
		(net "SSD9_PERST_N")
	)
	(segment
		(start 43.558968 -62.989968)
		(end 43.9166 -63.3476)
		(width 0.17145)
		(layer "F.Cu")
		(net "SSD9_PERST_N")
	)
	(segment
		(start 27.122628 -68.273676)
		(end 29.864304 -65.532)
		(width 0.17145)
		(layer "F.Cu")
		(net "SSD9_PERST_N")
	)
	(segment
		(start 3.612388 -190.342012)
		(end 3.79857 -190.15583)
		(width 0.17145)
		(layer "F.Cu")
		(net "SSD9_PERST_N")
	)
	(segment
		(start 42.39006 -63.789814)
		(end 43.474386 -63.789814)
		(width 0.17145)
		(layer "F.Cu")
		(net "SSD9_PERST_N")
	)
	(segment
		(start 10.033 -166.151306)
		(end 10.927842 -165.256464)
		(width 0.17145)
		(layer "F.Cu")
		(net "SSD9_PERST_N")
	)
	(segment
		(start 34.9758 -65.532)
		(end 36.4744 -64.0334)
		(width 0.17145)
		(layer "F.Cu")
		(net "SSD9_PERST_N")
	)
	(segment
		(start 10.927842 -99.874578)
		(end 17.023588 -93.778832)
		(width 0.17145)
		(layer "F.Cu")
		(net "SSD9_PERST_N")
	)
	(via
		(at 43.9166 -63.3476)
		(size 0.508)
		(drill 0.254)
		(layers "F.Cu" "B.Cu")
		(net "SSD9_PERST_N")
	)
	(via
		(at 27.122628 -68.273676)
		(size 0.7112)
		(drill 0.3556)
		(layers "F.Cu" "B.Cu")
		(net "SSD9_PERST_N")
	)
	(via
		(at 36.4744 -64.0334)
		(size 0.508)
		(drill 0.254)
		(layers "F.Cu" "B.Cu")
		(net "SSD9_PERST_N")
	)
	(segment
		(start 43.2308 -64.0334)
		(end 43.9166 -63.3476)
		(width 0.17145)
		(layer "B.Cu")
		(net "SSD9_PERST_N")
	)
	(segment
		(start 36.4744 -64.0334)
		(end 43.2308 -64.0334)
		(width 0.17145)
		(layer "B.Cu")
		(net "SSD9_PERST_N")
	)
	(segment
		(start 48.18126 -58.606436)
		(end 74.05751 -58.606436)
		(width 0.17145)
		(layer "F.Cu")
		(net "SSD9_CLK0_OE_N")
	)
	(segment
		(start 41.975024 -69.574918)
		(end 43.58513 -69.574918)
		(width 0.17145)
		(layer "F.Cu")
		(net "SSD9_CLK0_OE_N")
	)
	(segment
		(start 89.662 -86.6775)
		(end 89.5985 -86.614)
		(width 0.17145)
		(layer "F.Cu")
		(net "SSD9_CLK0_OE_N")
	)
	(segment
		(start 43.58513 -69.574918)
		(end 46.863 -66.297048)
		(width 0.17145)
		(layer "F.Cu")
		(net "SSD9_CLK0_OE_N")
	)
	(segment
		(start 89.5985 -86.614)
		(end 89.5985 -85.344)
		(width 0.17145)
		(layer "F.Cu")
		(net "SSD9_CLK0_OE_N")
	)
	(segment
		(start 89.662 -87.6935)
		(end 89.662 -86.6775)
		(width 0.17145)
		(layer "F.Cu")
		(net "SSD9_CLK0_OE_N")
	)
	(segment
		(start 46.863 -59.924696)
		(end 48.18126 -58.606436)
		(width 0.17145)
		(layer "F.Cu")
		(net "SSD9_CLK0_OE_N")
	)
	(segment
		(start 89.5985 -74.147426)
		(end 89.5985 -85.344)
		(width 0.17145)
		(layer "F.Cu")
		(net "SSD9_CLK0_OE_N")
	)
	(segment
		(start 74.05751 -58.606436)
		(end 89.5985 -74.147426)
		(width 0.17145)
		(layer "F.Cu")
		(net "SSD9_CLK0_OE_N")
	)
	(segment
		(start 46.863 -66.297048)
		(end 46.863 -59.924696)
		(width 0.17145)
		(layer "F.Cu")
		(net "SSD9_CLK0_OE_N")
	)
	(via
		(at 89.5985 -85.344)
		(size 0.7112)
		(drill 0.3556)
		(layers "F.Cu" "B.Cu")
		(net "SSD9_CLK0_OE_N")
	)
	(segment
		(start 20.37461 -198.55561)
		(end 20.77085 -198.95185)
		(width 0.17145)
		(layer "F.Cu")
		(net "SSD8_PWREN")
	)
	(segment
		(start 25.74925 -195.1355)
		(end 26.416 -195.80225)
		(width 0.17145)
		(layer "F.Cu")
		(net "SSD8_PWREN")
	)
	(segment
		(start 22.86 -197.6755)
		(end 24.003 -197.6755)
		(width 0.17145)
		(layer "F.Cu")
		(net "SSD8_PWREN")
	)
	(segment
		(start 21.69795 -198.95185)
		(end 22.86 -197.7898)
		(width 0.17145)
		(layer "F.Cu")
		(net "SSD8_PWREN")
	)
	(segment
		(start 22.86 -197.7898)
		(end 22.86 -197.6755)
		(width 0.17145)
		(layer "F.Cu")
		(net "SSD8_PWREN")
	)
	(segment
		(start 25.29205 -195.1355)
		(end 25.74925 -195.1355)
		(width 0.17145)
		(layer "F.Cu")
		(net "SSD8_PWREN")
	)
	(segment
		(start 26.416 -195.80225)
		(end 26.416 -197.358)
		(width 0.17145)
		(layer "F.Cu")
		(net "SSD8_PWREN")
	)
	(segment
		(start 20.77085 -198.95185)
		(end 21.69795 -198.95185)
		(width 0.17145)
		(layer "F.Cu")
		(net "SSD8_PWREN")
	)
	(segment
		(start 20.37461 -197.392798)
		(end 20.37461 -198.55561)
		(width 0.17145)
		(layer "F.Cu")
		(net "SSD8_PWREN")
	)
	(segment
		(start 26.0985 -197.6755)
		(end 24.003 -197.6755)
		(width 0.17145)
		(layer "F.Cu")
		(net "SSD8_PWREN")
	)
	(segment
		(start 26.416 -197.358)
		(end 26.0985 -197.6755)
		(width 0.17145)
		(layer "F.Cu")
		(net "SSD8_PWREN")
	)
	(via
		(at 20.37461 -197.392798)
		(size 0.508)
		(drill 0.254)
		(layers "F.Cu" "B.Cu")
		(net "SSD8_PWREN")
	)
	(via
		(at 20.37461 -200.1266)
		(size 0.7112)
		(drill 0.3556)
		(layers "F.Cu" "B.Cu")
		(net "SSD8_PWREN")
	)
	(segment
		(start 20.37461 -201.55408)
		(end 20.37461 -200.1266)
		(width 0.17145)
		(layer "B.Cu")
		(net "SSD8_PWREN")
	)
	(segment
		(start 4.887214 -226.568)
		(end 5.274564 -226.18065)
		(width 0.17145)
		(layer "B.Cu")
		(net "SSD8_PWREN")
	)
	(segment
		(start 11.765534 -210.163156)
		(end 20.37461 -201.55408)
		(width 0.17145)
		(layer "B.Cu")
		(net "SSD8_PWREN")
	)
	(segment
		(start 20.37461 -197.392798)
		(end 20.37461 -200.1266)
		(width 0.17145)
		(layer "B.Cu")
		(net "SSD8_PWREN")
	)
	(segment
		(start 1.868932 -226.342194)
		(end 3.683 -226.342194)
		(width 0.17145)
		(layer "B.Cu")
		(net "SSD8_PWREN")
	)
	(segment
		(start 11.765534 -221.91345)
		(end 11.765534 -210.163156)
		(width 0.17145)
		(layer "B.Cu")
		(net "SSD8_PWREN")
	)
	(segment
		(start 3.683 -226.342194)
		(end 3.908806 -226.568)
		(width 0.17145)
		(layer "B.Cu")
		(net "SSD8_PWREN")
	)
	(segment
		(start 5.274564 -226.18065)
		(end 7.498334 -226.18065)
		(width 0.17145)
		(layer "B.Cu")
		(net "SSD8_PWREN")
	)
	(segment
		(start 3.908806 -226.568)
		(end 4.887214 -226.568)
		(width 0.17145)
		(layer "B.Cu")
		(net "SSD8_PWREN")
	)
	(segment
		(start 7.498334 -226.18065)
		(end 11.765534 -221.91345)
		(width 0.17145)
		(layer "B.Cu")
		(net "SSD8_PWREN")
	)
	(segment
		(start 12.573 -195.834)
		(end 11.06297 -197.34403)
		(width 0.17145)
		(layer "F.Cu")
		(net "SSD8_PERST_N")
	)
	(segment
		(start 42.39006 -166.789862)
		(end 43.572938 -166.789862)
		(width 0.17145)
		(layer "F.Cu")
		(net "SSD8_PERST_N")
	)
	(segment
		(start 42.39006 -165.990016)
		(end 43.511216 -165.990016)
		(width 0.17145)
		(layer "F.Cu")
		(net "SSD8_PERST_N")
	)
	(segment
		(start 11.06297 -197.34403)
		(end 8.857488 -199.549512)
		(width 0.17145)
		(layer "F.Cu")
		(net "SSD8_PERST_N")
	)
	(segment
		(start 43.511216 -165.990016)
		(end 43.942 -166.4208)
		(width 0.17145)
		(layer "F.Cu")
		(net "SSD8_PERST_N")
	)
	(segment
		(start 8.857488 -199.549512)
		(end 8.857488 -226.290124)
		(width 0.17145)
		(layer "F.Cu")
		(net "SSD8_PERST_N")
	)
	(segment
		(start 43.572938 -166.789862)
		(end 43.942 -166.4208)
		(width 0.17145)
		(layer "F.Cu")
		(net "SSD8_PERST_N")
	)
	(via
		(at 43.942 -166.4208)
		(size 0.508)
		(drill 0.254)
		(layers "F.Cu" "B.Cu")
		(net "SSD8_PERST_N")
	)
	(via
		(at 11.06297 -197.34403)
		(size 0.7112)
		(drill 0.3556)
		(layers "F.Cu" "B.Cu")
		(net "SSD8_PERST_N")
	)
	(via
		(at 12.573 -195.834)
		(size 0.508)
		(drill 0.254)
		(layers "F.Cu" "B.Cu")
		(net "SSD8_PERST_N")
	)
	(via
		(at 8.857488 -226.290124)
		(size 0.508)
		(drill 0.254)
		(layers "F.Cu" "B.Cu")
		(net "SSD8_PERST_N")
	)
	(segment
		(start 42.452544 -167.910256)
		(end 43.942 -166.4208)
		(width 0.17145)
		(layer "B.Cu")
		(net "SSD8_PERST_N")
	)
	(segment
		(start 5.675376 -228.487224)
		(end 4.330192 -227.14204)
		(width 0.17145)
		(layer "B.Cu")
		(net "SSD8_PERST_N")
	)
	(segment
		(start 5.986018 -228.981)
		(end 5.675376 -228.670358)
		(width 0.17145)
		(layer "B.Cu")
		(net "SSD8_PERST_N")
	)
	(segment
		(start 4.330192 -227.14204)
		(end 1.868932 -227.14204)
		(width 0.17145)
		(layer "B.Cu")
		(net "SSD8_PERST_N")
	)
	(segment
		(start 42.452544 -181.487064)
		(end 42.452544 -167.910256)
		(width 0.17145)
		(layer "B.Cu")
		(net "SSD8_PERST_N")
	)
	(segment
		(start 12.573 -195.834)
		(end 22.6441 -185.7629)
		(width 0.17145)
		(layer "B.Cu")
		(net "SSD8_PERST_N")
	)
	(segment
		(start 5.675376 -228.670358)
		(end 5.675376 -228.487224)
		(width 0.17145)
		(layer "B.Cu")
		(net "SSD8_PERST_N")
	)
	(segment
		(start 7.085076 -228.981)
		(end 5.986018 -228.981)
		(width 0.17145)
		(layer "B.Cu")
		(net "SSD8_PERST_N")
	)
	(segment
		(start 38.176708 -185.7629)
		(end 42.452544 -181.487064)
		(width 0.17145)
		(layer "B.Cu")
		(net "SSD8_PERST_N")
	)
	(segment
		(start 8.857488 -227.208588)
		(end 7.085076 -228.981)
		(width 0.17145)
		(layer "B.Cu")
		(net "SSD8_PERST_N")
	)
	(segment
		(start 22.6441 -185.7629)
		(end 38.176708 -185.7629)
		(width 0.17145)
		(layer "B.Cu")
		(net "SSD8_PERST_N")
	)
	(segment
		(start 8.857488 -226.290124)
		(end 8.857488 -227.208588)
		(width 0.17145)
		(layer "B.Cu")
		(net "SSD8_PERST_N")
	)
	(segment
		(start 41.975024 -172.574966)
		(end 43.58513 -172.574966)
		(width 0.17145)
		(layer "F.Cu")
		(net "SSD8_CLK0_OE_N")
	)
	(segment
		(start 97.155 -116.5225)
		(end 97.2185 -116.586)
		(width 0.17145)
		(layer "F.Cu")
		(net "SSD8_CLK0_OE_N")
	)
	(segment
		(start 46.736 -157.273244)
		(end 73.254616 -130.754628)
		(width 0.17145)
		(layer "F.Cu")
		(net "SSD8_CLK0_OE_N")
	)
	(segment
		(start 97.155 -115.5065)
		(end 97.155 -116.5225)
		(width 0.17145)
		(layer "F.Cu")
		(net "SSD8_CLK0_OE_N")
	)
	(segment
		(start 97.2185 -116.586)
		(end 97.2185 -117.856)
		(width 0.17145)
		(layer "F.Cu")
		(net "SSD8_CLK0_OE_N")
	)
	(segment
		(start 73.254616 -130.754628)
		(end 84.319872 -130.754628)
		(width 0.17145)
		(layer "F.Cu")
		(net "SSD8_CLK0_OE_N")
	)
	(segment
		(start 43.58513 -172.574966)
		(end 46.736 -169.424096)
		(width 0.17145)
		(layer "F.Cu")
		(net "SSD8_CLK0_OE_N")
	)
	(segment
		(start 46.736 -169.424096)
		(end 46.736 -157.273244)
		(width 0.17145)
		(layer "F.Cu")
		(net "SSD8_CLK0_OE_N")
	)
	(segment
		(start 84.319872 -130.754628)
		(end 97.2185 -117.856)
		(width 0.17145)
		(layer "F.Cu")
		(net "SSD8_CLK0_OE_N")
	)
	(via
		(at 97.2185 -117.856)
		(size 0.7112)
		(drill 0.3556)
		(layers "F.Cu" "B.Cu")
		(net "SSD8_CLK0_OE_N")
	)
	(segment
		(start 22.86 -300.6725)
		(end 24.003 -300.6725)
		(width 0.17145)
		(layer "F.Cu")
		(net "SSD7_PWREN")
	)
	(segment
		(start 26.416 -299.35805)
		(end 25.29205 -298.2341)
		(width 0.17145)
		(layer "F.Cu")
		(net "SSD7_PWREN")
	)
	(segment
		(start 26.0985 -300.6725)
		(end 26.416 -300.355)
		(width 0.17145)
		(layer "F.Cu")
		(net "SSD7_PWREN")
	)
	(segment
		(start 26.416 -300.355)
		(end 26.416 -299.35805)
		(width 0.17145)
		(layer "F.Cu")
		(net "SSD7_PWREN")
	)
	(segment
		(start 22.4155 -300.228)
		(end 22.86 -300.6725)
		(width 0.17145)
		(layer "F.Cu")
		(net "SSD7_PWREN")
	)
	(segment
		(start 21.69795 -301.94885)
		(end 21.69795 -301.22495)
		(width 0.17145)
		(layer "F.Cu")
		(net "SSD7_PWREN")
	)
	(segment
		(start 21.6662 -300.228)
		(end 22.4155 -300.228)
		(width 0.17145)
		(layer "F.Cu")
		(net "SSD7_PWREN")
	)
	(segment
		(start 21.6662 -301.1932)
		(end 21.6662 -300.228)
		(width 0.17145)
		(layer "F.Cu")
		(net "SSD7_PWREN")
	)
	(segment
		(start 24.003 -300.6725)
		(end 26.0985 -300.6725)
		(width 0.17145)
		(layer "F.Cu")
		(net "SSD7_PWREN")
	)
	(segment
		(start 21.69795 -301.22495)
		(end 21.6662 -301.1932)
		(width 0.17145)
		(layer "F.Cu")
		(net "SSD7_PWREN")
	)
	(via
		(at 13.193776 -313.056524)
		(size 0.7112)
		(drill 0.3556)
		(layers "F.Cu" "B.Cu")
		(net "SSD7_PWREN")
	)
	(via
		(at 21.6662 -300.228)
		(size 0.508)
		(drill 0.254)
		(layers "F.Cu" "B.Cu")
		(net "SSD7_PWREN")
	)
	(segment
		(start 4.486148 -311.572148)
		(end 7.5946 -314.6806)
		(width 0.17145)
		(layer "B.Cu")
		(net "SSD7_PWREN")
	)
	(segment
		(start 21.6662 -304.5841)
		(end 21.6662 -300.228)
		(width 0.17145)
		(layer "B.Cu")
		(net "SSD7_PWREN")
	)
	(segment
		(start 13.193776 -313.056524)
		(end 21.6662 -304.5841)
		(width 0.17145)
		(layer "B.Cu")
		(net "SSD7_PWREN")
	)
	(segment
		(start 7.5946 -314.6806)
		(end 11.5697 -314.6806)
		(width 0.17145)
		(layer "B.Cu")
		(net "SSD7_PWREN")
	)
	(segment
		(start 3.997706 -311.572148)
		(end 4.486148 -311.572148)
		(width 0.17145)
		(layer "B.Cu")
		(net "SSD7_PWREN")
	)
	(segment
		(start 11.5697 -314.6806)
		(end 13.193776 -313.056524)
		(width 0.17145)
		(layer "B.Cu")
		(net "SSD7_PWREN")
	)
	(segment
		(start 3.249676 -312.342022)
		(end 3.707384 -311.884314)
		(width 0.17145)
		(layer "B.Cu")
		(net "SSD7_PWREN")
	)
	(segment
		(start 3.707384 -311.86247)
		(end 3.997706 -311.572148)
		(width 0.17145)
		(layer "B.Cu")
		(net "SSD7_PWREN")
	)
	(segment
		(start 3.707384 -311.884314)
		(end 3.707384 -311.86247)
		(width 0.17145)
		(layer "B.Cu")
		(net "SSD7_PWREN")
	)
	(segment
		(start 1.868932 -312.342022)
		(end 3.249676 -312.342022)
		(width 0.17145)
		(layer "B.Cu")
		(net "SSD7_PWREN")
	)
	(segment
		(start 10.184638 -294.11422)
		(end 9.41578 -294.883078)
		(width 0.17145)
		(layer "F.Cu")
		(net "SSD7_PERST_N")
	)
	(segment
		(start 42.39006 -268.990064)
		(end 43.590464 -268.990064)
		(width 0.17145)
		(layer "F.Cu")
		(net "SSD7_PERST_N")
	)
	(segment
		(start 43.49369 -269.78991)
		(end 43.942 -269.3416)
		(width 0.17145)
		(layer "F.Cu")
		(net "SSD7_PERST_N")
	)
	(segment
		(start 9.41578 -311.60847)
		(end 8.433054 -312.591196)
		(width 0.17145)
		(layer "F.Cu")
		(net "SSD7_PERST_N")
	)
	(segment
		(start 10.184638 -293.367968)
		(end 10.184638 -294.11422)
		(width 0.17145)
		(layer "F.Cu")
		(net "SSD7_PERST_N")
	)
	(segment
		(start 9.41578 -294.883078)
		(end 9.41578 -311.60847)
		(width 0.17145)
		(layer "F.Cu")
		(net "SSD7_PERST_N")
	)
	(segment
		(start 43.590464 -268.990064)
		(end 43.942 -269.3416)
		(width 0.17145)
		(layer "F.Cu")
		(net "SSD7_PERST_N")
	)
	(segment
		(start 42.39006 -269.78991)
		(end 43.49369 -269.78991)
		(width 0.17145)
		(layer "F.Cu")
		(net "SSD7_PERST_N")
	)
	(segment
		(start 10.184638 -290.198302)
		(end 10.184638 -293.367968)
		(width 0.17145)
		(layer "F.Cu")
		(net "SSD7_PERST_N")
	)
	(via
		(at 8.433054 -312.591196)
		(size 0.508)
		(drill 0.254)
		(layers "F.Cu" "B.Cu")
		(net "SSD7_PERST_N")
	)
	(via
		(at 43.942 -269.3416)
		(size 0.508)
		(drill 0.254)
		(layers "F.Cu" "B.Cu")
		(net "SSD7_PERST_N")
	)
	(via
		(at 10.184638 -290.198302)
		(size 0.508)
		(drill 0.254)
		(layers "F.Cu" "B.Cu")
		(net "SSD7_PERST_N")
	)
	(via
		(at 10.184638 -293.367968)
		(size 0.7112)
		(drill 0.3556)
		(layers "F.Cu" "B.Cu")
		(net "SSD7_PERST_N")
	)
	(segment
		(start 43.1546 -270.129)
		(end 43.942 -269.3416)
		(width 0.17145)
		(layer "B.Cu")
		(net "SSD7_PERST_N")
	)
	(segment
		(start 3.599434 -311.542176)
		(end 1.868932 -311.542176)
		(width 0.17145)
		(layer "B.Cu")
		(net "SSD7_PERST_N")
	)
	(segment
		(start 4.583684 -311.240932)
		(end 3.900678 -311.240932)
		(width 0.17145)
		(layer "B.Cu")
		(net "SSD7_PERST_N")
	)
	(segment
		(start 10.184638 -290.198302)
		(end 11.58494 -288.798)
		(width 0.17145)
		(layer "B.Cu")
		(net "SSD7_PERST_N")
	)
	(segment
		(start 11.58494 -288.798)
		(end 12.954 -288.798)
		(width 0.17145)
		(layer "B.Cu")
		(net "SSD7_PERST_N")
	)
	(segment
		(start 12.954 -288.798)
		(end 31.623 -270.129)
		(width 0.17145)
		(layer "B.Cu")
		(net "SSD7_PERST_N")
	)
	(segment
		(start 3.900678 -311.240932)
		(end 3.599434 -311.542176)
		(width 0.17145)
		(layer "B.Cu")
		(net "SSD7_PERST_N")
	)
	(segment
		(start 31.623 -270.129)
		(end 43.1546 -270.129)
		(width 0.17145)
		(layer "B.Cu")
		(net "SSD7_PERST_N")
	)
	(segment
		(start 5.933948 -312.591196)
		(end 4.583684 -311.240932)
		(width 0.17145)
		(layer "B.Cu")
		(net "SSD7_PERST_N")
	)
	(segment
		(start 8.433054 -312.591196)
		(end 5.933948 -312.591196)
		(width 0.17145)
		(layer "B.Cu")
		(net "SSD7_PERST_N")
	)
	(segment
		(start 46.886114 -272.27403)
		(end 46.886114 -259.934202)
		(width 0.17145)
		(layer "F.Cu")
		(net "SSD7_CLK0_OE_N")
	)
	(segment
		(start 41.975024 -275.575014)
		(end 43.58513 -275.575014)
		(width 0.17145)
		(layer "F.Cu")
		(net "SSD7_CLK0_OE_N")
	)
	(segment
		(start 97.155 -224.7265)
		(end 97.155 -225.7425)
		(width 0.17145)
		(layer "F.Cu")
		(net "SSD7_CLK0_OE_N")
	)
	(segment
		(start 97.2185 -227.076)
		(end 97.2185 -225.806)
		(width 0.17145)
		(layer "F.Cu")
		(net "SSD7_CLK0_OE_N")
	)
	(segment
		(start 97.2185 -228.325426)
		(end 97.2185 -227.076)
		(width 0.17145)
		(layer "F.Cu")
		(net "SSD7_CLK0_OE_N")
	)
	(segment
		(start 46.886114 -259.934202)
		(end 65.388744 -241.431572)
		(width 0.17145)
		(layer "F.Cu")
		(net "SSD7_CLK0_OE_N")
	)
	(segment
		(start 65.388744 -241.431572)
		(end 84.112354 -241.431572)
		(width 0.17145)
		(layer "F.Cu")
		(net "SSD7_CLK0_OE_N")
	)
	(segment
		(start 84.112354 -241.431572)
		(end 97.2185 -228.325426)
		(width 0.17145)
		(layer "F.Cu")
		(net "SSD7_CLK0_OE_N")
	)
	(segment
		(start 43.58513 -275.575014)
		(end 46.886114 -272.27403)
		(width 0.17145)
		(layer "F.Cu")
		(net "SSD7_CLK0_OE_N")
	)
	(segment
		(start 97.155 -225.7425)
		(end 97.2185 -225.806)
		(width 0.17145)
		(layer "F.Cu")
		(net "SSD7_CLK0_OE_N")
	)
	(via
		(at 97.2185 -227.076)
		(size 0.7112)
		(drill 0.3556)
		(layers "F.Cu" "B.Cu")
		(net "SSD7_CLK0_OE_N")
	)
	(segment
		(start 23.478998 -402.388324)
		(end 25.11425 -400.753072)
		(width 0.17145)
		(layer "F.Cu")
		(net "SSD6_PWREN")
	)
	(segment
		(start 5.09778 -360.34345)
		(end 3.939794 -360.34345)
		(width 0.17145)
		(layer "F.Cu")
		(net "SSD6_PWREN")
	)
	(segment
		(start 7.112 -366.776)
		(end 7.112 -362.35767)
		(width 0.17145)
		(layer "F.Cu")
		(net "SSD6_PWREN")
	)
	(segment
		(start 19.115024 -402.24075)
		(end 20.16125 -402.24075)
		(width 0.17145)
		(layer "F.Cu")
		(net "SSD6_PWREN")
	)
	(segment
		(start 21.99132 -402.388324)
		(end 23.478998 -402.388324)
		(width 0.17145)
		(layer "F.Cu")
		(net "SSD6_PWREN")
	)
	(segment
		(start 21.30425 -402.24075)
		(end 20.16125 -402.24075)
		(width 0.17145)
		(layer "F.Cu")
		(net "SSD6_PWREN")
	)
	(segment
		(start 25.11425 -400.753072)
		(end 25.11425 -398.8435)
		(width 0.17145)
		(layer "F.Cu")
		(net "SSD6_PWREN")
	)
	(segment
		(start 21.30425 -402.24075)
		(end 21.843746 -402.24075)
		(width 0.17145)
		(layer "F.Cu")
		(net "SSD6_PWREN")
	)
	(segment
		(start 3.939794 -360.34345)
		(end 3.938524 -360.34218)
		(width 0.17145)
		(layer "F.Cu")
		(net "SSD6_PWREN")
	)
	(segment
		(start 19.115024 -402.24075)
		(end 19.115024 -398.206468)
		(width 0.17145)
		(layer "F.Cu")
		(net "SSD6_PWREN")
	)
	(segment
		(start 3.938524 -360.34218)
		(end 2.249932 -360.34218)
		(width 0.17145)
		(layer "F.Cu")
		(net "SSD6_PWREN")
	)
	(segment
		(start 19.115024 -398.206468)
		(end 19.712178 -397.609314)
		(width 0.17145)
		(layer "F.Cu")
		(net "SSD6_PWREN")
	)
	(segment
		(start 21.843746 -402.24075)
		(end 21.99132 -402.388324)
		(width 0.17145)
		(layer "F.Cu")
		(net "SSD6_PWREN")
	)
	(segment
		(start 7.112 -362.35767)
		(end 5.09778 -360.34345)
		(width 0.17145)
		(layer "F.Cu")
		(net "SSD6_PWREN")
	)
	(via
		(at 7.112 -366.776)
		(size 0.508)
		(drill 0.254)
		(layers "F.Cu" "B.Cu")
		(net "SSD6_PWREN")
	)
	(via
		(at 19.712178 -397.609314)
		(size 0.5588)
		(drill 0.3048)
		(layers "F.Cu" "B.Cu")
		(net "SSD6_PWREN")
	)
	(segment
		(start 19.712178 -397.609314)
		(end 19.712178 -397.283178)
		(width 0.1524)
		(layer "In5.Cu")
		(net "SSD6_PWREN")
	)
	(segment
		(start 10.103866 -387.674866)
		(end 10.103866 -372.28907)
		(width 0.1524)
		(layer "In5.Cu")
		(net "SSD6_PWREN")
	)
	(segment
		(start 19.712178 -397.283178)
		(end 10.103866 -387.674866)
		(width 0.1524)
		(layer "In5.Cu")
		(net "SSD6_PWREN")
	)
	(segment
		(start 10.103866 -372.28907)
		(end 7.112 -369.297204)
		(width 0.1524)
		(layer "In5.Cu")
		(net "SSD6_PWREN")
	)
	(segment
		(start 7.112 -369.297204)
		(end 7.112 -366.776)
		(width 0.1524)
		(layer "In5.Cu")
		(net "SSD6_PWREN")
	)
	(segment
		(start 35.664902 -373.063008)
		(end 37.61613 -373.063008)
		(width 0.17145)
		(layer "F.Cu")
		(net "SSD6_PERST_N")
	)
	(segment
		(start 20.862798 -375.02973)
		(end 25.09393 -375.02973)
		(width 0.17145)
		(layer "F.Cu")
		(net "SSD6_PERST_N")
	)
	(segment
		(start 17.61871 -374.578626)
		(end 18.069814 -375.02973)
		(width 0.17145)
		(layer "F.Cu")
		(net "SSD6_PERST_N")
	)
	(segment
		(start 42.39006 -372.789958)
		(end 43.617642 -372.789958)
		(width 0.17145)
		(layer "F.Cu")
		(net "SSD6_PERST_N")
	)
	(segment
		(start 42.39006 -371.990112)
		(end 43.517312 -371.990112)
		(width 0.17145)
		(layer "F.Cu")
		(net "SSD6_PERST_N")
	)
	(segment
		(start 18.069814 -375.02973)
		(end 20.862798 -375.02973)
		(width 0.17145)
		(layer "F.Cu")
		(net "SSD6_PERST_N")
	)
	(segment
		(start 28.406598 -371.717062)
		(end 34.318956 -371.717062)
		(width 0.17145)
		(layer "F.Cu")
		(net "SSD6_PERST_N")
	)
	(segment
		(start 43.517312 -371.990112)
		(end 43.9674 -372.4402)
		(width 0.17145)
		(layer "F.Cu")
		(net "SSD6_PERST_N")
	)
	(segment
		(start 34.318956 -371.717062)
		(end 35.664902 -373.063008)
		(width 0.17145)
		(layer "F.Cu")
		(net "SSD6_PERST_N")
	)
	(segment
		(start 25.09393 -375.02973)
		(end 28.406598 -371.717062)
		(width 0.17145)
		(layer "F.Cu")
		(net "SSD6_PERST_N")
	)
	(segment
		(start 43.617642 -372.789958)
		(end 43.9674 -372.4402)
		(width 0.17145)
		(layer "F.Cu")
		(net "SSD6_PERST_N")
	)
	(via
		(at 20.862798 -375.02973)
		(size 0.7112)
		(drill 0.3556)
		(layers "F.Cu" "B.Cu")
		(net "SSD6_PERST_N")
	)
	(via
		(at 17.61871 -374.578626)
		(size 0.508)
		(drill 0.254)
		(layers "F.Cu" "B.Cu")
		(net "SSD6_PERST_N")
	)
	(via
		(at 37.61613 -373.063008)
		(size 0.508)
		(drill 0.254)
		(layers "F.Cu" "B.Cu")
		(net "SSD6_PERST_N")
	)
	(via
		(at 43.9674 -372.4402)
		(size 0.508)
		(drill 0.254)
		(layers "F.Cu" "B.Cu")
		(net "SSD6_PERST_N")
	)
	(segment
		(start 16.920972 -370.889276)
		(end 6.373876 -360.34218)
		(width 0.17145)
		(layer "B.Cu")
		(net "SSD6_PERST_N")
	)
	(segment
		(start 6.373876 -360.34218)
		(end 1.868932 -360.34218)
		(width 0.17145)
		(layer "B.Cu")
		(net "SSD6_PERST_N")
	)
	(segment
		(start 43.344592 -373.063008)
		(end 37.61613 -373.063008)
		(width 0.17145)
		(layer "B.Cu")
		(net "SSD6_PERST_N")
	)
	(segment
		(start 17.61871 -374.578626)
		(end 16.920972 -373.880888)
		(width 0.17145)
		(layer "B.Cu")
		(net "SSD6_PERST_N")
	)
	(segment
		(start 16.920972 -373.880888)
		(end 16.920972 -370.889276)
		(width 0.17145)
		(layer "B.Cu")
		(net "SSD6_PERST_N")
	)
	(segment
		(start 43.9674 -372.4402)
		(end 43.344592 -373.063008)
		(width 0.17145)
		(layer "B.Cu")
		(net "SSD6_PERST_N")
	)
	(segment
		(start 43.58513 -378.575062)
		(end 46.69155 -375.468642)
		(width 0.17145)
		(layer "F.Cu")
		(net "SSD6_CLK0_OE_N")
	)
	(segment
		(start 65.87744 -344.131646)
		(end 74.587354 -344.131646)
		(width 0.17145)
		(layer "F.Cu")
		(net "SSD6_CLK0_OE_N")
	)
	(segment
		(start 97.2185 -321.437)
		(end 97.2185 -320.167)
		(width 0.17145)
		(layer "F.Cu")
		(net "SSD6_CLK0_OE_N")
	)
	(segment
		(start 46.69155 -375.468642)
		(end 46.69155 -363.317536)
		(width 0.17145)
		(layer "F.Cu")
		(net "SSD6_CLK0_OE_N")
	)
	(segment
		(start 97.155 -320.1035)
		(end 97.2185 -320.167)
		(width 0.17145)
		(layer "F.Cu")
		(net "SSD6_CLK0_OE_N")
	)
	(segment
		(start 41.975024 -378.575062)
		(end 43.58513 -378.575062)
		(width 0.17145)
		(layer "F.Cu")
		(net "SSD6_CLK0_OE_N")
	)
	(segment
		(start 97.2185 -321.5005)
		(end 97.2185 -321.437)
		(width 0.17145)
		(layer "F.Cu")
		(net "SSD6_CLK0_OE_N")
	)
	(segment
		(start 97.155 -319.0875)
		(end 97.155 -320.1035)
		(width 0.17145)
		(layer "F.Cu")
		(net "SSD6_CLK0_OE_N")
	)
	(segment
		(start 74.587354 -344.131646)
		(end 97.2185 -321.5005)
		(width 0.17145)
		(layer "F.Cu")
		(net "SSD6_CLK0_OE_N")
	)
	(segment
		(start 46.69155 -363.317536)
		(end 65.87744 -344.131646)
		(width 0.17145)
		(layer "F.Cu")
		(net "SSD6_CLK0_OE_N")
	)
	(via
		(at 97.2185 -321.437)
		(size 0.7112)
		(drill 0.3556)
		(layers "F.Cu" "B.Cu")
		(net "SSD6_CLK0_OE_N")
	)
	(segment
		(start 8.46455 -500.44985)
		(end 7.67715 -500.44985)
		(width 0.17145)
		(layer "F.Cu")
		(net "SSD5_PWREN")
	)
	(segment
		(start 10.6172 -498.8687)
		(end 12.9159 -498.8687)
		(width 0.17145)
		(layer "F.Cu")
		(net "SSD5_PWREN")
	)
	(segment
		(start 8.46455 -499.87835)
		(end 9.4742 -498.8687)
		(width 0.17145)
		(layer "F.Cu")
		(net "SSD5_PWREN")
	)
	(segment
		(start 7.67715 -500.44985)
		(end 7.6708 -500.4562)
		(width 0.17145)
		(layer "F.Cu")
		(net "SSD5_PWREN")
	)
	(segment
		(start 12.9159 -498.8687)
		(end 14.3764 -497.4082)
		(width 0.17145)
		(layer "F.Cu")
		(net "SSD5_PWREN")
	)
	(segment
		(start 8.46455 -500.44985)
		(end 8.46455 -499.87835)
		(width 0.17145)
		(layer "F.Cu")
		(net "SSD5_PWREN")
	)
	(segment
		(start 9.4742 -498.8687)
		(end 10.6172 -498.8687)
		(width 0.17145)
		(layer "F.Cu")
		(net "SSD5_PWREN")
	)
	(segment
		(start 16.59255 -497.4082)
		(end 17.62125 -496.3795)
		(width 0.17145)
		(layer "F.Cu")
		(net "SSD5_PWREN")
	)
	(segment
		(start 14.3764 -497.4082)
		(end 16.59255 -497.4082)
		(width 0.17145)
		(layer "F.Cu")
		(net "SSD5_PWREN")
	)
	(via
		(at 7.6708 -500.4562)
		(size 0.508)
		(drill 0.254)
		(layers "F.Cu" "B.Cu")
		(net "SSD5_PWREN")
	)
	(via
		(at 37.3888 -446.1764)
		(size 0.7112)
		(drill 0.3556)
		(layers "F.Cu" "B.Cu")
		(net "SSD5_PWREN")
	)
	(via
		(at 38.468808 -459.74)
		(size 0.508)
		(drill 0.254)
		(layers "F.Cu" "B.Cu")
		(net "SSD5_PWREN")
	)
	(segment
		(start 4.5212 -433.7812)
		(end 4.953 -434.213)
		(width 0.17145)
		(layer "B.Cu")
		(net "SSD5_PWREN")
	)
	(segment
		(start 3.9624 -433.7812)
		(end 4.5212 -433.7812)
		(width 0.17145)
		(layer "B.Cu")
		(net "SSD5_PWREN")
	)
	(segment
		(start 24.738076 -442.6839)
		(end 24.833072 -442.778896)
		(width 0.17145)
		(layer "B.Cu")
		(net "SSD5_PWREN")
	)
	(segment
		(start 1.868932 -433.541932)
		(end 3.723132 -433.541932)
		(width 0.17145)
		(layer "B.Cu")
		(net "SSD5_PWREN")
	)
	(segment
		(start 4.953 -434.213)
		(end 5.51688 -434.213)
		(width 0.17145)
		(layer "B.Cu")
		(net "SSD5_PWREN")
	)
	(segment
		(start 5.51688 -434.213)
		(end 12.085828 -440.781948)
		(width 0.17145)
		(layer "B.Cu")
		(net "SSD5_PWREN")
	)
	(segment
		(start 38.468808 -459.74)
		(end 38.468808 -447.256408)
		(width 0.17145)
		(layer "B.Cu")
		(net "SSD5_PWREN")
	)
	(segment
		(start 38.468808 -447.256408)
		(end 37.3888 -446.1764)
		(width 0.17145)
		(layer "B.Cu")
		(net "SSD5_PWREN")
	)
	(segment
		(start 3.723132 -433.541932)
		(end 3.9624 -433.7812)
		(width 0.17145)
		(layer "B.Cu")
		(net "SSD5_PWREN")
	)
	(segment
		(start 24.833072 -442.778896)
		(end 33.991296 -442.778896)
		(width 0.17145)
		(layer "B.Cu")
		(net "SSD5_PWREN")
	)
	(segment
		(start 12.085828 -440.781948)
		(end 19.167348 -440.781948)
		(width 0.17145)
		(layer "B.Cu")
		(net "SSD5_PWREN")
	)
	(segment
		(start 21.0693 -442.6839)
		(end 24.738076 -442.6839)
		(width 0.17145)
		(layer "B.Cu")
		(net "SSD5_PWREN")
	)
	(segment
		(start 33.991296 -442.778896)
		(end 37.3888 -446.1764)
		(width 0.17145)
		(layer "B.Cu")
		(net "SSD5_PWREN")
	)
	(segment
		(start 19.167348 -440.781948)
		(end 21.0693 -442.6839)
		(width 0.17145)
		(layer "B.Cu")
		(net "SSD5_PWREN")
	)
	(segment
		(start 40.386 -463.042)
		(end 38.468808 -461.124808)
		(width 0.1524)
		(layer "In5.Cu")
		(net "SSD5_PWREN")
	)
	(segment
		(start 7.93115 -500.19585)
		(end 33.02635 -500.19585)
		(width 0.1524)
		(layer "In5.Cu")
		(net "SSD5_PWREN")
	)
	(segment
		(start 37.9222 -498.9576)
		(end 40.386 -496.4938)
		(width 0.1524)
		(layer "In5.Cu")
		(net "SSD5_PWREN")
	)
	(segment
		(start 34.2646 -498.9576)
		(end 37.9222 -498.9576)
		(width 0.1524)
		(layer "In5.Cu")
		(net "SSD5_PWREN")
	)
	(segment
		(start 38.468808 -461.124808)
		(end 38.468808 -459.74)
		(width 0.1524)
		(layer "In5.Cu")
		(net "SSD5_PWREN")
	)
	(segment
		(start 40.386 -496.4938)
		(end 40.386 -463.042)
		(width 0.1524)
		(layer "In5.Cu")
		(net "SSD5_PWREN")
	)
	(segment
		(start 33.02635 -500.19585)
		(end 34.2646 -498.9576)
		(width 0.1524)
		(layer "In5.Cu")
		(net "SSD5_PWREN")
	)
	(segment
		(start 7.6708 -500.4562)
		(end 7.93115 -500.19585)
		(width 0.1524)
		(layer "In5.Cu")
		(net "SSD5_PWREN")
	)
	(segment
		(start 21.313394 -479.172524)
		(end 15.63497 -479.172524)
		(width 0.17145)
		(layer "F.Cu")
		(net "SSD5_PERST_N")
	)
	(segment
		(start 43.690794 -475.790006)
		(end 44.069 -475.4118)
		(width 0.17145)
		(layer "F.Cu")
		(net "SSD5_PERST_N")
	)
	(segment
		(start 15.63497 -479.172524)
		(end 15.467838 -479.005392)
		(width 0.17145)
		(layer "F.Cu")
		(net "SSD5_PERST_N")
	)
	(segment
		(start 28.829 -476.49638)
		(end 27.98953 -476.49638)
		(width 0.17145)
		(layer "F.Cu")
		(net "SSD5_PERST_N")
	)
	(segment
		(start 42.39006 -474.99016)
		(end 43.64736 -474.99016)
		(width 0.17145)
		(layer "F.Cu")
		(net "SSD5_PERST_N")
	)
	(segment
		(start 27.98953 -476.49638)
		(end 25.313386 -479.172524)
		(width 0.17145)
		(layer "F.Cu")
		(net "SSD5_PERST_N")
	)
	(segment
		(start 25.313386 -479.172524)
		(end 21.313394 -479.172524)
		(width 0.17145)
		(layer "F.Cu")
		(net "SSD5_PERST_N")
	)
	(segment
		(start 43.64736 -474.99016)
		(end 44.069 -475.4118)
		(width 0.17145)
		(layer "F.Cu")
		(net "SSD5_PERST_N")
	)
	(segment
		(start 42.39006 -475.790006)
		(end 43.690794 -475.790006)
		(width 0.17145)
		(layer "F.Cu")
		(net "SSD5_PERST_N")
	)
	(via
		(at 15.467838 -479.005392)
		(size 0.508)
		(drill 0.254)
		(layers "F.Cu" "B.Cu")
		(net "SSD5_PERST_N")
	)
	(via
		(at 21.313394 -479.172524)
		(size 0.7112)
		(drill 0.3556)
		(layers "F.Cu" "B.Cu")
		(net "SSD5_PERST_N")
	)
	(via
		(at 28.829 -476.49638)
		(size 0.508)
		(drill 0.254)
		(layers "F.Cu" "B.Cu")
		(net "SSD5_PERST_N")
	)
	(via
		(at 44.069 -475.4118)
		(size 0.508)
		(drill 0.254)
		(layers "F.Cu" "B.Cu")
		(net "SSD5_PERST_N")
	)
	(segment
		(start 15.418054 -457.380086)
		(end 15.09522 -457.057252)
		(width 0.17145)
		(layer "B.Cu")
		(net "SSD5_PERST_N")
	)
	(segment
		(start 15.09522 -457.057252)
		(end 15.094966 -457.057252)
		(width 0.17145)
		(layer "B.Cu")
		(net "SSD5_PERST_N")
	)
	(segment
		(start 15.467838 -479.005392)
		(end 15.4178 -478.955354)
		(width 0.17145)
		(layer "B.Cu")
		(net "SSD5_PERST_N")
	)
	(segment
		(start 15.4178 -477.800416)
		(end 15.764002 -477.454214)
		(width 0.17145)
		(layer "B.Cu")
		(net "SSD5_PERST_N")
	)
	(segment
		(start 7.188454 -454.2409)
		(end 4.8895 -451.941946)
		(width 0.17145)
		(layer "B.Cu")
		(net "SSD5_PERST_N")
	)
	(segment
		(start 44.069 -475.4118)
		(end 42.98442 -476.49638)
		(width 0.17145)
		(layer "B.Cu")
		(net "SSD5_PERST_N")
	)
	(segment
		(start 15.4178 -478.955354)
		(end 15.4178 -477.800416)
		(width 0.17145)
		(layer "B.Cu")
		(net "SSD5_PERST_N")
	)
	(segment
		(start 15.764002 -472.773248)
		(end 15.418054 -472.4273)
		(width 0.17145)
		(layer "B.Cu")
		(net "SSD5_PERST_N")
	)
	(segment
		(start 15.764002 -477.454214)
		(end 15.764002 -472.773248)
		(width 0.17145)
		(layer "B.Cu")
		(net "SSD5_PERST_N")
	)
	(segment
		(start 12.278614 -454.2409)
		(end 7.188454 -454.2409)
		(width 0.17145)
		(layer "B.Cu")
		(net "SSD5_PERST_N")
	)
	(segment
		(start 4.8895 -451.941946)
		(end 1.868932 -451.941946)
		(width 0.17145)
		(layer "B.Cu")
		(net "SSD5_PERST_N")
	)
	(segment
		(start 42.98442 -476.49638)
		(end 28.829 -476.49638)
		(width 0.17145)
		(layer "B.Cu")
		(net "SSD5_PERST_N")
	)
	(segment
		(start 15.418054 -472.4273)
		(end 15.418054 -457.380086)
		(width 0.17145)
		(layer "B.Cu")
		(net "SSD5_PERST_N")
	)
	(segment
		(start 15.094966 -457.057252)
		(end 12.278614 -454.2409)
		(width 0.17145)
		(layer "B.Cu")
		(net "SSD5_PERST_N")
	)
	(segment
		(start 88.2015 -448.056)
		(end 88.2015 -453.660002)
		(width 0.17145)
		(layer "F.Cu")
		(net "SSD5_CLK0_OE_N")
	)
	(segment
		(start 70.916546 -470.944956)
		(end 47.286672 -470.944956)
		(width 0.17145)
		(layer "F.Cu")
		(net "SSD5_CLK0_OE_N")
	)
	(segment
		(start 43.58513 -481.57511)
		(end 41.975024 -481.57511)
		(width 0.17145)
		(layer "F.Cu")
		(net "SSD5_CLK0_OE_N")
	)
	(segment
		(start 88.2015 -453.660002)
		(end 70.916546 -470.944956)
		(width 0.17145)
		(layer "F.Cu")
		(net "SSD5_CLK0_OE_N")
	)
	(segment
		(start 46.599856 -478.560384)
		(end 43.58513 -481.57511)
		(width 0.17145)
		(layer "F.Cu")
		(net "SSD5_CLK0_OE_N")
	)
	(segment
		(start 88.138 -445.7065)
		(end 88.138 -446.7225)
		(width 0.17145)
		(layer "F.Cu")
		(net "SSD5_CLK0_OE_N")
	)
	(segment
		(start 46.599856 -471.631772)
		(end 46.599856 -478.560384)
		(width 0.17145)
		(layer "F.Cu")
		(net "SSD5_CLK0_OE_N")
	)
	(segment
		(start 88.138 -446.7225)
		(end 88.2015 -446.786)
		(width 0.17145)
		(layer "F.Cu")
		(net "SSD5_CLK0_OE_N")
	)
	(segment
		(start 88.2015 -448.056)
		(end 88.2015 -446.786)
		(width 0.17145)
		(layer "F.Cu")
		(net "SSD5_CLK0_OE_N")
	)
	(segment
		(start 47.286672 -470.944956)
		(end 46.599856 -471.631772)
		(width 0.17145)
		(layer "F.Cu")
		(net "SSD5_CLK0_OE_N")
	)
	(via
		(at 88.2015 -448.056)
		(size 0.7112)
		(drill 0.3556)
		(layers "F.Cu" "B.Cu")
		(net "SSD5_CLK0_OE_N")
	)
	(segment
		(start 210.28025 -92.1385)
		(end 210.28025 -92.80525)
		(width 0.17145)
		(layer "F.Cu")
		(net "SSD4_PWREN")
	)
	(segment
		(start 210.82 -93.345)
		(end 210.82 -94.488)
		(width 0.17145)
		(layer "F.Cu")
		(net "SSD4_PWREN")
	)
	(segment
		(start 205.170024 -95.95485)
		(end 206.22895 -95.95485)
		(width 0.17145)
		(layer "F.Cu")
		(net "SSD4_PWREN")
	)
	(segment
		(start 206.22895 -95.428054)
		(end 206.978504 -94.6785)
		(width 0.17145)
		(layer "F.Cu")
		(net "SSD4_PWREN")
	)
	(segment
		(start 210.82 -94.488)
		(end 210.6295 -94.6785)
		(width 0.17145)
		(layer "F.Cu")
		(net "SSD4_PWREN")
	)
	(segment
		(start 210.6295 -94.6785)
		(end 208.534 -94.6785)
		(width 0.17145)
		(layer "F.Cu")
		(net "SSD4_PWREN")
	)
	(segment
		(start 210.28025 -92.80525)
		(end 210.82 -93.345)
		(width 0.17145)
		(layer "F.Cu")
		(net "SSD4_PWREN")
	)
	(segment
		(start 208.534 -94.6785)
		(end 207.391 -94.6785)
		(width 0.17145)
		(layer "F.Cu")
		(net "SSD4_PWREN")
	)
	(segment
		(start 206.978504 -94.6785)
		(end 207.391 -94.6785)
		(width 0.17145)
		(layer "F.Cu")
		(net "SSD4_PWREN")
	)
	(segment
		(start 206.22895 -95.95485)
		(end 206.22895 -95.428054)
		(width 0.17145)
		(layer "F.Cu")
		(net "SSD4_PWREN")
	)
	(via
		(at 205.170024 -95.95485)
		(size 0.5588)
		(drill 0.3048)
		(layers "F.Cu" "B.Cu")
		(net "SSD4_PWREN")
	)
	(segment
		(start 10.033 -91.2876)
		(end 19.1262 -82.1944)
		(width 0.17145)
		(layer "B.Cu")
		(net "SSD4_PWREN")
	)
	(segment
		(start 30.226 -52.705)
		(end 38.354 -44.577)
		(width 0.17145)
		(layer "B.Cu")
		(net "SSD4_PWREN")
	)
	(segment
		(start 235.1532 -61.8998)
		(end 234.2642 -62.7888)
		(width 0.17145)
		(layer "B.Cu")
		(net "SSD4_PWREN")
	)
	(segment
		(start 225.552 -42.291)
		(end 226.06 -42.799)
		(width 0.17145)
		(layer "B.Cu")
		(net "SSD4_PWREN")
	)
	(segment
		(start 30.226 -55.631334)
		(end 30.226 -52.705)
		(width 0.17145)
		(layer "B.Cu")
		(net "SSD4_PWREN")
	)
	(segment
		(start 226.06 -42.799)
		(end 228.6 -42.799)
		(width 0.17145)
		(layer "B.Cu")
		(net "SSD4_PWREN")
	)
	(segment
		(start 1.868932 -198.341996)
		(end 4.031996 -198.341996)
		(width 0.17145)
		(layer "B.Cu")
		(net "SSD4_PWREN")
	)
	(segment
		(start 4.699 -199.009)
		(end 7.531608 -199.009)
		(width 0.17145)
		(layer "B.Cu")
		(net "SSD4_PWREN")
	)
	(segment
		(start 199.644 -44.577)
		(end 205.1812 -39.0398)
		(width 0.17145)
		(layer "B.Cu")
		(net "SSD4_PWREN")
	)
	(segment
		(start 230.375714 -62.7888)
		(end 230.299514 -62.865)
		(width 0.17145)
		(layer "B.Cu")
		(net "SSD4_PWREN")
	)
	(segment
		(start 223.0628 -39.0398)
		(end 225.552 -41.529)
		(width 0.17145)
		(layer "B.Cu")
		(net "SSD4_PWREN")
	)
	(segment
		(start 19.1262 -82.1944)
		(end 19.1262 -73.0758)
		(width 0.17145)
		(layer "B.Cu")
		(net "SSD4_PWREN")
	)
	(segment
		(start 230.299514 -62.865)
		(end 228.809296 -62.865)
		(width 0.17145)
		(layer "B.Cu")
		(net "SSD4_PWREN")
	)
	(segment
		(start 7.531608 -199.009)
		(end 10.033 -196.507608)
		(width 0.17145)
		(layer "B.Cu")
		(net "SSD4_PWREN")
	)
	(segment
		(start 228.809296 -62.865)
		(end 228.1682 -63.506096)
		(width 0.17145)
		(layer "B.Cu")
		(net "SSD4_PWREN")
	)
	(segment
		(start 10.033 -196.507608)
		(end 10.033 -91.2876)
		(width 0.17145)
		(layer "B.Cu")
		(net "SSD4_PWREN")
	)
	(segment
		(start 228.6 -42.799)
		(end 235.1532 -49.3522)
		(width 0.17145)
		(layer "B.Cu")
		(net "SSD4_PWREN")
	)
	(segment
		(start 38.354 -44.577)
		(end 199.644 -44.577)
		(width 0.17145)
		(layer "B.Cu")
		(net "SSD4_PWREN")
	)
	(segment
		(start 26.230834 -65.971166)
		(end 26.230834 -59.6265)
		(width 0.17145)
		(layer "B.Cu")
		(net "SSD4_PWREN")
	)
	(segment
		(start 228.1682 -63.506096)
		(end 228.1682 -65.1256)
		(width 0.17145)
		(layer "B.Cu")
		(net "SSD4_PWREN")
	)
	(segment
		(start 235.1532 -49.3522)
		(end 235.1532 -61.8998)
		(width 0.17145)
		(layer "B.Cu")
		(net "SSD4_PWREN")
	)
	(segment
		(start 26.230834 -59.6265)
		(end 30.226 -55.631334)
		(width 0.17145)
		(layer "B.Cu")
		(net "SSD4_PWREN")
	)
	(segment
		(start 205.1812 -39.0398)
		(end 223.0628 -39.0398)
		(width 0.17145)
		(layer "B.Cu")
		(net "SSD4_PWREN")
	)
	(segment
		(start 226.187 -94.869)
		(end 206.255874 -94.869)
		(width 0.17145)
		(layer "B.Cu")
		(net "SSD4_PWREN")
	)
	(segment
		(start 4.031996 -198.341996)
		(end 4.699 -199.009)
		(width 0.17145)
		(layer "B.Cu")
		(net "SSD4_PWREN")
	)
	(segment
		(start 230.505 -67.4624)
		(end 230.505 -90.551)
		(width 0.17145)
		(layer "B.Cu")
		(net "SSD4_PWREN")
	)
	(segment
		(start 19.1262 -73.0758)
		(end 26.230834 -65.971166)
		(width 0.17145)
		(layer "B.Cu")
		(net "SSD4_PWREN")
	)
	(segment
		(start 230.505 -90.551)
		(end 226.187 -94.869)
		(width 0.17145)
		(layer "B.Cu")
		(net "SSD4_PWREN")
	)
	(segment
		(start 225.552 -41.529)
		(end 225.552 -42.291)
		(width 0.17145)
		(layer "B.Cu")
		(net "SSD4_PWREN")
	)
	(segment
		(start 228.1682 -65.1256)
		(end 230.505 -67.4624)
		(width 0.17145)
		(layer "B.Cu")
		(net "SSD4_PWREN")
	)
	(segment
		(start 234.2642 -62.7888)
		(end 230.375714 -62.7888)
		(width 0.17145)
		(layer "B.Cu")
		(net "SSD4_PWREN")
	)
	(segment
		(start 206.255874 -94.869)
		(end 205.170024 -95.95485)
		(width 0.17145)
		(layer "B.Cu")
		(net "SSD4_PWREN")
	)
	(segment
		(start 9.48055 -185.457084)
		(end 9.48055 -165.70325)
		(width 0.17145)
		(layer "F.Cu")
		(net "SSD4_PERST_N")
	)
	(segment
		(start 7.035546 -187.33389)
		(end 7.603744 -187.33389)
		(width 0.17145)
		(layer "F.Cu")
		(net "SSD4_PERST_N")
	)
	(segment
		(start 228.547168 -62.989968)
		(end 229.0064 -63.4492)
		(width 0.17145)
		(layer "F.Cu")
		(net "SSD4_PERST_N")
	)
	(segment
		(start 227.389944 -62.989968)
		(end 228.547168 -62.989968)
		(width 0.17145)
		(layer "F.Cu")
		(net "SSD4_PERST_N")
	)
	(segment
		(start 227.389944 -63.789814)
		(end 228.665786 -63.789814)
		(width 0.17145)
		(layer "F.Cu")
		(net "SSD4_PERST_N")
	)
	(segment
		(start 16.471138 -75.620626)
		(end 16.91894 -75.172824)
		(width 0.17145)
		(layer "F.Cu")
		(net "SSD4_PERST_N")
	)
	(segment
		(start 10.375392 -164.808408)
		(end 10.375392 -99.645724)
		(width 0.17145)
		(layer "F.Cu")
		(net "SSD4_PERST_N")
	)
	(segment
		(start 9.927844 -165.255956)
		(end 10.375392 -164.808408)
		(width 0.17145)
		(layer "F.Cu")
		(net "SSD4_PERST_N")
	)
	(segment
		(start 7.603744 -187.33389)
		(end 9.48055 -185.457084)
		(width 0.17145)
		(layer "F.Cu")
		(net "SSD4_PERST_N")
	)
	(segment
		(start 9.48055 -165.70325)
		(end 9.927844 -165.255956)
		(width 0.17145)
		(layer "F.Cu")
		(net "SSD4_PERST_N")
	)
	(segment
		(start 10.375392 -99.645724)
		(end 16.471138 -93.549978)
		(width 0.17145)
		(layer "F.Cu")
		(net "SSD4_PERST_N")
	)
	(segment
		(start 16.471138 -93.549978)
		(end 16.471138 -75.620626)
		(width 0.17145)
		(layer "F.Cu")
		(net "SSD4_PERST_N")
	)
	(segment
		(start 228.665786 -63.789814)
		(end 229.0064 -63.4492)
		(width 0.17145)
		(layer "F.Cu")
		(net "SSD4_PERST_N")
	)
	(via
		(at 16.91894 -75.172824)
		(size 0.508)
		(drill 0.254)
		(layers "F.Cu" "B.Cu")
		(net "SSD4_PERST_N")
	)
	(via
		(at 229.0064 -63.4492)
		(size 0.508)
		(drill 0.254)
		(layers "F.Cu" "B.Cu")
		(net "SSD4_PERST_N")
	)
	(via
		(at 7.035546 -187.33389)
		(size 0.508)
		(drill 0.254)
		(layers "F.Cu" "B.Cu")
		(net "SSD4_PERST_N")
	)
	(via
		(at 9.927844 -165.255956)
		(size 0.7112)
		(drill 0.3556)
		(layers "F.Cu" "B.Cu")
		(net "SSD4_PERST_N")
	)
	(segment
		(start 229.0064 -63.4492)
		(end 234.5436 -63.4492)
		(width 0.17145)
		(layer "B.Cu")
		(net "SSD4_PERST_N")
	)
	(segment
		(start 3.310128 -186.34202)
		(end 1.868932 -186.34202)
		(width 0.17145)
		(layer "B.Cu")
		(net "SSD4_PERST_N")
	)
	(segment
		(start 3.724148 -185.861706)
		(end 3.724148 -185.928)
		(width 0.17145)
		(layer "B.Cu")
		(net "SSD4_PERST_N")
	)
	(segment
		(start 234.5436 -63.4492)
		(end 235.7374 -62.2554)
		(width 0.17145)
		(layer "B.Cu")
		(net "SSD4_PERST_N")
	)
	(segment
		(start 28.46705 -52.120038)
		(end 28.46705 -54.920642)
		(width 0.17145)
		(layer "B.Cu")
		(net "SSD4_PERST_N")
	)
	(segment
		(start 225.0694 -37.2618)
		(end 204.615288 -37.2618)
		(width 0.17145)
		(layer "B.Cu")
		(net "SSD4_PERST_N")
	)
	(segment
		(start 7.035546 -187.33389)
		(end 6.23189 -187.33389)
		(width 0.17145)
		(layer "B.Cu")
		(net "SSD4_PERST_N")
	)
	(segment
		(start 4.486148 -185.588148)
		(end 3.997706 -185.588148)
		(width 0.17145)
		(layer "B.Cu")
		(net "SSD4_PERST_N")
	)
	(segment
		(start 3.997706 -185.588148)
		(end 3.724148 -185.861706)
		(width 0.17145)
		(layer "B.Cu")
		(net "SSD4_PERST_N")
	)
	(segment
		(start 24.562054 -58.825638)
		(end 24.562054 -65.296034)
		(width 0.17145)
		(layer "B.Cu")
		(net "SSD4_PERST_N")
	)
	(segment
		(start 198.957438 -42.91965)
		(end 37.667438 -42.91965)
		(width 0.17145)
		(layer "B.Cu")
		(net "SSD4_PERST_N")
	)
	(segment
		(start 28.46705 -54.920642)
		(end 24.562054 -58.825638)
		(width 0.17145)
		(layer "B.Cu")
		(net "SSD4_PERST_N")
	)
	(segment
		(start 235.7374 -47.9298)
		(end 225.0694 -37.2618)
		(width 0.17145)
		(layer "B.Cu")
		(net "SSD4_PERST_N")
	)
	(segment
		(start 37.667438 -42.91965)
		(end 28.46705 -52.120038)
		(width 0.17145)
		(layer "B.Cu")
		(net "SSD4_PERST_N")
	)
	(segment
		(start 3.724148 -185.928)
		(end 3.310128 -186.34202)
		(width 0.17145)
		(layer "B.Cu")
		(net "SSD4_PERST_N")
	)
	(segment
		(start 235.7374 -62.2554)
		(end 235.7374 -47.9298)
		(width 0.17145)
		(layer "B.Cu")
		(net "SSD4_PERST_N")
	)
	(segment
		(start 17.46885 -74.622914)
		(end 16.91894 -75.172824)
		(width 0.17145)
		(layer "B.Cu")
		(net "SSD4_PERST_N")
	)
	(segment
		(start 24.562054 -65.296034)
		(end 17.46885 -72.389238)
		(width 0.17145)
		(layer "B.Cu")
		(net "SSD4_PERST_N")
	)
	(segment
		(start 204.615288 -37.2618)
		(end 198.957438 -42.91965)
		(width 0.17145)
		(layer "B.Cu")
		(net "SSD4_PERST_N")
	)
	(segment
		(start 6.23189 -187.33389)
		(end 4.486148 -185.588148)
		(width 0.17145)
		(layer "B.Cu")
		(net "SSD4_PERST_N")
	)
	(segment
		(start 17.46885 -72.389238)
		(end 17.46885 -74.622914)
		(width 0.17145)
		(layer "B.Cu")
		(net "SSD4_PERST_N")
	)
	(segment
		(start 97.028 -196.9135)
		(end 97.028 -195.8975)
		(width 0.17145)
		(layer "F.Cu")
		(net "SSD4_CLK0_OE_N")
	)
	(segment
		(start 96.9645 -195.834)
		(end 96.9645 -194.564)
		(width 0.17145)
		(layer "F.Cu")
		(net "SSD4_CLK0_OE_N")
	)
	(segment
		(start 96.9645 -194.564)
		(end 96.9645 -172.642276)
		(width 0.17145)
		(layer "F.Cu")
		(net "SSD4_CLK0_OE_N")
	)
	(segment
		(start 97.028 -195.8975)
		(end 96.9645 -195.834)
		(width 0.17145)
		(layer "F.Cu")
		(net "SSD4_CLK0_OE_N")
	)
	(segment
		(start 228.585014 -69.574918)
		(end 226.974908 -69.574918)
		(width 0.17145)
		(layer "F.Cu")
		(net "SSD4_CLK0_OE_N")
	)
	(segment
		(start 229.514146 -50.84445)
		(end 231.73055 -53.060854)
		(width 0.17145)
		(layer "F.Cu")
		(net "SSD4_CLK0_OE_N")
	)
	(segment
		(start 96.9645 -172.642276)
		(end 218.762326 -50.84445)
		(width 0.17145)
		(layer "F.Cu")
		(net "SSD4_CLK0_OE_N")
	)
	(segment
		(start 231.73055 -53.060854)
		(end 231.73055 -66.429382)
		(width 0.17145)
		(layer "F.Cu")
		(net "SSD4_CLK0_OE_N")
	)
	(segment
		(start 218.762326 -50.84445)
		(end 229.514146 -50.84445)
		(width 0.17145)
		(layer "F.Cu")
		(net "SSD4_CLK0_OE_N")
	)
	(segment
		(start 231.73055 -66.429382)
		(end 228.585014 -69.574918)
		(width 0.17145)
		(layer "F.Cu")
		(net "SSD4_CLK0_OE_N")
	)
	(via
		(at 96.9645 -194.564)
		(size 0.7112)
		(drill 0.3556)
		(layers "F.Cu" "B.Cu")
		(net "SSD4_CLK0_OE_N")
	)
	(segment
		(start 10.149586 -286.590232)
		(end 9.354058 -286.590232)
		(width 0.17145)
		(layer "F.Cu")
		(net "SSD3_PWREN")
	)
	(segment
		(start 210.947 -197.358)
		(end 210.6295 -197.6755)
		(width 0.17145)
		(layer "F.Cu")
		(net "SSD3_PWREN")
	)
	(segment
		(start 205.297024 -198.95185)
		(end 206.22895 -198.95185)
		(width 0.17145)
		(layer "F.Cu")
		(net "SSD3_PWREN")
	)
	(segment
		(start 7.25932 -285.814516)
		(end 4.001516 -285.814516)
		(width 0.17145)
		(layer "F.Cu")
		(net "SSD3_PWREN")
	)
	(segment
		(start 9.354058 -286.590232)
		(end 9.12114 -286.357314)
		(width 0.17145)
		(layer "F.Cu")
		(net "SSD3_PWREN")
	)
	(segment
		(start 210.6295 -197.6755)
		(end 208.534 -197.6755)
		(width 0.17145)
		(layer "F.Cu")
		(net "SSD3_PWREN")
	)
	(segment
		(start 4.001516 -285.814516)
		(end 3.329178 -285.142178)
		(width 0.17145)
		(layer "F.Cu")
		(net "SSD3_PWREN")
	)
	(segment
		(start 206.22895 -198.425054)
		(end 206.978504 -197.6755)
		(width 0.17145)
		(layer "F.Cu")
		(net "SSD3_PWREN")
	)
	(segment
		(start 206.22895 -198.95185)
		(end 206.22895 -198.425054)
		(width 0.17145)
		(layer "F.Cu")
		(net "SSD3_PWREN")
	)
	(segment
		(start 9.12114 -286.357314)
		(end 7.802118 -286.357314)
		(width 0.17145)
		(layer "F.Cu")
		(net "SSD3_PWREN")
	)
	(segment
		(start 206.978504 -197.6755)
		(end 207.391 -197.6755)
		(width 0.17145)
		(layer "F.Cu")
		(net "SSD3_PWREN")
	)
	(segment
		(start 7.802118 -286.357314)
		(end 7.25932 -285.814516)
		(width 0.17145)
		(layer "F.Cu")
		(net "SSD3_PWREN")
	)
	(segment
		(start 3.329178 -285.142178)
		(end 2.249932 -285.142178)
		(width 0.17145)
		(layer "F.Cu")
		(net "SSD3_PWREN")
	)
	(segment
		(start 210.28025 -195.73875)
		(end 210.947 -196.4055)
		(width 0.17145)
		(layer "F.Cu")
		(net "SSD3_PWREN")
	)
	(segment
		(start 210.28025 -195.1355)
		(end 210.28025 -195.73875)
		(width 0.17145)
		(layer "F.Cu")
		(net "SSD3_PWREN")
	)
	(segment
		(start 208.534 -197.6755)
		(end 207.391 -197.6755)
		(width 0.17145)
		(layer "F.Cu")
		(net "SSD3_PWREN")
	)
	(segment
		(start 210.947 -196.4055)
		(end 210.947 -197.358)
		(width 0.17145)
		(layer "F.Cu")
		(net "SSD3_PWREN")
	)
	(via
		(at 10.149586 -286.590232)
		(size 0.508)
		(drill 0.254)
		(layers "F.Cu" "B.Cu")
		(net "SSD3_PWREN")
	)
	(via
		(at 39.5986 -242.3668)
		(size 0.508)
		(drill 0.254)
		(layers "F.Cu" "B.Cu")
		(net "SSD3_PWREN")
	)
	(via
		(at 205.297024 -198.95185)
		(size 0.5588)
		(drill 0.3048)
		(layers "F.Cu" "B.Cu")
		(net "SSD3_PWREN")
	)
	(segment
		(start 31.1912 -265.925808)
		(end 31.1912 -250.6218)
		(width 0.17145)
		(layer "B.Cu")
		(net "SSD3_PWREN")
	)
	(segment
		(start 31.1912 -250.6218)
		(end 39.4462 -242.3668)
		(width 0.17145)
		(layer "B.Cu")
		(net "SSD3_PWREN")
	)
	(segment
		(start 10.149586 -286.590232)
		(end 10.526776 -286.590232)
		(width 0.17145)
		(layer "B.Cu")
		(net "SSD3_PWREN")
	)
	(segment
		(start 10.526776 -286.590232)
		(end 31.1912 -265.925808)
		(width 0.17145)
		(layer "B.Cu")
		(net "SSD3_PWREN")
	)
	(segment
		(start 39.4462 -242.3668)
		(end 39.5986 -242.3668)
		(width 0.17145)
		(layer "B.Cu")
		(net "SSD3_PWREN")
	)
	(segment
		(start 137.15238 -204.8256)
		(end 112.55502 -204.8256)
		(width 0.1524)
		(layer "In5.Cu")
		(net "SSD3_PWREN")
	)
	(segment
		(start 144.061434 -211.734654)
		(end 137.15238 -204.8256)
		(width 0.1524)
		(layer "In5.Cu")
		(net "SSD3_PWREN")
	)
	(segment
		(start 109.8296 -217.31478)
		(end 99.02698 -228.1174)
		(width 0.1524)
		(layer "In5.Cu")
		(net "SSD3_PWREN")
	)
	(segment
		(start 109.8296 -207.55102)
		(end 109.8296 -217.31478)
		(width 0.1524)
		(layer "In5.Cu")
		(net "SSD3_PWREN")
	)
	(segment
		(start 57.60974 -228.1174)
		(end 43.13174 -242.5954)
		(width 0.1524)
		(layer "In5.Cu")
		(net "SSD3_PWREN")
	)
	(segment
		(start 205.678024 -199.33285)
		(end 205.678024 -205.801976)
		(width 0.1524)
		(layer "In5.Cu")
		(net "SSD3_PWREN")
	)
	(segment
		(start 144.502886 -211.734654)
		(end 144.061434 -211.734654)
		(width 0.1524)
		(layer "In5.Cu")
		(net "SSD3_PWREN")
	)
	(segment
		(start 99.02698 -228.1174)
		(end 57.60974 -228.1174)
		(width 0.1524)
		(layer "In5.Cu")
		(net "SSD3_PWREN")
	)
	(segment
		(start 144.50314 -211.7344)
		(end 144.502886 -211.734654)
		(width 0.1524)
		(layer "In5.Cu")
		(net "SSD3_PWREN")
	)
	(segment
		(start 205.678024 -205.801976)
		(end 199.7456 -211.7344)
		(width 0.1524)
		(layer "In5.Cu")
		(net "SSD3_PWREN")
	)
	(segment
		(start 205.297024 -198.95185)
		(end 205.678024 -199.33285)
		(width 0.1524)
		(layer "In5.Cu")
		(net "SSD3_PWREN")
	)
	(segment
		(start 112.55502 -204.8256)
		(end 109.8296 -207.55102)
		(width 0.1524)
		(layer "In5.Cu")
		(net "SSD3_PWREN")
	)
	(segment
		(start 39.8272 -242.5954)
		(end 39.5986 -242.3668)
		(width 0.1524)
		(layer "In5.Cu")
		(net "SSD3_PWREN")
	)
	(segment
		(start 43.13174 -242.5954)
		(end 39.8272 -242.5954)
		(width 0.1524)
		(layer "In5.Cu")
		(net "SSD3_PWREN")
	)
	(segment
		(start 199.7456 -211.7344)
		(end 144.50314 -211.7344)
		(width 0.1524)
		(layer "In5.Cu")
		(net "SSD3_PWREN")
	)
	(segment
		(start 3.957066 -285.262066)
		(end 7.488174 -285.262066)
		(width 0.17145)
		(layer "F.Cu")
		(net "SSD3_PERST_N")
	)
	(segment
		(start 227.389944 -165.990016)
		(end 228.499416 -165.990016)
		(width 0.17145)
		(layer "F.Cu")
		(net "SSD3_PERST_N")
	)
	(segment
		(start 227.389944 -166.789862)
		(end 228.510338 -166.789862)
		(width 0.17145)
		(layer "F.Cu")
		(net "SSD3_PERST_N")
	)
	(segment
		(start 3.249422 -284.342078)
		(end 3.707384 -284.80004)
		(width 0.17145)
		(layer "F.Cu")
		(net "SSD3_PERST_N")
	)
	(segment
		(start 7.488174 -285.262066)
		(end 7.992618 -285.76651)
		(width 0.17145)
		(layer "F.Cu")
		(net "SSD3_PERST_N")
	)
	(segment
		(start 9.564878 -285.76651)
		(end 10.568432 -285.76651)
		(width 0.17145)
		(layer "F.Cu")
		(net "SSD3_PERST_N")
	)
	(segment
		(start 228.499416 -165.990016)
		(end 228.9048 -166.3954)
		(width 0.17145)
		(layer "F.Cu")
		(net "SSD3_PERST_N")
	)
	(segment
		(start 3.707384 -285.012384)
		(end 3.957066 -285.262066)
		(width 0.17145)
		(layer "F.Cu")
		(net "SSD3_PERST_N")
	)
	(segment
		(start 2.249932 -284.342078)
		(end 3.249422 -284.342078)
		(width 0.17145)
		(layer "F.Cu")
		(net "SSD3_PERST_N")
	)
	(segment
		(start 228.510338 -166.789862)
		(end 228.9048 -166.3954)
		(width 0.17145)
		(layer "F.Cu")
		(net "SSD3_PERST_N")
	)
	(segment
		(start 7.992618 -285.76651)
		(end 9.564878 -285.76651)
		(width 0.17145)
		(layer "F.Cu")
		(net "SSD3_PERST_N")
	)
	(segment
		(start 3.707384 -284.80004)
		(end 3.707384 -285.012384)
		(width 0.17145)
		(layer "F.Cu")
		(net "SSD3_PERST_N")
	)
	(via
		(at 9.564878 -285.76651)
		(size 0.7112)
		(drill 0.3556)
		(layers "F.Cu" "B.Cu")
		(net "SSD3_PERST_N")
	)
	(via
		(at 228.9048 -166.3954)
		(size 0.508)
		(drill 0.254)
		(layers "F.Cu" "B.Cu")
		(net "SSD3_PERST_N")
	)
	(via
		(at 10.568432 -285.76651)
		(size 0.508)
		(drill 0.254)
		(layers "F.Cu" "B.Cu")
		(net "SSD3_PERST_N")
	)
	(via
		(at 39.9288 -241.5032)
		(size 0.508)
		(drill 0.254)
		(layers "F.Cu" "B.Cu")
		(net "SSD3_PERST_N")
	)
	(segment
		(start 10.568432 -285.76651)
		(end 30.607 -265.727942)
		(width 0.17145)
		(layer "B.Cu")
		(net "SSD3_PERST_N")
	)
	(segment
		(start 39.243 -241.427)
		(end 39.8526 -241.427)
		(width 0.17145)
		(layer "B.Cu")
		(net "SSD3_PERST_N")
	)
	(segment
		(start 30.607 -265.727942)
		(end 30.607 -250.063)
		(width 0.17145)
		(layer "B.Cu")
		(net "SSD3_PERST_N")
	)
	(segment
		(start 30.607 -250.063)
		(end 39.243 -241.427)
		(width 0.17145)
		(layer "B.Cu")
		(net "SSD3_PERST_N")
	)
	(segment
		(start 39.8526 -241.427)
		(end 39.9288 -241.5032)
		(width 0.17145)
		(layer "B.Cu")
		(net "SSD3_PERST_N")
	)
	(segment
		(start 57.38876 -227.584)
		(end 98.806 -227.584)
		(width 0.1524)
		(layer "In5.Cu")
		(net "SSD3_PERST_N")
	)
	(segment
		(start 109.2962 -207.3148)
		(end 112.3188 -204.2922)
		(width 0.1524)
		(layer "In5.Cu")
		(net "SSD3_PERST_N")
	)
	(segment
		(start 112.3188 -204.2922)
		(end 137.37336 -204.2922)
		(width 0.1524)
		(layer "In5.Cu")
		(net "SSD3_PERST_N")
	)
	(segment
		(start 217.43162 -193.548)
		(end 225.044 -185.93562)
		(width 0.1524)
		(layer "In5.Cu")
		(net "SSD3_PERST_N")
	)
	(segment
		(start 137.37336 -204.2922)
		(end 144.28216 -211.201)
		(width 0.1524)
		(layer "In5.Cu")
		(net "SSD3_PERST_N")
	)
	(segment
		(start 39.9288 -241.5032)
		(end 40.4876 -242.062)
		(width 0.1524)
		(layer "In5.Cu")
		(net "SSD3_PERST_N")
	)
	(segment
		(start 225.044 -170.2562)
		(end 228.9048 -166.3954)
		(width 0.1524)
		(layer "In5.Cu")
		(net "SSD3_PERST_N")
	)
	(segment
		(start 109.2962 -217.0938)
		(end 109.2962 -207.3148)
		(width 0.1524)
		(layer "In5.Cu")
		(net "SSD3_PERST_N")
	)
	(segment
		(start 42.91076 -242.062)
		(end 57.38876 -227.584)
		(width 0.1524)
		(layer "In5.Cu")
		(net "SSD3_PERST_N")
	)
	(segment
		(start 209.55 -193.548)
		(end 217.43162 -193.548)
		(width 0.1524)
		(layer "In5.Cu")
		(net "SSD3_PERST_N")
	)
	(segment
		(start 225.044 -185.93562)
		(end 225.044 -170.2562)
		(width 0.1524)
		(layer "In5.Cu")
		(net "SSD3_PERST_N")
	)
	(segment
		(start 199.517 -211.201)
		(end 204.719682 -205.998318)
		(width 0.1524)
		(layer "In5.Cu")
		(net "SSD3_PERST_N")
	)
	(segment
		(start 98.806 -227.584)
		(end 109.2962 -217.0938)
		(width 0.1524)
		(layer "In5.Cu")
		(net "SSD3_PERST_N")
	)
	(segment
		(start 204.719682 -198.378318)
		(end 209.55 -193.548)
		(width 0.1524)
		(layer "In5.Cu")
		(net "SSD3_PERST_N")
	)
	(segment
		(start 204.719682 -205.998318)
		(end 204.719682 -198.378318)
		(width 0.1524)
		(layer "In5.Cu")
		(net "SSD3_PERST_N")
	)
	(segment
		(start 144.28216 -211.201)
		(end 199.517 -211.201)
		(width 0.1524)
		(layer "In5.Cu")
		(net "SSD3_PERST_N")
	)
	(segment
		(start 40.4876 -242.062)
		(end 42.91076 -242.062)
		(width 0.1524)
		(layer "In5.Cu")
		(net "SSD3_PERST_N")
	)
	(segment
		(start 228.585014 -172.574966)
		(end 226.974908 -172.574966)
		(width 0.17145)
		(layer "F.Cu")
		(net "SSD3_CLK0_OE_N")
	)
	(segment
		(start 113.760504 -164.430456)
		(end 124.34951 -153.84145)
		(width 0.17145)
		(layer "F.Cu")
		(net "SSD3_CLK0_OE_N")
	)
	(segment
		(start 124.34951 -153.84145)
		(end 229.514146 -153.84145)
		(width 0.17145)
		(layer "F.Cu")
		(net "SSD3_CLK0_OE_N")
	)
	(segment
		(start 231.885998 -156.213302)
		(end 231.885998 -169.273982)
		(width 0.17145)
		(layer "F.Cu")
		(net "SSD3_CLK0_OE_N")
	)
	(segment
		(start 110.236 -207.5815)
		(end 108.966 -207.5815)
		(width 0.17145)
		(layer "F.Cu")
		(net "SSD3_CLK0_OE_N")
	)
	(segment
		(start 108.9025 -207.645)
		(end 108.966 -207.5815)
		(width 0.17145)
		(layer "F.Cu")
		(net "SSD3_CLK0_OE_N")
	)
	(segment
		(start 107.8865 -207.645)
		(end 108.9025 -207.645)
		(width 0.17145)
		(layer "F.Cu")
		(net "SSD3_CLK0_OE_N")
	)
	(segment
		(start 112.7125 -207.5815)
		(end 113.760504 -206.533496)
		(width 0.17145)
		(layer "F.Cu")
		(net "SSD3_CLK0_OE_N")
	)
	(segment
		(start 113.760504 -206.533496)
		(end 113.760504 -164.430456)
		(width 0.17145)
		(layer "F.Cu")
		(net "SSD3_CLK0_OE_N")
	)
	(segment
		(start 229.514146 -153.84145)
		(end 231.885998 -156.213302)
		(width 0.17145)
		(layer "F.Cu")
		(net "SSD3_CLK0_OE_N")
	)
	(segment
		(start 110.236 -207.5815)
		(end 112.7125 -207.5815)
		(width 0.17145)
		(layer "F.Cu")
		(net "SSD3_CLK0_OE_N")
	)
	(segment
		(start 231.885998 -169.273982)
		(end 228.585014 -172.574966)
		(width 0.17145)
		(layer "F.Cu")
		(net "SSD3_CLK0_OE_N")
	)
	(via
		(at 110.236 -207.5815)
		(size 0.7112)
		(drill 0.3556)
		(layers "F.Cu" "B.Cu")
		(net "SSD3_CLK0_OE_N")
	)
	(segment
		(start 210.28025 -298.1325)
		(end 210.82 -298.67225)
		(width 0.17145)
		(layer "F.Cu")
		(net "SSD2_PWREN")
	)
	(segment
		(start 5.461 -331.724)
		(end 6.223 -330.962)
		(width 0.17145)
		(layer "F.Cu")
		(net "SSD2_PWREN")
	)
	(segment
		(start 207.391 -300.6725)
		(end 206.978504 -300.6725)
		(width 0.17145)
		(layer "F.Cu")
		(net "SSD2_PWREN")
	)
	(segment
		(start 208.534 -300.6725)
		(end 207.391 -300.6725)
		(width 0.17145)
		(layer "F.Cu")
		(net "SSD2_PWREN")
	)
	(segment
		(start 3.707384 -331.2668)
		(end 4.164584 -331.724)
		(width 0.17145)
		(layer "F.Cu")
		(net "SSD2_PWREN")
	)
	(segment
		(start 206.978504 -300.6725)
		(end 206.22895 -301.422054)
		(width 0.17145)
		(layer "F.Cu")
		(net "SSD2_PWREN")
	)
	(segment
		(start 205.170024 -301.94885)
		(end 206.22895 -301.94885)
		(width 0.17145)
		(layer "F.Cu")
		(net "SSD2_PWREN")
	)
	(segment
		(start 6.223 -330.962)
		(end 7.874 -330.962)
		(width 0.17145)
		(layer "F.Cu")
		(net "SSD2_PWREN")
	)
	(segment
		(start 4.164584 -331.724)
		(end 5.461 -331.724)
		(width 0.17145)
		(layer "F.Cu")
		(net "SSD2_PWREN")
	)
	(segment
		(start 2.249932 -330.742036)
		(end 3.249422 -330.742036)
		(width 0.17145)
		(layer "F.Cu")
		(net "SSD2_PWREN")
	)
	(segment
		(start 210.5025 -300.6725)
		(end 208.534 -300.6725)
		(width 0.17145)
		(layer "F.Cu")
		(net "SSD2_PWREN")
	)
	(segment
		(start 3.707384 -331.199998)
		(end 3.707384 -331.2668)
		(width 0.17145)
		(layer "F.Cu")
		(net "SSD2_PWREN")
	)
	(segment
		(start 8.620252 -331.708252)
		(end 8.620252 -332.994)
		(width 0.17145)
		(layer "F.Cu")
		(net "SSD2_PWREN")
	)
	(segment
		(start 210.82 -300.355)
		(end 210.5025 -300.6725)
		(width 0.17145)
		(layer "F.Cu")
		(net "SSD2_PWREN")
	)
	(segment
		(start 3.249422 -330.742036)
		(end 3.707384 -331.199998)
		(width 0.17145)
		(layer "F.Cu")
		(net "SSD2_PWREN")
	)
	(segment
		(start 206.22895 -301.422054)
		(end 206.22895 -301.94885)
		(width 0.17145)
		(layer "F.Cu")
		(net "SSD2_PWREN")
	)
	(segment
		(start 7.874 -330.962)
		(end 8.620252 -331.708252)
		(width 0.17145)
		(layer "F.Cu")
		(net "SSD2_PWREN")
	)
	(segment
		(start 210.82 -298.67225)
		(end 210.82 -300.355)
		(width 0.17145)
		(layer "F.Cu")
		(net "SSD2_PWREN")
	)
	(via
		(at 8.620252 -332.994)
		(size 0.508)
		(drill 0.254)
		(layers "F.Cu" "B.Cu")
		(net "SSD2_PWREN")
	)
	(via
		(at 205.170024 -301.94885)
		(size 0.5588)
		(drill 0.3048)
		(layers "F.Cu" "B.Cu")
		(net "SSD2_PWREN")
	)
	(segment
		(start 26.12898 -317.0174)
		(end 44.28998 -317.0174)
		(width 0.1524)
		(layer "In5.Cu")
		(net "SSD2_PWREN")
	)
	(segment
		(start 8.620252 -332.994)
		(end 9.255252 -333.629)
		(width 0.1524)
		(layer "In5.Cu")
		(net "SSD2_PWREN")
	)
	(segment
		(start 44.28998 -317.0174)
		(end 58.25998 -303.0474)
		(width 0.1524)
		(layer "In5.Cu")
		(net "SSD2_PWREN")
	)
	(segment
		(start 99.7712 -294.767)
		(end 100.6602 -293.878)
		(width 0.1524)
		(layer "In5.Cu")
		(net "SSD2_PWREN")
	)
	(segment
		(start 19.9644 -323.18198)
		(end 26.12898 -317.0174)
		(width 0.1524)
		(layer "In5.Cu")
		(net "SSD2_PWREN")
	)
	(segment
		(start 64.99098 -303.0474)
		(end 74.16038 -293.878)
		(width 0.1524)
		(layer "In5.Cu")
		(net "SSD2_PWREN")
	)
	(segment
		(start 100.6602 -293.878)
		(end 204.2795 -293.878)
		(width 0.1524)
		(layer "In5.Cu")
		(net "SSD2_PWREN")
	)
	(segment
		(start 19.9644 -325.17715)
		(end 19.9644 -323.18198)
		(width 0.1524)
		(layer "In5.Cu")
		(net "SSD2_PWREN")
	)
	(segment
		(start 97.9678 -293.878)
		(end 98.8568 -294.767)
		(width 0.1524)
		(layer "In5.Cu")
		(net "SSD2_PWREN")
	)
	(segment
		(start 205.678024 -295.276524)
		(end 205.678024 -301.44085)
		(width 0.1524)
		(layer "In5.Cu")
		(net "SSD2_PWREN")
	)
	(segment
		(start 58.25998 -303.0474)
		(end 64.99098 -303.0474)
		(width 0.1524)
		(layer "In5.Cu")
		(net "SSD2_PWREN")
	)
	(segment
		(start 205.678024 -301.44085)
		(end 205.170024 -301.94885)
		(width 0.1524)
		(layer "In5.Cu")
		(net "SSD2_PWREN")
	)
	(segment
		(start 98.8568 -294.767)
		(end 99.7712 -294.767)
		(width 0.1524)
		(layer "In5.Cu")
		(net "SSD2_PWREN")
	)
	(segment
		(start 204.2795 -293.878)
		(end 205.678024 -295.276524)
		(width 0.1524)
		(layer "In5.Cu")
		(net "SSD2_PWREN")
	)
	(segment
		(start 74.16038 -293.878)
		(end 97.9678 -293.878)
		(width 0.1524)
		(layer "In5.Cu")
		(net "SSD2_PWREN")
	)
	(segment
		(start 11.51255 -333.629)
		(end 19.9644 -325.17715)
		(width 0.1524)
		(layer "In5.Cu")
		(net "SSD2_PWREN")
	)
	(segment
		(start 9.255252 -333.629)
		(end 11.51255 -333.629)
		(width 0.1524)
		(layer "In5.Cu")
		(net "SSD2_PWREN")
	)
	(segment
		(start 24.844248 -270.869918)
		(end 23.842726 -271.87144)
		(width 0.17145)
		(layer "F.Cu")
		(net "SSD2_PERST_N")
	)
	(segment
		(start 227.389944 -269.78991)
		(end 228.55809 -269.78991)
		(width 0.17145)
		(layer "F.Cu")
		(net "SSD2_PERST_N")
	)
	(segment
		(start 228.55809 -269.78991)
		(end 228.9302 -269.4178)
		(width 0.17145)
		(layer "F.Cu")
		(net "SSD2_PERST_N")
	)
	(segment
		(start 34.925 -257.683)
		(end 34.036 -257.683)
		(width 0.17145)
		(layer "F.Cu")
		(net "SSD2_PERST_N")
	)
	(segment
		(start 34.036 -257.683)
		(end 27.6098 -264.1092)
		(width 0.17145)
		(layer "F.Cu")
		(net "SSD2_PERST_N")
	)
	(segment
		(start 227.389944 -268.990064)
		(end 228.502464 -268.990064)
		(width 0.17145)
		(layer "F.Cu")
		(net "SSD2_PERST_N")
	)
	(segment
		(start 23.842726 -271.87144)
		(end 17.04086 -271.87144)
		(width 0.17145)
		(layer "F.Cu")
		(net "SSD2_PERST_N")
	)
	(segment
		(start 27.6098 -268.104366)
		(end 24.844248 -270.869918)
		(width 0.17145)
		(layer "F.Cu")
		(net "SSD2_PERST_N")
	)
	(segment
		(start 27.6098 -264.1092)
		(end 27.6098 -268.104366)
		(width 0.17145)
		(layer "F.Cu")
		(net "SSD2_PERST_N")
	)
	(segment
		(start 228.502464 -268.990064)
		(end 228.9302 -269.4178)
		(width 0.17145)
		(layer "F.Cu")
		(net "SSD2_PERST_N")
	)
	(via
		(at 24.844248 -270.869918)
		(size 0.7112)
		(drill 0.3556)
		(layers "F.Cu" "B.Cu")
		(net "SSD2_PERST_N")
	)
	(via
		(at 17.04086 -271.87144)
		(size 0.508)
		(drill 0.254)
		(layers "F.Cu" "B.Cu")
		(net "SSD2_PERST_N")
	)
	(via
		(at 34.925 -257.683)
		(size 0.508)
		(drill 0.254)
		(layers "F.Cu" "B.Cu")
		(net "SSD2_PERST_N")
	)
	(via
		(at 228.9302 -269.4178)
		(size 0.508)
		(drill 0.254)
		(layers "F.Cu" "B.Cu")
		(net "SSD2_PERST_N")
	)
	(segment
		(start 17.04086 -271.87144)
		(end 11.1633 -277.749)
		(width 0.17145)
		(layer "B.Cu")
		(net "SSD2_PERST_N")
	)
	(segment
		(start 4.67106 -278.74214)
		(end 1.868932 -278.74214)
		(width 0.17145)
		(layer "B.Cu")
		(net "SSD2_PERST_N")
	)
	(segment
		(start 5.6642 -277.749)
		(end 4.67106 -278.74214)
		(width 0.17145)
		(layer "B.Cu")
		(net "SSD2_PERST_N")
	)
	(segment
		(start 11.1633 -277.749)
		(end 5.6642 -277.749)
		(width 0.17145)
		(layer "B.Cu")
		(net "SSD2_PERST_N")
	)
	(segment
		(start 44.4246 -242.8494)
		(end 47.1678 -242.8494)
		(width 0.1524)
		(layer "In5.Cu")
		(net "SSD2_PERST_N")
	)
	(segment
		(start 50.3936 -239.6236)
		(end 223.4184 -239.6236)
		(width 0.1524)
		(layer "In5.Cu")
		(net "SSD2_PERST_N")
	)
	(segment
		(start 39.878 -247.396)
		(end 44.4246 -242.8494)
		(width 0.1524)
		(layer "In5.Cu")
		(net "SSD2_PERST_N")
	)
	(segment
		(start 224.6376 -249.518678)
		(end 224.6376 -265.1252)
		(width 0.1524)
		(layer "In5.Cu")
		(net "SSD2_PERST_N")
	)
	(segment
		(start 226.7712 -247.385078)
		(end 224.6376 -249.518678)
		(width 0.1524)
		(layer "In5.Cu")
		(net "SSD2_PERST_N")
	)
	(segment
		(start 39.878 -252.73)
		(end 39.878 -247.396)
		(width 0.1524)
		(layer "In5.Cu")
		(net "SSD2_PERST_N")
	)
	(segment
		(start 47.1678 -242.8494)
		(end 50.3936 -239.6236)
		(width 0.1524)
		(layer "In5.Cu")
		(net "SSD2_PERST_N")
	)
	(segment
		(start 34.925 -257.683)
		(end 39.878 -252.73)
		(width 0.1524)
		(layer "In5.Cu")
		(net "SSD2_PERST_N")
	)
	(segment
		(start 224.6376 -265.1252)
		(end 228.9302 -269.4178)
		(width 0.1524)
		(layer "In5.Cu")
		(net "SSD2_PERST_N")
	)
	(segment
		(start 223.4184 -239.6236)
		(end 226.7712 -242.9764)
		(width 0.1524)
		(layer "In5.Cu")
		(net "SSD2_PERST_N")
	)
	(segment
		(start 226.7712 -242.9764)
		(end 226.7712 -247.385078)
		(width 0.1524)
		(layer "In5.Cu")
		(net "SSD2_PERST_N")
	)
	(segment
		(start 98.679 -291.2745)
		(end 98.679 -290.2585)
		(width 0.17145)
		(layer "F.Cu")
		(net "SSD2_CLK0_OE_N")
	)
	(segment
		(start 229.7684 -257.7338)
		(end 230.9368 -257.7338)
		(width 0.17145)
		(layer "F.Cu")
		(net "SSD2_CLK0_OE_N")
	)
	(segment
		(start 98.6155 -290.195)
		(end 98.6155 -288.925)
		(width 0.17145)
		(layer "F.Cu")
		(net "SSD2_CLK0_OE_N")
	)
	(segment
		(start 228.9556 -256.921)
		(end 229.7684 -257.7338)
		(width 0.17145)
		(layer "F.Cu")
		(net "SSD2_CLK0_OE_N")
	)
	(segment
		(start 228.585014 -275.575014)
		(end 226.974908 -275.575014)
		(width 0.17145)
		(layer "F.Cu")
		(net "SSD2_CLK0_OE_N")
	)
	(segment
		(start 124.587 -256.921)
		(end 228.9556 -256.921)
		(width 0.17145)
		(layer "F.Cu")
		(net "SSD2_CLK0_OE_N")
	)
	(segment
		(start 231.885998 -258.682998)
		(end 231.885998 -272.27403)
		(width 0.17145)
		(layer "F.Cu")
		(net "SSD2_CLK0_OE_N")
	)
	(segment
		(start 230.9368 -257.7338)
		(end 231.885998 -258.682998)
		(width 0.17145)
		(layer "F.Cu")
		(net "SSD2_CLK0_OE_N")
	)
	(segment
		(start 98.6155 -282.8925)
		(end 124.587 -256.921)
		(width 0.17145)
		(layer "F.Cu")
		(net "SSD2_CLK0_OE_N")
	)
	(segment
		(start 98.679 -290.2585)
		(end 98.6155 -290.195)
		(width 0.17145)
		(layer "F.Cu")
		(net "SSD2_CLK0_OE_N")
	)
	(segment
		(start 231.885998 -272.27403)
		(end 228.585014 -275.575014)
		(width 0.17145)
		(layer "F.Cu")
		(net "SSD2_CLK0_OE_N")
	)
	(segment
		(start 98.6155 -288.925)
		(end 98.6155 -282.8925)
		(width 0.17145)
		(layer "F.Cu")
		(net "SSD2_CLK0_OE_N")
	)
	(via
		(at 98.6155 -288.925)
		(size 0.7112)
		(drill 0.3556)
		(layers "F.Cu" "B.Cu")
		(net "SSD2_CLK0_OE_N")
	)
	(segment
		(start 49.05375 -9.8425)
		(end 48.387 -9.17575)
		(width 0.17145)
		(layer "F.Cu")
		(net "SSD14_PWREN")
	)
	(segment
		(start 51.943 -7.3025)
		(end 50.8 -7.3025)
		(width 0.17145)
		(layer "F.Cu")
		(net "SSD14_PWREN")
	)
	(segment
		(start 54.163976 -6.02615)
		(end 53.10505 -6.02615)
		(width 0.17145)
		(layer "F.Cu")
		(net "SSD14_PWREN")
	)
	(segment
		(start 48.7045 -7.3025)
		(end 50.8 -7.3025)
		(width 0.17145)
		(layer "F.Cu")
		(net "SSD14_PWREN")
	)
	(segment
		(start 52.355496 -7.3025)
		(end 51.943 -7.3025)
		(width 0.17145)
		(layer "F.Cu")
		(net "SSD14_PWREN")
	)
	(segment
		(start 53.10505 -6.552946)
		(end 52.355496 -7.3025)
		(width 0.17145)
		(layer "F.Cu")
		(net "SSD14_PWREN")
	)
	(segment
		(start 53.10505 -6.02615)
		(end 53.10505 -6.552946)
		(width 0.17145)
		(layer "F.Cu")
		(net "SSD14_PWREN")
	)
	(segment
		(start 48.387 -9.17575)
		(end 48.387 -7.62)
		(width 0.17145)
		(layer "F.Cu")
		(net "SSD14_PWREN")
	)
	(segment
		(start 48.387 -7.62)
		(end 48.7045 -7.3025)
		(width 0.17145)
		(layer "F.Cu")
		(net "SSD14_PWREN")
	)
	(via
		(at 54.163976 -6.02615)
		(size 0.5588)
		(drill 0.3048)
		(layers "F.Cu" "B.Cu")
		(net "SSD14_PWREN")
	)
	(segment
		(start 40.9194 -4.699)
		(end 36.4744 -9.144)
		(width 0.17145)
		(layer "B.Cu")
		(net "SSD14_PWREN")
	)
	(segment
		(start 28.2067 -12.0015)
		(end 22.8981 -12.0015)
		(width 0.17145)
		(layer "B.Cu")
		(net "SSD14_PWREN")
	)
	(segment
		(start 6.26745 -151.08555)
		(end 4.610862 -152.742138)
		(width 0.17145)
		(layer "B.Cu")
		(net "SSD14_PWREN")
	)
	(segment
		(start 36.4744 -10.9982)
		(end 34.7726 -12.7)
		(width 0.17145)
		(layer "B.Cu")
		(net "SSD14_PWREN")
	)
	(segment
		(start 34.7726 -12.7)
		(end 28.9052 -12.7)
		(width 0.17145)
		(layer "B.Cu")
		(net "SSD14_PWREN")
	)
	(segment
		(start 52.836826 -4.699)
		(end 40.9194 -4.699)
		(width 0.17145)
		(layer "B.Cu")
		(net "SSD14_PWREN")
	)
	(segment
		(start 15.80515 -72.338692)
		(end 15.80515 -82.084672)
		(width 0.17145)
		(layer "B.Cu")
		(net "SSD14_PWREN")
	)
	(segment
		(start 22.225 -12.6746)
		(end 16.9672 -12.6746)
		(width 0.17145)
		(layer "B.Cu")
		(net "SSD14_PWREN")
	)
	(segment
		(start 4.610862 -152.742138)
		(end 1.868932 -152.742138)
		(width 0.17145)
		(layer "B.Cu")
		(net "SSD14_PWREN")
	)
	(segment
		(start 6.26745 -91.622372)
		(end 6.26745 -151.08555)
		(width 0.17145)
		(layer "B.Cu")
		(net "SSD14_PWREN")
	)
	(segment
		(start 54.163976 -6.02615)
		(end 52.836826 -4.699)
		(width 0.17145)
		(layer "B.Cu")
		(net "SSD14_PWREN")
	)
	(segment
		(start 23.452074 -59.367674)
		(end 23.452074 -64.691768)
		(width 0.17145)
		(layer "B.Cu")
		(net "SSD14_PWREN")
	)
	(segment
		(start 15.80515 -82.084672)
		(end 6.26745 -91.622372)
		(width 0.17145)
		(layer "B.Cu")
		(net "SSD14_PWREN")
	)
	(segment
		(start 14.5288 -50.4444)
		(end 23.452074 -59.367674)
		(width 0.17145)
		(layer "B.Cu")
		(net "SSD14_PWREN")
	)
	(segment
		(start 23.452074 -64.691768)
		(end 15.80515 -72.338692)
		(width 0.17145)
		(layer "B.Cu")
		(net "SSD14_PWREN")
	)
	(segment
		(start 14.5288 -15.113)
		(end 14.5288 -50.4444)
		(width 0.17145)
		(layer "B.Cu")
		(net "SSD14_PWREN")
	)
	(segment
		(start 28.9052 -12.7)
		(end 28.2067 -12.0015)
		(width 0.17145)
		(layer "B.Cu")
		(net "SSD14_PWREN")
	)
	(segment
		(start 36.4744 -9.144)
		(end 36.4744 -10.9982)
		(width 0.17145)
		(layer "B.Cu")
		(net "SSD14_PWREN")
	)
	(segment
		(start 22.8981 -12.0015)
		(end 22.225 -12.6746)
		(width 0.17145)
		(layer "B.Cu")
		(net "SSD14_PWREN")
	)
	(segment
		(start 16.9672 -12.6746)
		(end 14.5288 -15.113)
		(width 0.17145)
		(layer "B.Cu")
		(net "SSD14_PWREN")
	)
	(segment
		(start 29.103066 -34.99485)
		(end 29.103066 -35.641788)
		(width 0.17145)
		(layer "F.Cu")
		(net "SSD14_PERST_N")
	)
	(segment
		(start 16.52524 -30.63621)
		(end 15.4559 -31.70555)
		(width 0.17145)
		(layer "F.Cu")
		(net "SSD14_PERST_N")
	)
	(segment
		(start 17.766284 -30.63621)
		(end 18.139918 -31.009844)
		(width 0.17145)
		(layer "F.Cu")
		(net "SSD14_PERST_N")
	)
	(segment
		(start 30.183328 -41.04005)
		(end 30.183328 -38.749986)
		(width 0.17145)
		(layer "F.Cu")
		(net "SSD14_PERST_N")
	)
	(segment
		(start 29.103066 -35.641788)
		(end 30.183328 -36.72205)
		(width 0.17145)
		(layer "F.Cu")
		(net "SSD14_PERST_N")
	)
	(segment
		(start 16.961104 -43.3578)
		(end 27.865578 -43.3578)
		(width 0.17145)
		(layer "F.Cu")
		(net "SSD14_PERST_N")
	)
	(segment
		(start 30.183328 -36.72205)
		(end 30.183328 -38.749986)
		(width 0.17145)
		(layer "F.Cu")
		(net "SSD14_PERST_N")
	)
	(segment
		(start 18.139918 -31.009844)
		(end 19.61007 -31.009844)
		(width 0.17145)
		(layer "F.Cu")
		(net "SSD14_PERST_N")
	)
	(segment
		(start 18.192496 -30.209998)
		(end 17.766284 -30.63621)
		(width 0.17145)
		(layer "F.Cu")
		(net "SSD14_PERST_N")
	)
	(segment
		(start 15.4559 -31.70555)
		(end 15.4559 -41.852596)
		(width 0.17145)
		(layer "F.Cu")
		(net "SSD14_PERST_N")
	)
	(segment
		(start 27.865578 -43.3578)
		(end 30.183328 -41.04005)
		(width 0.17145)
		(layer "F.Cu")
		(net "SSD14_PERST_N")
	)
	(segment
		(start 19.61007 -30.209998)
		(end 18.192496 -30.209998)
		(width 0.17145)
		(layer "F.Cu")
		(net "SSD14_PERST_N")
	)
	(segment
		(start 17.766284 -30.63621)
		(end 16.52524 -30.63621)
		(width 0.17145)
		(layer "F.Cu")
		(net "SSD14_PERST_N")
	)
	(segment
		(start 15.4559 -41.852596)
		(end 16.961104 -43.3578)
		(width 0.17145)
		(layer "F.Cu")
		(net "SSD14_PERST_N")
	)
	(via
		(at 29.103066 -34.99485)
		(size 0.508)
		(drill 0.254)
		(layers "F.Cu" "B.Cu")
		(net "SSD14_PERST_N")
	)
	(via
		(at 30.183328 -38.749986)
		(size 0.7112)
		(drill 0.3556)
		(layers "F.Cu" "B.Cu")
		(net "SSD14_PERST_N")
	)
	(segment
		(start 24.009604 -55.730902)
		(end 24.009604 -64.915796)
		(width 0.17145)
		(layer "B.Cu")
		(net "SSD14_PERST_N")
	)
	(segment
		(start 24.461724 -55.278782)
		(end 24.009604 -55.730902)
		(width 0.17145)
		(layer "B.Cu")
		(net "SSD14_PERST_N")
	)
	(segment
		(start 27.333194 -53.71338)
		(end 25.767792 -55.278782)
		(width 0.17145)
		(layer "B.Cu")
		(net "SSD14_PERST_N")
	)
	(segment
		(start 3.741674 -185.208926)
		(end 3.408426 -185.542174)
		(width 0.17145)
		(layer "B.Cu")
		(net "SSD14_PERST_N")
	)
	(segment
		(start 7.6454 -91.139518)
		(end 7.6454 -185.9026)
		(width 0.17145)
		(layer "B.Cu")
		(net "SSD14_PERST_N")
	)
	(segment
		(start 25.767792 -55.278782)
		(end 24.461724 -55.278782)
		(width 0.17145)
		(layer "B.Cu")
		(net "SSD14_PERST_N")
	)
	(segment
		(start 29.103066 -34.99485)
		(end 29.103066 -49.839626)
		(width 0.17145)
		(layer "B.Cu")
		(net "SSD14_PERST_N")
	)
	(segment
		(start 27.333194 -51.609498)
		(end 27.333194 -53.71338)
		(width 0.17145)
		(layer "B.Cu")
		(net "SSD14_PERST_N")
	)
	(segment
		(start 4.529074 -185.208926)
		(end 3.741674 -185.208926)
		(width 0.17145)
		(layer "B.Cu")
		(net "SSD14_PERST_N")
	)
	(segment
		(start 6.9596 -186.5884)
		(end 5.908548 -186.5884)
		(width 0.17145)
		(layer "B.Cu")
		(net "SSD14_PERST_N")
	)
	(segment
		(start 16.3576 -82.427318)
		(end 7.6454 -91.139518)
		(width 0.17145)
		(layer "B.Cu")
		(net "SSD14_PERST_N")
	)
	(segment
		(start 7.6454 -185.9026)
		(end 6.9596 -186.5884)
		(width 0.17145)
		(layer "B.Cu")
		(net "SSD14_PERST_N")
	)
	(segment
		(start 5.908548 -186.5884)
		(end 4.529074 -185.208926)
		(width 0.17145)
		(layer "B.Cu")
		(net "SSD14_PERST_N")
	)
	(segment
		(start 16.3576 -72.5678)
		(end 16.3576 -82.427318)
		(width 0.17145)
		(layer "B.Cu")
		(net "SSD14_PERST_N")
	)
	(segment
		(start 3.408426 -185.542174)
		(end 1.868932 -185.542174)
		(width 0.17145)
		(layer "B.Cu")
		(net "SSD14_PERST_N")
	)
	(segment
		(start 24.009604 -64.915796)
		(end 16.3576 -72.5678)
		(width 0.17145)
		(layer "B.Cu")
		(net "SSD14_PERST_N")
	)
	(segment
		(start 29.103066 -49.839626)
		(end 27.333194 -51.609498)
		(width 0.17145)
		(layer "B.Cu")
		(net "SSD14_PERST_N")
	)
	(segment
		(start 98.6155 -86.614)
		(end 98.6155 -85.344)
		(width 0.17145)
		(layer "F.Cu")
		(net "SSD14_CLK0_OE_N")
	)
	(segment
		(start 98.6155 -68.0085)
		(end 98.6155 -85.344)
		(width 0.17145)
		(layer "F.Cu")
		(net "SSD14_CLK0_OE_N")
	)
	(segment
		(start 98.679 -87.6935)
		(end 98.679 -86.6775)
		(width 0.17145)
		(layer "F.Cu")
		(net "SSD14_CLK0_OE_N")
	)
	(segment
		(start 31.1023 -40.902382)
		(end 31.1023 -36.271454)
		(width 0.17145)
		(layer "F.Cu")
		(net "SSD14_CLK0_OE_N")
	)
	(segment
		(start 60.955682 -30.348682)
		(end 98.6155 -68.0085)
		(width 0.17145)
		(layer "F.Cu")
		(net "SSD14_CLK0_OE_N")
	)
	(segment
		(start 20.025106 -24.424894)
		(end 18.415 -24.424894)
		(width 0.17145)
		(layer "F.Cu")
		(net "SSD14_CLK0_OE_N")
	)
	(segment
		(start 98.679 -86.6775)
		(end 98.6155 -86.614)
		(width 0.17145)
		(layer "F.Cu")
		(net "SSD14_CLK0_OE_N")
	)
	(segment
		(start 30.069282 -35.238436)
		(end 30.069282 -31.336488)
		(width 0.17145)
		(layer "F.Cu")
		(net "SSD14_CLK0_OE_N")
	)
	(segment
		(start 31.1023 -36.271454)
		(end 30.069282 -35.238436)
		(width 0.17145)
		(layer "F.Cu")
		(net "SSD14_CLK0_OE_N")
	)
	(segment
		(start 30.069282 -31.336488)
		(end 31.057088 -30.348682)
		(width 0.17145)
		(layer "F.Cu")
		(net "SSD14_CLK0_OE_N")
	)
	(segment
		(start 14.90345 -27.936444)
		(end 14.90345 -42.08145)
		(width 0.17145)
		(layer "F.Cu")
		(net "SSD14_CLK0_OE_N")
	)
	(segment
		(start 16.73225 -43.91025)
		(end 28.094432 -43.91025)
		(width 0.17145)
		(layer "F.Cu")
		(net "SSD14_CLK0_OE_N")
	)
	(segment
		(start 18.415 -24.424894)
		(end 14.90345 -27.936444)
		(width 0.17145)
		(layer "F.Cu")
		(net "SSD14_CLK0_OE_N")
	)
	(segment
		(start 31.057088 -30.348682)
		(end 60.955682 -30.348682)
		(width 0.17145)
		(layer "F.Cu")
		(net "SSD14_CLK0_OE_N")
	)
	(segment
		(start 14.90345 -42.08145)
		(end 16.73225 -43.91025)
		(width 0.17145)
		(layer "F.Cu")
		(net "SSD14_CLK0_OE_N")
	)
	(segment
		(start 28.094432 -43.91025)
		(end 31.1023 -40.902382)
		(width 0.17145)
		(layer "F.Cu")
		(net "SSD14_CLK0_OE_N")
	)
	(via
		(at 98.6155 -85.344)
		(size 0.7112)
		(drill 0.3556)
		(layers "F.Cu" "B.Cu")
		(net "SSD14_CLK0_OE_N")
	)
	(segment
		(start 35.46475 -102.52075)
		(end 35.78225 -102.20325)
		(width 0.17145)
		(layer "F.Cu")
		(net "SSD13_PWREN")
	)
	(segment
		(start 35.46475 -104.0765)
		(end 35.46475 -102.52075)
		(width 0.17145)
		(layer "F.Cu")
		(net "SSD13_PWREN")
	)
	(segment
		(start 11.322304 -166.477696)
		(end 11.322304 -183.98744)
		(width 0.17145)
		(layer "F.Cu")
		(net "SSD13_PWREN")
	)
	(segment
		(start 40.1828 -100.9269)
		(end 40.853106 -101.597206)
		(width 0.17145)
		(layer "F.Cu")
		(net "SSD13_PWREN")
	)
	(segment
		(start 40.1828 -101.2698)
		(end 39.24935 -102.20325)
		(width 0.17145)
		(layer "F.Cu")
		(net "SSD13_PWREN")
	)
	(segment
		(start 35.78225 -102.20325)
		(end 37.87775 -102.20325)
		(width 0.17145)
		(layer "F.Cu")
		(net "SSD13_PWREN")
	)
	(segment
		(start 3.334004 -198.341996)
		(end 2.249932 -198.341996)
		(width 0.17145)
		(layer "F.Cu")
		(net "SSD13_PWREN")
	)
	(segment
		(start 36.25215 -104.8639)
		(end 35.46475 -104.0765)
		(width 0.17145)
		(layer "F.Cu")
		(net "SSD13_PWREN")
	)
	(segment
		(start 11.322304 -193.344292)
		(end 6.546596 -198.12)
		(width 0.17145)
		(layer "F.Cu")
		(net "SSD13_PWREN")
	)
	(segment
		(start 40.1828 -100.9269)
		(end 40.1828 -101.2698)
		(width 0.17145)
		(layer "F.Cu")
		(net "SSD13_PWREN")
	)
	(segment
		(start 11.811 -165.989)
		(end 11.322304 -166.477696)
		(width 0.17145)
		(layer "F.Cu")
		(net "SSD13_PWREN")
	)
	(segment
		(start 36.70935 -104.8639)
		(end 36.25215 -104.8639)
		(width 0.17145)
		(layer "F.Cu")
		(net "SSD13_PWREN")
	)
	(segment
		(start 6.546596 -198.12)
		(end 3.556 -198.12)
		(width 0.17145)
		(layer "F.Cu")
		(net "SSD13_PWREN")
	)
	(segment
		(start 39.24935 -102.20325)
		(end 39.02075 -102.20325)
		(width 0.17145)
		(layer "F.Cu")
		(net "SSD13_PWREN")
	)
	(segment
		(start 3.556 -198.12)
		(end 3.334004 -198.341996)
		(width 0.17145)
		(layer "F.Cu")
		(net "SSD13_PWREN")
	)
	(segment
		(start 11.322304 -183.98744)
		(end 11.322304 -193.344292)
		(width 0.17145)
		(layer "F.Cu")
		(net "SSD13_PWREN")
	)
	(segment
		(start 40.853106 -101.597206)
		(end 40.853106 -103.037894)
		(width 0.17145)
		(layer "F.Cu")
		(net "SSD13_PWREN")
	)
	(segment
		(start 40.853106 -103.037894)
		(end 40.259 -103.632)
		(width 0.17145)
		(layer "F.Cu")
		(net "SSD13_PWREN")
	)
	(segment
		(start 39.02075 -102.20325)
		(end 37.87775 -102.20325)
		(width 0.17145)
		(layer "F.Cu")
		(net "SSD13_PWREN")
	)
	(via
		(at 11.322304 -183.98744)
		(size 0.7112)
		(drill 0.3556)
		(layers "F.Cu" "B.Cu")
		(net "SSD13_PWREN")
	)
	(via
		(at 40.259 -103.632)
		(size 0.508)
		(drill 0.254)
		(layers "F.Cu" "B.Cu")
		(net "SSD13_PWREN")
	)
	(via
		(at 11.811 -165.989)
		(size 0.508)
		(drill 0.254)
		(layers "F.Cu" "B.Cu")
		(net "SSD13_PWREN")
	)
	(segment
		(start 40.259 -103.632)
		(end 37.846 -103.632)
		(width 0.1524)
		(layer "In5.Cu")
		(net "SSD13_PWREN")
	)
	(segment
		(start 17.526 -116.84)
		(end 17.526 -119.1006)
		(width 0.1524)
		(layer "In5.Cu")
		(net "SSD13_PWREN")
	)
	(segment
		(start 22.987 -103.124)
		(end 22.987 -111.379)
		(width 0.1524)
		(layer "In5.Cu")
		(net "SSD13_PWREN")
	)
	(segment
		(start 18.961354 -155.247086)
		(end 18.961354 -159.118046)
		(width 0.1524)
		(layer "In5.Cu")
		(net "SSD13_PWREN")
	)
	(segment
		(start 23.876 -102.235)
		(end 22.987 -103.124)
		(width 0.1524)
		(layer "In5.Cu")
		(net "SSD13_PWREN")
	)
	(segment
		(start 22.987 -111.379)
		(end 17.526 -116.84)
		(width 0.1524)
		(layer "In5.Cu")
		(net "SSD13_PWREN")
	)
	(segment
		(start 37.846 -103.632)
		(end 36.449 -102.235)
		(width 0.1524)
		(layer "In5.Cu")
		(net "SSD13_PWREN")
	)
	(segment
		(start 36.449 -102.235)
		(end 23.876 -102.235)
		(width 0.1524)
		(layer "In5.Cu")
		(net "SSD13_PWREN")
	)
	(segment
		(start 22.4536 -124.0282)
		(end 22.4536 -151.75484)
		(width 0.1524)
		(layer "In5.Cu")
		(net "SSD13_PWREN")
	)
	(segment
		(start 22.4536 -151.75484)
		(end 18.961354 -155.247086)
		(width 0.1524)
		(layer "In5.Cu")
		(net "SSD13_PWREN")
	)
	(segment
		(start 18.961354 -159.118046)
		(end 12.0904 -165.989)
		(width 0.1524)
		(layer "In5.Cu")
		(net "SSD13_PWREN")
	)
	(segment
		(start 12.0904 -165.989)
		(end 11.811 -165.989)
		(width 0.1524)
		(layer "In5.Cu")
		(net "SSD13_PWREN")
	)
	(segment
		(start 17.526 -119.1006)
		(end 22.4536 -124.0282)
		(width 0.1524)
		(layer "In5.Cu")
		(net "SSD13_PWREN")
	)
	(segment
		(start 19.61007 -134.009892)
		(end 18.830036 -134.009892)
		(width 0.17145)
		(layer "F.Cu")
		(net "SSD13_PERST_N")
	)
	(segment
		(start 3.98272 -190.45428)
		(end 7.03072 -190.45428)
		(width 0.17145)
		(layer "F.Cu")
		(net "SSD13_PERST_N")
	)
	(segment
		(start 7.03072 -190.45428)
		(end 10.642854 -186.842146)
		(width 0.17145)
		(layer "F.Cu")
		(net "SSD13_PERST_N")
	)
	(segment
		(start 19.61007 -133.210046)
		(end 18.03781 -133.210046)
		(width 0.17145)
		(layer "F.Cu")
		(net "SSD13_PERST_N")
	)
	(segment
		(start 10.642854 -166.329106)
		(end 10.642854 -182.10784)
		(width 0.17145)
		(layer "F.Cu")
		(net "SSD13_PERST_N")
	)
	(segment
		(start 3.294888 -191.142112)
		(end 3.98272 -190.45428)
		(width 0.17145)
		(layer "F.Cu")
		(net "SSD13_PERST_N")
	)
	(segment
		(start 18.03781 -133.210046)
		(end 18.034 -133.213856)
		(width 0.17145)
		(layer "F.Cu")
		(net "SSD13_PERST_N")
	)
	(segment
		(start 18.830036 -134.009892)
		(end 18.034 -133.213856)
		(width 0.17145)
		(layer "F.Cu")
		(net "SSD13_PERST_N")
	)
	(segment
		(start 2.249932 -191.142112)
		(end 3.294888 -191.142112)
		(width 0.17145)
		(layer "F.Cu")
		(net "SSD13_PERST_N")
	)
	(segment
		(start 11.99896 -164.973)
		(end 10.642854 -166.329106)
		(width 0.17145)
		(layer "F.Cu")
		(net "SSD13_PERST_N")
	)
	(segment
		(start 12.192 -164.973)
		(end 11.99896 -164.973)
		(width 0.17145)
		(layer "F.Cu")
		(net "SSD13_PERST_N")
	)
	(segment
		(start 10.642854 -186.842146)
		(end 10.642854 -182.10784)
		(width 0.17145)
		(layer "F.Cu")
		(net "SSD13_PERST_N")
	)
	(via
		(at 18.034 -133.213856)
		(size 0.508)
		(drill 0.254)
		(layers "F.Cu" "B.Cu")
		(net "SSD13_PERST_N")
	)
	(via
		(at 10.642854 -182.10784)
		(size 0.7112)
		(drill 0.3556)
		(layers "F.Cu" "B.Cu")
		(net "SSD13_PERST_N")
	)
	(via
		(at 12.192 -164.973)
		(size 0.508)
		(drill 0.254)
		(layers "F.Cu" "B.Cu")
		(net "SSD13_PERST_N")
	)
	(segment
		(start 19.5326 -145.4658)
		(end 16.4338 -148.5646)
		(width 0.1524)
		(layer "In5.Cu")
		(net "SSD13_PERST_N")
	)
	(segment
		(start 16.4338 -148.5646)
		(end 16.4338 -160.89122)
		(width 0.1524)
		(layer "In5.Cu")
		(net "SSD13_PERST_N")
	)
	(segment
		(start 19.5326 -134.712456)
		(end 19.5326 -145.4658)
		(width 0.1524)
		(layer "In5.Cu")
		(net "SSD13_PERST_N")
	)
	(segment
		(start 12.35202 -164.973)
		(end 12.192 -164.973)
		(width 0.1524)
		(layer "In5.Cu")
		(net "SSD13_PERST_N")
	)
	(segment
		(start 18.034 -133.213856)
		(end 19.5326 -134.712456)
		(width 0.1524)
		(layer "In5.Cu")
		(net "SSD13_PERST_N")
	)
	(segment
		(start 16.4338 -160.89122)
		(end 12.35202 -164.973)
		(width 0.1524)
		(layer "In5.Cu")
		(net "SSD13_PERST_N")
	)
	(segment
		(start 15.875 -144.252696)
		(end 17.754854 -146.13255)
		(width 0.17145)
		(layer "F.Cu")
		(net "SSD13_CLK0_OE_N")
	)
	(segment
		(start 20.025106 -127.424942)
		(end 18.415 -127.424942)
		(width 0.17145)
		(layer "F.Cu")
		(net "SSD13_CLK0_OE_N")
	)
	(segment
		(start 18.415 -127.424942)
		(end 15.875 -129.964942)
		(width 0.17145)
		(layer "F.Cu")
		(net "SSD13_CLK0_OE_N")
	)
	(segment
		(start 88.2015 -118.314724)
		(end 88.2015 -117.856)
		(width 0.17145)
		(layer "F.Cu")
		(net "SSD13_CLK0_OE_N")
	)
	(segment
		(start 88.2015 -116.586)
		(end 88.2015 -117.856)
		(width 0.17145)
		(layer "F.Cu")
		(net "SSD13_CLK0_OE_N")
	)
	(segment
		(start 29.662628 -134.747)
		(end 39.351966 -125.057662)
		(width 0.17145)
		(layer "F.Cu")
		(net "SSD13_CLK0_OE_N")
	)
	(segment
		(start 88.138 -115.5065)
		(end 88.138 -116.5225)
		(width 0.17145)
		(layer "F.Cu")
		(net "SSD13_CLK0_OE_N")
	)
	(segment
		(start 17.754854 -146.13255)
		(end 28.219146 -146.13255)
		(width 0.17145)
		(layer "F.Cu")
		(net "SSD13_CLK0_OE_N")
	)
	(segment
		(start 15.875 -129.964942)
		(end 15.875 -144.252696)
		(width 0.17145)
		(layer "F.Cu")
		(net "SSD13_CLK0_OE_N")
	)
	(segment
		(start 81.458562 -125.057662)
		(end 88.2015 -118.314724)
		(width 0.17145)
		(layer "F.Cu")
		(net "SSD13_CLK0_OE_N")
	)
	(segment
		(start 88.138 -116.5225)
		(end 88.2015 -116.586)
		(width 0.17145)
		(layer "F.Cu")
		(net "SSD13_CLK0_OE_N")
	)
	(segment
		(start 29.662628 -144.689068)
		(end 29.662628 -134.747)
		(width 0.17145)
		(layer "F.Cu")
		(net "SSD13_CLK0_OE_N")
	)
	(segment
		(start 39.351966 -125.057662)
		(end 81.458562 -125.057662)
		(width 0.17145)
		(layer "F.Cu")
		(net "SSD13_CLK0_OE_N")
	)
	(segment
		(start 28.219146 -146.13255)
		(end 29.662628 -144.689068)
		(width 0.17145)
		(layer "F.Cu")
		(net "SSD13_CLK0_OE_N")
	)
	(via
		(at 88.2015 -117.856)
		(size 0.7112)
		(drill 0.3556)
		(layers "F.Cu" "B.Cu")
		(net "SSD13_CLK0_OE_N")
	)
	(segment
		(start 37.973 -205.2955)
		(end 39.116 -205.2955)
		(width 0.17145)
		(layer "F.Cu")
		(net "SSD12_PWREN")
	)
	(segment
		(start 37.7571 -205.0796)
		(end 36.5252 -205.0796)
		(width 0.17145)
		(layer "F.Cu")
		(net "SSD12_PWREN")
	)
	(segment
		(start 39.624 -205.2955)
		(end 39.116 -205.2955)
		(width 0.17145)
		(layer "F.Cu")
		(net "SSD12_PWREN")
	)
	(segment
		(start 36.0934 -205.0796)
		(end 36.5252 -205.0796)
		(width 0.17145)
		(layer "F.Cu")
		(net "SSD12_PWREN")
	)
	(segment
		(start 37.973 -205.2955)
		(end 37.7571 -205.0796)
		(width 0.17145)
		(layer "F.Cu")
		(net "SSD12_PWREN")
	)
	(segment
		(start 35.56 -205.613)
		(end 36.0934 -205.0796)
		(width 0.17145)
		(layer "F.Cu")
		(net "SSD12_PWREN")
	)
	(segment
		(start 35.56 -207.16875)
		(end 35.56 -205.613)
		(width 0.17145)
		(layer "F.Cu")
		(net "SSD12_PWREN")
	)
	(segment
		(start 40.259 -205.1685)
		(end 39.751 -205.1685)
		(width 0.17145)
		(layer "F.Cu")
		(net "SSD12_PWREN")
	)
	(segment
		(start 36.70935 -207.8609)
		(end 36.25215 -207.8609)
		(width 0.17145)
		(layer "F.Cu")
		(net "SSD12_PWREN")
	)
	(segment
		(start 36.25215 -207.8609)
		(end 35.56 -207.16875)
		(width 0.17145)
		(layer "F.Cu")
		(net "SSD12_PWREN")
	)
	(segment
		(start 39.751 -205.1685)
		(end 39.624 -205.2955)
		(width 0.17145)
		(layer "F.Cu")
		(net "SSD12_PWREN")
	)
	(via
		(at 36.5252 -205.0796)
		(size 0.508)
		(drill 0.254)
		(layers "F.Cu" "B.Cu")
		(net "SSD12_PWREN")
	)
	(via
		(at 20.3454 -204.597)
		(size 0.7112)
		(drill 0.3556)
		(layers "F.Cu" "B.Cu")
		(net "SSD12_PWREN")
	)
	(segment
		(start 17.145 -235.966)
		(end 18.542 -235.966)
		(width 0.17145)
		(layer "B.Cu")
		(net "SSD12_PWREN")
	)
	(segment
		(start 18.796 -235.712)
		(end 18.796 -233.553)
		(width 0.17145)
		(layer "B.Cu")
		(net "SSD12_PWREN")
	)
	(segment
		(start 18.542 -204.597)
		(end 20.3454 -204.597)
		(width 0.17145)
		(layer "B.Cu")
		(net "SSD12_PWREN")
	)
	(segment
		(start 13.4112 -228.1682)
		(end 13.4112 -209.7278)
		(width 0.17145)
		(layer "B.Cu")
		(net "SSD12_PWREN")
	)
	(segment
		(start 5.514594 -286.742124)
		(end 6.457442 -285.799276)
		(width 0.17145)
		(layer "B.Cu")
		(net "SSD12_PWREN")
	)
	(segment
		(start 14.90345 -238.20755)
		(end 17.145 -235.966)
		(width 0.17145)
		(layer "B.Cu")
		(net "SSD12_PWREN")
	)
	(segment
		(start 13.4112 -209.7278)
		(end 18.542 -204.597)
		(width 0.17145)
		(layer "B.Cu")
		(net "SSD12_PWREN")
	)
	(segment
		(start 19.177 -267.462)
		(end 20.066 -266.573)
		(width 0.17145)
		(layer "B.Cu")
		(net "SSD12_PWREN")
	)
	(segment
		(start 36.5252 -205.0796)
		(end 36.0426 -204.597)
		(width 0.17145)
		(layer "B.Cu")
		(net "SSD12_PWREN")
	)
	(segment
		(start 18.796 -233.553)
		(end 13.4112 -228.1682)
		(width 0.17145)
		(layer "B.Cu")
		(net "SSD12_PWREN")
	)
	(segment
		(start 16.698976 -257.009138)
		(end 16.109442 -257.009138)
		(width 0.17145)
		(layer "B.Cu")
		(net "SSD12_PWREN")
	)
	(segment
		(start 20.066 -266.573)
		(end 20.066 -260.376162)
		(width 0.17145)
		(layer "B.Cu")
		(net "SSD12_PWREN")
	)
	(segment
		(start 8.172704 -285.799276)
		(end 19.177 -274.79498)
		(width 0.17145)
		(layer "B.Cu")
		(net "SSD12_PWREN")
	)
	(segment
		(start 19.177 -274.79498)
		(end 19.177 -267.462)
		(width 0.17145)
		(layer "B.Cu")
		(net "SSD12_PWREN")
	)
	(segment
		(start 36.0426 -204.597)
		(end 20.3454 -204.597)
		(width 0.17145)
		(layer "B.Cu")
		(net "SSD12_PWREN")
	)
	(segment
		(start 16.109442 -257.009138)
		(end 14.90345 -255.803146)
		(width 0.17145)
		(layer "B.Cu")
		(net "SSD12_PWREN")
	)
	(segment
		(start 1.868932 -286.742124)
		(end 5.514594 -286.742124)
		(width 0.17145)
		(layer "B.Cu")
		(net "SSD12_PWREN")
	)
	(segment
		(start 18.542 -235.966)
		(end 18.796 -235.712)
		(width 0.17145)
		(layer "B.Cu")
		(net "SSD12_PWREN")
	)
	(segment
		(start 14.90345 -255.803146)
		(end 14.90345 -238.20755)
		(width 0.17145)
		(layer "B.Cu")
		(net "SSD12_PWREN")
	)
	(segment
		(start 20.066 -260.376162)
		(end 16.698976 -257.009138)
		(width 0.17145)
		(layer "B.Cu")
		(net "SSD12_PWREN")
	)
	(segment
		(start 6.457442 -285.799276)
		(end 8.172704 -285.799276)
		(width 0.17145)
		(layer "B.Cu")
		(net "SSD12_PWREN")
	)
	(segment
		(start 10.62736 -281.792172)
		(end 10.62736 -283.350208)
		(width 0.17145)
		(layer "F.Cu")
		(net "SSD12_PERST_N")
	)
	(segment
		(start 18.034 -235.8644)
		(end 18.034 -235.077)
		(width 0.17145)
		(layer "F.Cu")
		(net "SSD12_PERST_N")
	)
	(segment
		(start 18.379694 -236.210094)
		(end 18.034 -235.8644)
		(width 0.17145)
		(layer "F.Cu")
		(net "SSD12_PERST_N")
	)
	(segment
		(start 10.62736 -284.339792)
		(end 9.978644 -284.988508)
		(width 0.17145)
		(layer "F.Cu")
		(net "SSD12_PERST_N")
	)
	(segment
		(start 18.250916 -237.00994)
		(end 18.129504 -236.888528)
		(width 0.17145)
		(layer "F.Cu")
		(net "SSD12_PERST_N")
	)
	(segment
		(start 9.978644 -284.988508)
		(end 8.21309 -284.988508)
		(width 0.17145)
		(layer "F.Cu")
		(net "SSD12_PERST_N")
	)
	(segment
		(start 10.62736 -283.350208)
		(end 10.62736 -284.339792)
		(width 0.17145)
		(layer "F.Cu")
		(net "SSD12_PERST_N")
	)
	(segment
		(start 18.129504 -236.460284)
		(end 18.379694 -236.210094)
		(width 0.17145)
		(layer "F.Cu")
		(net "SSD12_PERST_N")
	)
	(segment
		(start 18.129504 -236.888528)
		(end 18.129504 -236.460284)
		(width 0.17145)
		(layer "F.Cu")
		(net "SSD12_PERST_N")
	)
	(segment
		(start 19.61007 -236.210094)
		(end 18.379694 -236.210094)
		(width 0.17145)
		(layer "F.Cu")
		(net "SSD12_PERST_N")
	)
	(segment
		(start 19.61007 -237.00994)
		(end 18.250916 -237.00994)
		(width 0.17145)
		(layer "F.Cu")
		(net "SSD12_PERST_N")
	)
	(segment
		(start 9.987026 -281.151838)
		(end 10.62736 -281.792172)
		(width 0.17145)
		(layer "F.Cu")
		(net "SSD12_PERST_N")
	)
	(segment
		(start 9.987026 -276.470618)
		(end 9.987026 -281.151838)
		(width 0.17145)
		(layer "F.Cu")
		(net "SSD12_PERST_N")
	)
	(segment
		(start 10.740644 -275.717)
		(end 9.987026 -276.470618)
		(width 0.17145)
		(layer "F.Cu")
		(net "SSD12_PERST_N")
	)
	(via
		(at 10.62736 -283.350208)
		(size 0.7112)
		(drill 0.3556)
		(layers "F.Cu" "B.Cu")
		(net "SSD12_PERST_N")
	)
	(via
		(at 18.034 -235.077)
		(size 0.508)
		(drill 0.254)
		(layers "F.Cu" "B.Cu")
		(net "SSD12_PERST_N")
	)
	(via
		(at 8.21309 -284.988508)
		(size 0.508)
		(drill 0.254)
		(layers "F.Cu" "B.Cu")
		(net "SSD12_PERST_N")
	)
	(via
		(at 10.740644 -275.717)
		(size 0.508)
		(drill 0.254)
		(layers "F.Cu" "B.Cu")
		(net "SSD12_PERST_N")
	)
	(segment
		(start 13.5636 -237.617)
		(end 16.3068 -234.8738)
		(width 0.17145)
		(layer "B.Cu")
		(net "SSD12_PERST_N")
	)
	(segment
		(start 10.740644 -275.717)
		(end 12.394692 -275.717)
		(width 0.17145)
		(layer "B.Cu")
		(net "SSD12_PERST_N")
	)
	(segment
		(start 16.3068 -234.8738)
		(end 17.8308 -234.8738)
		(width 0.17145)
		(layer "B.Cu")
		(net "SSD12_PERST_N")
	)
	(segment
		(start 18.034 -270.077692)
		(end 18.034 -265.938)
		(width 0.17145)
		(layer "B.Cu")
		(net "SSD12_PERST_N")
	)
	(segment
		(start 13.5636 -256.279904)
		(end 13.5636 -237.617)
		(width 0.17145)
		(layer "B.Cu")
		(net "SSD12_PERST_N")
	)
	(segment
		(start 4.799584 -285.942024)
		(end 1.868932 -285.942024)
		(width 0.17145)
		(layer "B.Cu")
		(net "SSD12_PERST_N")
	)
	(segment
		(start 18.8722 -261.588504)
		(end 13.5636 -256.279904)
		(width 0.17145)
		(layer "B.Cu")
		(net "SSD12_PERST_N")
	)
	(segment
		(start 18.8722 -265.0998)
		(end 18.8722 -261.588504)
		(width 0.17145)
		(layer "B.Cu")
		(net "SSD12_PERST_N")
	)
	(segment
		(start 5.7531 -284.988508)
		(end 4.799584 -285.942024)
		(width 0.17145)
		(layer "B.Cu")
		(net "SSD12_PERST_N")
	)
	(segment
		(start 8.21309 -284.988508)
		(end 5.7531 -284.988508)
		(width 0.17145)
		(layer "B.Cu")
		(net "SSD12_PERST_N")
	)
	(segment
		(start 17.8308 -234.8738)
		(end 18.034 -235.077)
		(width 0.17145)
		(layer "B.Cu")
		(net "SSD12_PERST_N")
	)
	(segment
		(start 18.034 -265.938)
		(end 18.8722 -265.0998)
		(width 0.17145)
		(layer "B.Cu")
		(net "SSD12_PERST_N")
	)
	(segment
		(start 12.394692 -275.717)
		(end 18.034 -270.077692)
		(width 0.17145)
		(layer "B.Cu")
		(net "SSD12_PERST_N")
	)
	(segment
		(start 88.138 -224.7265)
		(end 88.138 -225.7425)
		(width 0.17145)
		(layer "F.Cu")
		(net "SSD12_CLK0_OE_N")
	)
	(segment
		(start 88.138 -225.7425)
		(end 88.2015 -225.806)
		(width 0.17145)
		(layer "F.Cu")
		(net "SSD12_CLK0_OE_N")
	)
	(segment
		(start 88.2015 -228.235764)
		(end 88.2015 -227.076)
		(width 0.17145)
		(layer "F.Cu")
		(net "SSD12_CLK0_OE_N")
	)
	(segment
		(start 17.47901 -230.42499)
		(end 16.041878 -231.862122)
		(width 0.17145)
		(layer "F.Cu")
		(net "SSD12_CLK0_OE_N")
	)
	(segment
		(start 21.086826 -255.93167)
		(end 41.731946 -235.28655)
		(width 0.17145)
		(layer "F.Cu")
		(net "SSD12_CLK0_OE_N")
	)
	(segment
		(start 41.731946 -235.28655)
		(end 81.150714 -235.28655)
		(width 0.17145)
		(layer "F.Cu")
		(net "SSD12_CLK0_OE_N")
	)
	(segment
		(start 17.49806 -255.93167)
		(end 21.086826 -255.93167)
		(width 0.17145)
		(layer "F.Cu")
		(net "SSD12_CLK0_OE_N")
	)
	(segment
		(start 16.041878 -231.862122)
		(end 16.041878 -254.475488)
		(width 0.17145)
		(layer "F.Cu")
		(net "SSD12_CLK0_OE_N")
	)
	(segment
		(start 20.025106 -230.42499)
		(end 17.47901 -230.42499)
		(width 0.17145)
		(layer "F.Cu")
		(net "SSD12_CLK0_OE_N")
	)
	(segment
		(start 88.2015 -227.076)
		(end 88.2015 -225.806)
		(width 0.17145)
		(layer "F.Cu")
		(net "SSD12_CLK0_OE_N")
	)
	(segment
		(start 16.041878 -254.475488)
		(end 17.49806 -255.93167)
		(width 0.17145)
		(layer "F.Cu")
		(net "SSD12_CLK0_OE_N")
	)
	(segment
		(start 81.150714 -235.28655)
		(end 88.2015 -228.235764)
		(width 0.17145)
		(layer "F.Cu")
		(net "SSD12_CLK0_OE_N")
	)
	(via
		(at 88.2015 -227.076)
		(size 0.7112)
		(drill 0.3556)
		(layers "F.Cu" "B.Cu")
		(net "SSD12_CLK0_OE_N")
	)
	(segment
		(start 35.8775 -308.2925)
		(end 37.973 -308.2925)
		(width 0.17145)
		(layer "F.Cu")
		(net "SSD11_PWREN")
	)
	(segment
		(start 36.25215 -310.8579)
		(end 35.56 -310.16575)
		(width 0.17145)
		(layer "F.Cu")
		(net "SSD11_PWREN")
	)
	(segment
		(start 40.27805 -307.542946)
		(end 39.528496 -308.2925)
		(width 0.17145)
		(layer "F.Cu")
		(net "SSD11_PWREN")
	)
	(segment
		(start 41.44518 -307.593746)
		(end 40.867584 -307.01615)
		(width 0.17145)
		(layer "F.Cu")
		(net "SSD11_PWREN")
	)
	(segment
		(start 35.56 -308.61)
		(end 35.8775 -308.2925)
		(width 0.17145)
		(layer "F.Cu")
		(net "SSD11_PWREN")
	)
	(segment
		(start 36.78555 -310.8579)
		(end 36.25215 -310.8579)
		(width 0.17145)
		(layer "F.Cu")
		(net "SSD11_PWREN")
	)
	(segment
		(start 40.27805 -307.01615)
		(end 40.27805 -307.542946)
		(width 0.17145)
		(layer "F.Cu")
		(net "SSD11_PWREN")
	)
	(segment
		(start 40.867584 -307.01615)
		(end 40.27805 -307.01615)
		(width 0.17145)
		(layer "F.Cu")
		(net "SSD11_PWREN")
	)
	(segment
		(start 39.116 -308.2925)
		(end 37.973 -308.2925)
		(width 0.17145)
		(layer "F.Cu")
		(net "SSD11_PWREN")
	)
	(segment
		(start 39.528496 -308.2925)
		(end 39.116 -308.2925)
		(width 0.17145)
		(layer "F.Cu")
		(net "SSD11_PWREN")
	)
	(segment
		(start 35.56 -310.16575)
		(end 35.56 -308.61)
		(width 0.17145)
		(layer "F.Cu")
		(net "SSD11_PWREN")
	)
	(via
		(at 41.44518 -307.593746)
		(size 0.5588)
		(drill 0.3048)
		(layers "F.Cu" "B.Cu")
		(net "SSD11_PWREN")
	)
	(via
		(at 6.731 -331.500734)
		(size 0.508)
		(drill 0.254)
		(layers "F.Cu" "B.Cu")
		(net "SSD11_PWREN")
	)
	(segment
		(start 1.868932 -332.342236)
		(end 4.106164 -332.342236)
		(width 0.17145)
		(layer "B.Cu")
		(net "SSD11_PWREN")
	)
	(segment
		(start 4.947666 -331.500734)
		(end 6.731 -331.500734)
		(width 0.17145)
		(layer "B.Cu")
		(net "SSD11_PWREN")
	)
	(segment
		(start 4.106164 -332.342236)
		(end 4.947666 -331.500734)
		(width 0.17145)
		(layer "B.Cu")
		(net "SSD11_PWREN")
	)
	(segment
		(start 41.44518 -310.19242)
		(end 37.6936 -313.944)
		(width 0.1524)
		(layer "In5.Cu")
		(net "SSD11_PWREN")
	)
	(segment
		(start 9.63168 -329.7428)
		(end 7.6962 -329.7428)
		(width 0.1524)
		(layer "In5.Cu")
		(net "SSD11_PWREN")
	)
	(segment
		(start 37.6936 -313.944)
		(end 25.43048 -313.944)
		(width 0.1524)
		(layer "In5.Cu")
		(net "SSD11_PWREN")
	)
	(segment
		(start 6.731 -330.708)
		(end 6.731 -331.500734)
		(width 0.1524)
		(layer "In5.Cu")
		(net "SSD11_PWREN")
	)
	(segment
		(start 25.43048 -313.944)
		(end 9.63168 -329.7428)
		(width 0.1524)
		(layer "In5.Cu")
		(net "SSD11_PWREN")
	)
	(segment
		(start 41.44518 -307.593746)
		(end 41.44518 -310.19242)
		(width 0.1524)
		(layer "In5.Cu")
		(net "SSD11_PWREN")
	)
	(segment
		(start 7.6962 -329.7428)
		(end 6.731 -330.708)
		(width 0.1524)
		(layer "In5.Cu")
		(net "SSD11_PWREN")
	)
	(segment
		(start 18.03781 -339.210142)
		(end 18.034 -339.213952)
		(width 0.17145)
		(layer "F.Cu")
		(net "SSD11_PERST_N")
	)
	(segment
		(start 19.61007 -340.009988)
		(end 18.830036 -340.009988)
		(width 0.17145)
		(layer "F.Cu")
		(net "SSD11_PERST_N")
	)
	(segment
		(start 8.559546 -325.831454)
		(end 8.559546 -330.652628)
		(width 0.17145)
		(layer "F.Cu")
		(net "SSD11_PERST_N")
	)
	(segment
		(start 10.740644 -281.054048)
		(end 11.221212 -281.534616)
		(width 0.17145)
		(layer "F.Cu")
		(net "SSD11_PERST_N")
	)
	(segment
		(start 11.221212 -293.916608)
		(end 9.96823 -295.16959)
		(width 0.17145)
		(layer "F.Cu")
		(net "SSD11_PERST_N")
	)
	(segment
		(start 19.61007 -339.210142)
		(end 18.03781 -339.210142)
		(width 0.17145)
		(layer "F.Cu")
		(net "SSD11_PERST_N")
	)
	(segment
		(start 11.221212 -281.534616)
		(end 11.221212 -293.916608)
		(width 0.17145)
		(layer "F.Cu")
		(net "SSD11_PERST_N")
	)
	(segment
		(start 18.830036 -340.009988)
		(end 18.034 -339.213952)
		(width 0.17145)
		(layer "F.Cu")
		(net "SSD11_PERST_N")
	)
	(segment
		(start 9.96823 -324.42277)
		(end 8.559546 -325.831454)
		(width 0.17145)
		(layer "F.Cu")
		(net "SSD11_PERST_N")
	)
	(segment
		(start 10.740644 -280.488644)
		(end 10.740644 -281.054048)
		(width 0.17145)
		(layer "F.Cu")
		(net "SSD11_PERST_N")
	)
	(segment
		(start 10.740644 -276.733)
		(end 10.740644 -280.488644)
		(width 0.17145)
		(layer "F.Cu")
		(net "SSD11_PERST_N")
	)
	(segment
		(start 9.96823 -295.16959)
		(end 9.96823 -324.42277)
		(width 0.17145)
		(layer "F.Cu")
		(net "SSD11_PERST_N")
	)
	(via
		(at 18.034 -339.213952)
		(size 0.508)
		(drill 0.254)
		(layers "F.Cu" "B.Cu")
		(net "SSD11_PERST_N")
	)
	(via
		(at 10.740644 -280.488644)
		(size 0.7112)
		(drill 0.3556)
		(layers "F.Cu" "B.Cu")
		(net "SSD11_PERST_N")
	)
	(via
		(at 8.559546 -330.652628)
		(size 0.508)
		(drill 0.254)
		(layers "F.Cu" "B.Cu")
		(net "SSD11_PERST_N")
	)
	(via
		(at 10.740644 -276.733)
		(size 0.508)
		(drill 0.254)
		(layers "F.Cu" "B.Cu")
		(net "SSD11_PERST_N")
	)
	(segment
		(start 13.008102 -330.652628)
		(end 8.559546 -330.652628)
		(width 0.17145)
		(layer "B.Cu")
		(net "SSD11_PERST_N")
	)
	(segment
		(start 18.923 -338.328)
		(end 18.923 -334.339438)
		(width 0.17145)
		(layer "B.Cu")
		(net "SSD11_PERST_N")
	)
	(segment
		(start 4.445 -276.733)
		(end 3.23596 -277.94204)
		(width 0.17145)
		(layer "B.Cu")
		(net "SSD11_PERST_N")
	)
	(segment
		(start 15.640812 -333.285338)
		(end 13.008102 -330.652628)
		(width 0.17145)
		(layer "B.Cu")
		(net "SSD11_PERST_N")
	)
	(segment
		(start 17.8689 -333.285338)
		(end 15.640812 -333.285338)
		(width 0.17145)
		(layer "B.Cu")
		(net "SSD11_PERST_N")
	)
	(segment
		(start 10.740644 -276.733)
		(end 4.445 -276.733)
		(width 0.17145)
		(layer "B.Cu")
		(net "SSD11_PERST_N")
	)
	(segment
		(start 18.923 -334.339438)
		(end 17.8689 -333.285338)
		(width 0.17145)
		(layer "B.Cu")
		(net "SSD11_PERST_N")
	)
	(segment
		(start 18.037048 -339.213952)
		(end 18.923 -338.328)
		(width 0.17145)
		(layer "B.Cu")
		(net "SSD11_PERST_N")
	)
	(segment
		(start 3.23596 -277.94204)
		(end 1.868932 -277.94204)
		(width 0.17145)
		(layer "B.Cu")
		(net "SSD11_PERST_N")
	)
	(segment
		(start 18.034 -339.213952)
		(end 18.037048 -339.213952)
		(width 0.17145)
		(layer "B.Cu")
		(net "SSD11_PERST_N")
	)
	(segment
		(start 18.618962 -333.425038)
		(end 17.0434 -335.0006)
		(width 0.17145)
		(layer "F.Cu")
		(net "SSD11_CLK0_OE_N")
	)
	(segment
		(start 29.967682 -340.091014)
		(end 33.77057 -336.288126)
		(width 0.17145)
		(layer "F.Cu")
		(net "SSD11_CLK0_OE_N")
	)
	(segment
		(start 33.77057 -336.288126)
		(end 73.809098 -336.288126)
		(width 0.17145)
		(layer "F.Cu")
		(net "SSD11_CLK0_OE_N")
	)
	(segment
		(start 73.809098 -336.288126)
		(end 88.2015 -321.895724)
		(width 0.17145)
		(layer "F.Cu")
		(net "SSD11_CLK0_OE_N")
	)
	(segment
		(start 88.138 -320.1035)
		(end 88.2015 -320.167)
		(width 0.17145)
		(layer "F.Cu")
		(net "SSD11_CLK0_OE_N")
	)
	(segment
		(start 16.383 -339.2932)
		(end 16.383 -351.663)
		(width 0.17145)
		(layer "F.Cu")
		(net "SSD11_CLK0_OE_N")
	)
	(segment
		(start 88.138 -319.0875)
		(end 88.138 -320.1035)
		(width 0.17145)
		(layer "F.Cu")
		(net "SSD11_CLK0_OE_N")
	)
	(segment
		(start 29.967682 -349.762318)
		(end 29.967682 -340.091014)
		(width 0.17145)
		(layer "F.Cu")
		(net "SSD11_CLK0_OE_N")
	)
	(segment
		(start 27.559 -352.171)
		(end 29.967682 -349.762318)
		(width 0.17145)
		(layer "F.Cu")
		(net "SSD11_CLK0_OE_N")
	)
	(segment
		(start 16.383 -351.663)
		(end 16.891 -352.171)
		(width 0.17145)
		(layer "F.Cu")
		(net "SSD11_CLK0_OE_N")
	)
	(segment
		(start 88.2015 -321.895724)
		(end 88.2015 -321.437)
		(width 0.17145)
		(layer "F.Cu")
		(net "SSD11_CLK0_OE_N")
	)
	(segment
		(start 17.0434 -338.6328)
		(end 16.383 -339.2932)
		(width 0.17145)
		(layer "F.Cu")
		(net "SSD11_CLK0_OE_N")
	)
	(segment
		(start 88.2015 -321.437)
		(end 88.2015 -320.167)
		(width 0.17145)
		(layer "F.Cu")
		(net "SSD11_CLK0_OE_N")
	)
	(segment
		(start 16.891 -352.171)
		(end 27.559 -352.171)
		(width 0.17145)
		(layer "F.Cu")
		(net "SSD11_CLK0_OE_N")
	)
	(segment
		(start 17.0434 -335.0006)
		(end 17.0434 -338.6328)
		(width 0.17145)
		(layer "F.Cu")
		(net "SSD11_CLK0_OE_N")
	)
	(segment
		(start 20.025106 -333.425038)
		(end 18.618962 -333.425038)
		(width 0.17145)
		(layer "F.Cu")
		(net "SSD11_CLK0_OE_N")
	)
	(via
		(at 88.2015 -321.437)
		(size 0.7112)
		(drill 0.3556)
		(layers "F.Cu" "B.Cu")
		(net "SSD11_CLK0_OE_N")
	)
	(segment
		(start 35.56 -413.16275)
		(end 35.56 -411.607)
		(width 0.17145)
		(layer "F.Cu")
		(net "SSD10_PWREN")
	)
	(segment
		(start 39.2049 -408.94)
		(end 21.211286 -408.94)
		(width 0.17145)
		(layer "F.Cu")
		(net "SSD10_PWREN")
	)
	(segment
		(start 40.27805 -410.01315)
		(end 40.27805 -410.539946)
		(width 0.17145)
		(layer "F.Cu")
		(net "SSD10_PWREN")
	)
	(segment
		(start 21.211286 -408.94)
		(end 16.38935 -404.118064)
		(width 0.17145)
		(layer "F.Cu")
		(net "SSD10_PWREN")
	)
	(segment
		(start 37.09035 -413.8549)
		(end 36.25215 -413.8549)
		(width 0.17145)
		(layer "F.Cu")
		(net "SSD10_PWREN")
	)
	(segment
		(start 39.528496 -411.2895)
		(end 39.116 -411.2895)
		(width 0.17145)
		(layer "F.Cu")
		(net "SSD10_PWREN")
	)
	(segment
		(start 36.25215 -413.8549)
		(end 35.56 -413.16275)
		(width 0.17145)
		(layer "F.Cu")
		(net "SSD10_PWREN")
	)
	(segment
		(start 35.8775 -411.2895)
		(end 37.973 -411.2895)
		(width 0.17145)
		(layer "F.Cu")
		(net "SSD10_PWREN")
	)
	(segment
		(start 35.56 -411.607)
		(end 35.8775 -411.2895)
		(width 0.17145)
		(layer "F.Cu")
		(net "SSD10_PWREN")
	)
	(segment
		(start 37.973 -411.2895)
		(end 39.116 -411.2895)
		(width 0.17145)
		(layer "F.Cu")
		(net "SSD10_PWREN")
	)
	(segment
		(start 40.27805 -410.01315)
		(end 39.2049 -408.94)
		(width 0.17145)
		(layer "F.Cu")
		(net "SSD10_PWREN")
	)
	(segment
		(start 40.27805 -410.539946)
		(end 39.528496 -411.2895)
		(width 0.17145)
		(layer "F.Cu")
		(net "SSD10_PWREN")
	)
	(via
		(at 16.38935 -404.118064)
		(size 0.508)
		(drill 0.254)
		(layers "F.Cu" "B.Cu")
		(net "SSD10_PWREN")
	)
	(via
		(at 14.157452 -400.961098)
		(size 0.7112)
		(drill 0.3556)
		(layers "F.Cu" "B.Cu")
		(net "SSD10_PWREN")
	)
	(segment
		(start 16.38935 -403.192996)
		(end 14.157452 -400.961098)
		(width 0.17145)
		(layer "B.Cu")
		(net "SSD10_PWREN")
	)
	(segment
		(start 4.5212 -400.2532)
		(end 4.032504 -400.741896)
		(width 0.17145)
		(layer "B.Cu")
		(net "SSD10_PWREN")
	)
	(segment
		(start 16.38935 -404.118064)
		(end 16.38935 -403.192996)
		(width 0.17145)
		(layer "B.Cu")
		(net "SSD10_PWREN")
	)
	(segment
		(start 13.449554 -400.2532)
		(end 4.5212 -400.2532)
		(width 0.17145)
		(layer "B.Cu")
		(net "SSD10_PWREN")
	)
	(segment
		(start 4.032504 -400.741896)
		(end 1.868932 -400.741896)
		(width 0.17145)
		(layer "B.Cu")
		(net "SSD10_PWREN")
	)
	(segment
		(start 14.157452 -400.961098)
		(end 13.449554 -400.2532)
		(width 0.17145)
		(layer "B.Cu")
		(net "SSD10_PWREN")
	)
	(segment
		(start 19.61007 -442.21019)
		(end 18.215356 -442.21019)
		(width 0.17145)
		(layer "F.Cu")
		(net "SSD10_PERST_N")
	)
	(segment
		(start 18.111978 -443.010036)
		(end 19.61007 -443.010036)
		(width 0.17145)
		(layer "F.Cu")
		(net "SSD10_PERST_N")
	)
	(segment
		(start 13.136372 -422.979088)
		(end 13.11529 -423.00017)
		(width 0.17145)
		(layer "F.Cu")
		(net "SSD10_PERST_N")
	)
	(segment
		(start 13.136372 -405.272748)
		(end 13.136372 -422.979088)
		(width 0.17145)
		(layer "F.Cu")
		(net "SSD10_PERST_N")
	)
	(segment
		(start 13.136372 -385.860798)
		(end 13.136372 -405.272748)
		(width 0.17145)
		(layer "F.Cu")
		(net "SSD10_PERST_N")
	)
	(segment
		(start 17.977104 -442.448442)
		(end 17.977104 -442.875162)
		(width 0.17145)
		(layer "F.Cu")
		(net "SSD10_PERST_N")
	)
	(segment
		(start 17.977104 -442.875162)
		(end 18.111978 -443.010036)
		(width 0.17145)
		(layer "F.Cu")
		(net "SSD10_PERST_N")
	)
	(segment
		(start 18.215356 -442.21019)
		(end 17.977104 -442.448442)
		(width 0.17145)
		(layer "F.Cu")
		(net "SSD10_PERST_N")
	)
	(segment
		(start 18.03781 -441.452)
		(end 18.03781 -442.032644)
		(width 0.17145)
		(layer "F.Cu")
		(net "SSD10_PERST_N")
	)
	(segment
		(start 11.89863 -384.623056)
		(end 13.136372 -385.860798)
		(width 0.17145)
		(layer "F.Cu")
		(net "SSD10_PERST_N")
	)
	(segment
		(start 18.03781 -442.032644)
		(end 18.215356 -442.21019)
		(width 0.17145)
		(layer "F.Cu")
		(net "SSD10_PERST_N")
	)
	(via
		(at 18.03781 -441.452)
		(size 0.508)
		(drill 0.254)
		(layers "F.Cu" "B.Cu")
		(net "SSD10_PERST_N")
	)
	(via
		(at 13.136372 -405.272748)
		(size 0.7112)
		(drill 0.3556)
		(layers "F.Cu" "B.Cu")
		(net "SSD10_PERST_N")
	)
	(via
		(at 13.11529 -423.00017)
		(size 0.508)
		(drill 0.254)
		(layers "F.Cu" "B.Cu")
		(net "SSD10_PERST_N")
	)
	(via
		(at 11.89863 -384.623056)
		(size 0.508)
		(drill 0.254)
		(layers "F.Cu" "B.Cu")
		(net "SSD10_PERST_N")
	)
	(segment
		(start 10.193528 -386.6769)
		(end 9.749028 -387.1214)
		(width 0.17145)
		(layer "B.Cu")
		(net "SSD10_PERST_N")
	)
	(segment
		(start 8.1534 -387.1214)
		(end 7.112 -386.08)
		(width 0.17145)
		(layer "B.Cu")
		(net "SSD10_PERST_N")
	)
	(segment
		(start 10.193528 -385.091686)
		(end 10.193528 -386.6769)
		(width 0.17145)
		(layer "B.Cu")
		(net "SSD10_PERST_N")
	)
	(segment
		(start 7.112 -386.08)
		(end 5.588 -386.08)
		(width 0.17145)
		(layer "B.Cu")
		(net "SSD10_PERST_N")
	)
	(segment
		(start 11.89863 -384.623056)
		(end 10.662158 -384.623056)
		(width 0.17145)
		(layer "B.Cu")
		(net "SSD10_PERST_N")
	)
	(segment
		(start 9.749028 -387.1214)
		(end 8.1534 -387.1214)
		(width 0.17145)
		(layer "B.Cu")
		(net "SSD10_PERST_N")
	)
	(segment
		(start 4.526026 -387.141974)
		(end 1.868932 -387.141974)
		(width 0.17145)
		(layer "B.Cu")
		(net "SSD10_PERST_N")
	)
	(segment
		(start 10.662158 -384.623056)
		(end 10.193528 -385.091686)
		(width 0.17145)
		(layer "B.Cu")
		(net "SSD10_PERST_N")
	)
	(segment
		(start 5.588 -386.08)
		(end 4.526026 -387.141974)
		(width 0.17145)
		(layer "B.Cu")
		(net "SSD10_PERST_N")
	)
	(segment
		(start 18.53692 -426.07992)
		(end 20.066 -427.609)
		(width 0.1524)
		(layer "In5.Cu")
		(net "SSD10_PERST_N")
	)
	(segment
		(start 20.066 -427.609)
		(end 20.066 -439.42381)
		(width 0.1524)
		(layer "In5.Cu")
		(net "SSD10_PERST_N")
	)
	(segment
		(start 13.11529 -423.00017)
		(end 16.19504 -426.07992)
		(width 0.1524)
		(layer "In5.Cu")
		(net "SSD10_PERST_N")
	)
	(segment
		(start 20.066 -439.42381)
		(end 18.03781 -441.452)
		(width 0.1524)
		(layer "In5.Cu")
		(net "SSD10_PERST_N")
	)
	(segment
		(start 16.19504 -426.07992)
		(end 18.53692 -426.07992)
		(width 0.1524)
		(layer "In5.Cu")
		(net "SSD10_PERST_N")
	)
	(segment
		(start 29.972 -437.241696)
		(end 52.741068 -414.472628)
		(width 0.17145)
		(layer "F.Cu")
		(net "SSD10_CLK0_OE_N")
	)
	(segment
		(start 18.2118 -454.9648)
		(end 28.103068 -454.9648)
		(width 0.17145)
		(layer "F.Cu")
		(net "SSD10_CLK0_OE_N")
	)
	(segment
		(start 29.972 -453.095868)
		(end 29.972 -437.241696)
		(width 0.17145)
		(layer "F.Cu")
		(net "SSD10_CLK0_OE_N")
	)
	(segment
		(start 52.741068 -414.472628)
		(end 88.527128 -414.472628)
		(width 0.17145)
		(layer "F.Cu")
		(net "SSD10_CLK0_OE_N")
	)
	(segment
		(start 28.103068 -454.9648)
		(end 29.972 -453.095868)
		(width 0.17145)
		(layer "F.Cu")
		(net "SSD10_CLK0_OE_N")
	)
	(segment
		(start 16.383 -438.457086)
		(end 16.383 -453.136)
		(width 0.17145)
		(layer "F.Cu")
		(net "SSD10_CLK0_OE_N")
	)
	(segment
		(start 20.025106 -436.425086)
		(end 18.415 -436.425086)
		(width 0.17145)
		(layer "F.Cu")
		(net "SSD10_CLK0_OE_N")
	)
	(segment
		(start 88.527128 -414.472628)
		(end 89.5985 -415.544)
		(width 0.17145)
		(layer "F.Cu")
		(net "SSD10_CLK0_OE_N")
	)
	(segment
		(start 18.415 -436.425086)
		(end 16.383 -438.457086)
		(width 0.17145)
		(layer "F.Cu")
		(net "SSD10_CLK0_OE_N")
	)
	(segment
		(start 16.383 -453.136)
		(end 18.2118 -454.9648)
		(width 0.17145)
		(layer "F.Cu")
		(net "SSD10_CLK0_OE_N")
	)
	(segment
		(start 89.5985 -416.814)
		(end 89.5985 -415.544)
		(width 0.17145)
		(layer "F.Cu")
		(net "SSD10_CLK0_OE_N")
	)
	(segment
		(start 89.662 -416.8775)
		(end 89.5985 -416.814)
		(width 0.17145)
		(layer "F.Cu")
		(net "SSD10_CLK0_OE_N")
	)
	(segment
		(start 89.662 -417.8935)
		(end 89.662 -416.8775)
		(width 0.17145)
		(layer "F.Cu")
		(net "SSD10_CLK0_OE_N")
	)
	(via
		(at 89.5985 -415.544)
		(size 0.7112)
		(drill 0.3556)
		(layers "F.Cu" "B.Cu")
		(net "SSD10_CLK0_OE_N")
	)
	(segment
		(start 205.170024 -404.94585)
		(end 206.22895 -404.94585)
		(width 0.17145)
		(layer "F.Cu")
		(net "SSD1_PWREN")
	)
	(segment
		(start 10.831576 -386.577078)
		(end 11.479022 -387.224524)
		(width 0.17145)
		(layer "F.Cu")
		(net "SSD1_PWREN")
	)
	(segment
		(start 210.82 -402.336)
		(end 210.82 -403.352)
		(width 0.17145)
		(layer "F.Cu")
		(net "SSD1_PWREN")
	)
	(segment
		(start 207.391 -403.6695)
		(end 206.978504 -403.6695)
		(width 0.17145)
		(layer "F.Cu")
		(net "SSD1_PWREN")
	)
	(segment
		(start 206.22895 -404.419054)
		(end 206.22895 -404.94585)
		(width 0.17145)
		(layer "F.Cu")
		(net "SSD1_PWREN")
	)
	(segment
		(start 210.5025 -403.6695)
		(end 208.534 -403.6695)
		(width 0.17145)
		(layer "F.Cu")
		(net "SSD1_PWREN")
	)
	(segment
		(start 11.479022 -397.714978)
		(end 8.452104 -400.741896)
		(width 0.17145)
		(layer "F.Cu")
		(net "SSD1_PWREN")
	)
	(segment
		(start 210.28025 -401.79625)
		(end 210.82 -402.336)
		(width 0.17145)
		(layer "F.Cu")
		(net "SSD1_PWREN")
	)
	(segment
		(start 208.534 -403.6695)
		(end 207.391 -403.6695)
		(width 0.17145)
		(layer "F.Cu")
		(net "SSD1_PWREN")
	)
	(segment
		(start 210.28025 -401.1295)
		(end 210.28025 -401.79625)
		(width 0.17145)
		(layer "F.Cu")
		(net "SSD1_PWREN")
	)
	(segment
		(start 11.479022 -387.224524)
		(end 11.479022 -397.714978)
		(width 0.17145)
		(layer "F.Cu")
		(net "SSD1_PWREN")
	)
	(segment
		(start 206.978504 -403.6695)
		(end 206.22895 -404.419054)
		(width 0.17145)
		(layer "F.Cu")
		(net "SSD1_PWREN")
	)
	(segment
		(start 210.82 -403.352)
		(end 210.5025 -403.6695)
		(width 0.17145)
		(layer "F.Cu")
		(net "SSD1_PWREN")
	)
	(segment
		(start 8.452104 -400.741896)
		(end 2.249932 -400.741896)
		(width 0.17145)
		(layer "F.Cu")
		(net "SSD1_PWREN")
	)
	(via
		(at 205.170024 -404.94585)
		(size 0.5588)
		(drill 0.3048)
		(layers "F.Cu" "B.Cu")
		(net "SSD1_PWREN")
	)
	(via
		(at 10.831576 -386.577078)
		(size 0.508)
		(drill 0.254)
		(layers "F.Cu" "B.Cu")
		(net "SSD1_PWREN")
	)
	(segment
		(start 125.2474 -343.6366)
		(end 77.089 -391.795)
		(width 0.1524)
		(layer "In5.Cu")
		(net "SSD1_PWREN")
	)
	(segment
		(start 35.06216 -391.795)
		(end 31.68396 -388.4168)
		(width 0.1524)
		(layer "In5.Cu")
		(net "SSD1_PWREN")
	)
	(segment
		(start 77.089 -391.795)
		(end 35.06216 -391.795)
		(width 0.1524)
		(layer "In5.Cu")
		(net "SSD1_PWREN")
	)
	(segment
		(start 226.478338 -348.372938)
		(end 226.478338 -347.034358)
		(width 0.1524)
		(layer "In5.Cu")
		(net "SSD1_PWREN")
	)
	(segment
		(start 223.08058 -343.6366)
		(end 125.2474 -343.6366)
		(width 0.1524)
		(layer "In5.Cu")
		(net "SSD1_PWREN")
	)
	(segment
		(start 232.4354 -354.33)
		(end 226.478338 -348.372938)
		(width 0.1524)
		(layer "In5.Cu")
		(net "SSD1_PWREN")
	)
	(segment
		(start 31.68396 -388.4168)
		(end 22.39264 -388.4168)
		(width 0.1524)
		(layer "In5.Cu")
		(net "SSD1_PWREN")
	)
	(segment
		(start 11.477498 -387.223)
		(end 10.831576 -386.577078)
		(width 0.1524)
		(layer "In5.Cu")
		(net "SSD1_PWREN")
	)
	(segment
		(start 222.05315 -404.94585)
		(end 223.901 -403.098)
		(width 0.1524)
		(layer "In5.Cu")
		(net "SSD1_PWREN")
	)
	(segment
		(start 223.901 -403.098)
		(end 223.901 -390.525)
		(width 0.1524)
		(layer "In5.Cu")
		(net "SSD1_PWREN")
	)
	(segment
		(start 21.19884 -387.223)
		(end 11.477498 -387.223)
		(width 0.1524)
		(layer "In5.Cu")
		(net "SSD1_PWREN")
	)
	(segment
		(start 205.170024 -404.94585)
		(end 222.05315 -404.94585)
		(width 0.1524)
		(layer "In5.Cu")
		(net "SSD1_PWREN")
	)
	(segment
		(start 232.4354 -381.9906)
		(end 232.4354 -354.33)
		(width 0.1524)
		(layer "In5.Cu")
		(net "SSD1_PWREN")
	)
	(segment
		(start 223.901 -390.525)
		(end 232.4354 -381.9906)
		(width 0.1524)
		(layer "In5.Cu")
		(net "SSD1_PWREN")
	)
	(segment
		(start 22.39264 -388.4168)
		(end 21.19884 -387.223)
		(width 0.1524)
		(layer "In5.Cu")
		(net "SSD1_PWREN")
	)
	(segment
		(start 226.478338 -347.034358)
		(end 223.08058 -343.6366)
		(width 0.1524)
		(layer "In5.Cu")
		(net "SSD1_PWREN")
	)
	(segment
		(start 9.525 -401.574)
		(end 7.661148 -403.437852)
		(width 0.17145)
		(layer "F.Cu")
		(net "SSD1_PERST_N")
	)
	(segment
		(start 6.858 -417.957)
		(end 5.860542 -417.957)
		(width 0.17145)
		(layer "F.Cu")
		(net "SSD1_PERST_N")
	)
	(segment
		(start 7.661148 -417.153852)
		(end 6.858 -417.957)
		(width 0.17145)
		(layer "F.Cu")
		(net "SSD1_PERST_N")
	)
	(segment
		(start 3.980942 -418.229542)
		(end 3.293364 -417.541964)
		(width 0.17145)
		(layer "F.Cu")
		(net "SSD1_PERST_N")
	)
	(segment
		(start 12.031472 -399.067528)
		(end 9.525 -401.574)
		(width 0.17145)
		(layer "F.Cu")
		(net "SSD1_PERST_N")
	)
	(segment
		(start 12.031472 -387.940042)
		(end 12.031472 -399.067528)
		(width 0.17145)
		(layer "F.Cu")
		(net "SSD1_PERST_N")
	)
	(segment
		(start 227.389944 -371.990112)
		(end 228.556312 -371.990112)
		(width 0.17145)
		(layer "F.Cu")
		(net "SSD1_PERST_N")
	)
	(segment
		(start 5.860542 -417.957)
		(end 5.588 -418.229542)
		(width 0.17145)
		(layer "F.Cu")
		(net "SSD1_PERST_N")
	)
	(segment
		(start 228.556312 -371.990112)
		(end 228.9556 -372.3894)
		(width 0.17145)
		(layer "F.Cu")
		(net "SSD1_PERST_N")
	)
	(segment
		(start 228.555042 -372.789958)
		(end 228.9556 -372.3894)
		(width 0.17145)
		(layer "F.Cu")
		(net "SSD1_PERST_N")
	)
	(segment
		(start 7.661148 -403.437852)
		(end 7.661148 -417.153852)
		(width 0.17145)
		(layer "F.Cu")
		(net "SSD1_PERST_N")
	)
	(segment
		(start 227.389944 -372.789958)
		(end 228.555042 -372.789958)
		(width 0.17145)
		(layer "F.Cu")
		(net "SSD1_PERST_N")
	)
	(segment
		(start 3.293364 -417.541964)
		(end 2.249932 -417.541964)
		(width 0.17145)
		(layer "F.Cu")
		(net "SSD1_PERST_N")
	)
	(segment
		(start 5.588 -418.229542)
		(end 3.980942 -418.229542)
		(width 0.17145)
		(layer "F.Cu")
		(net "SSD1_PERST_N")
	)
	(via
		(at 9.525 -401.574)
		(size 0.7112)
		(drill 0.3556)
		(layers "F.Cu" "B.Cu")
		(net "SSD1_PERST_N")
	)
	(via
		(at 228.9556 -372.3894)
		(size 0.508)
		(drill 0.254)
		(layers "F.Cu" "B.Cu")
		(net "SSD1_PERST_N")
	)
	(via
		(at 12.031472 -387.940042)
		(size 0.508)
		(drill 0.254)
		(layers "F.Cu" "B.Cu")
		(net "SSD1_PERST_N")
	)
	(segment
		(start 22.03196 -388.9502)
		(end 21.021802 -387.940042)
		(width 0.1524)
		(layer "In5.Cu")
		(net "SSD1_PERST_N")
	)
	(segment
		(start 224.282 -356.616)
		(end 225.942906 -354.955094)
		(width 0.1524)
		(layer "In5.Cu")
		(net "SSD1_PERST_N")
	)
	(segment
		(start 225.942906 -347.253306)
		(end 222.8596 -344.17)
		(width 0.1524)
		(layer "In5.Cu")
		(net "SSD1_PERST_N")
	)
	(segment
		(start 31.46298 -388.9502)
		(end 22.03196 -388.9502)
		(width 0.1524)
		(layer "In5.Cu")
		(net "SSD1_PERST_N")
	)
	(segment
		(start 228.9556 -372.3894)
		(end 224.282 -367.7158)
		(width 0.1524)
		(layer "In5.Cu")
		(net "SSD1_PERST_N")
	)
	(segment
		(start 125.46838 -344.17)
		(end 76.521818 -393.116562)
		(width 0.1524)
		(layer "In5.Cu")
		(net "SSD1_PERST_N")
	)
	(segment
		(start 222.8596 -344.17)
		(end 125.46838 -344.17)
		(width 0.1524)
		(layer "In5.Cu")
		(net "SSD1_PERST_N")
	)
	(segment
		(start 225.942906 -354.955094)
		(end 225.942906 -347.253306)
		(width 0.1524)
		(layer "In5.Cu")
		(net "SSD1_PERST_N")
	)
	(segment
		(start 35.629342 -393.116562)
		(end 31.46298 -388.9502)
		(width 0.1524)
		(layer "In5.Cu")
		(net "SSD1_PERST_N")
	)
	(segment
		(start 76.521818 -393.116562)
		(end 35.629342 -393.116562)
		(width 0.1524)
		(layer "In5.Cu")
		(net "SSD1_PERST_N")
	)
	(segment
		(start 21.021802 -387.940042)
		(end 12.031472 -387.940042)
		(width 0.1524)
		(layer "In5.Cu")
		(net "SSD1_PERST_N")
	)
	(segment
		(start 224.282 -367.7158)
		(end 224.282 -356.616)
		(width 0.1524)
		(layer "In5.Cu")
		(net "SSD1_PERST_N")
	)
	(segment
		(start 231.885998 -375.274078)
		(end 228.585014 -378.575062)
		(width 0.17145)
		(layer "F.Cu")
		(net "SSD1_CLK0_OE_N")
	)
	(segment
		(start 108.9025 -309.88)
		(end 108.966 -309.8165)
		(width 0.17145)
		(layer "F.Cu")
		(net "SSD1_CLK0_OE_N")
	)
	(segment
		(start 228.585014 -378.575062)
		(end 226.974908 -378.575062)
		(width 0.17145)
		(layer "F.Cu")
		(net "SSD1_CLK0_OE_N")
	)
	(segment
		(start 110.236 -309.8165)
		(end 129.457196 -309.8165)
		(width 0.17145)
		(layer "F.Cu")
		(net "SSD1_CLK0_OE_N")
	)
	(segment
		(start 229.07625 -359.96245)
		(end 231.885998 -362.772198)
		(width 0.17145)
		(layer "F.Cu")
		(net "SSD1_CLK0_OE_N")
	)
	(segment
		(start 107.8865 -309.88)
		(end 108.9025 -309.88)
		(width 0.17145)
		(layer "F.Cu")
		(net "SSD1_CLK0_OE_N")
	)
	(segment
		(start 179.603146 -359.96245)
		(end 229.07625 -359.96245)
		(width 0.17145)
		(layer "F.Cu")
		(net "SSD1_CLK0_OE_N")
	)
	(segment
		(start 129.457196 -309.8165)
		(end 179.603146 -359.96245)
		(width 0.17145)
		(layer "F.Cu")
		(net "SSD1_CLK0_OE_N")
	)
	(segment
		(start 231.885998 -362.772198)
		(end 231.885998 -375.274078)
		(width 0.17145)
		(layer "F.Cu")
		(net "SSD1_CLK0_OE_N")
	)
	(segment
		(start 110.236 -309.8165)
		(end 108.966 -309.8165)
		(width 0.17145)
		(layer "F.Cu")
		(net "SSD1_CLK0_OE_N")
	)
	(via
		(at 110.236 -309.8165)
		(size 0.7112)
		(drill 0.3556)
		(layers "F.Cu" "B.Cu")
		(net "SSD1_CLK0_OE_N")
	)
	(segment
		(start 197.583806 -498.667278)
		(end 195.386706 -498.667278)
		(width 0.17145)
		(layer "F.Cu")
		(net "SSD0_PWREN")
	)
	(segment
		(start 193.081656 -499.003828)
		(end 193.418206 -498.667278)
		(width 0.17145)
		(layer "F.Cu")
		(net "SSD0_PWREN")
	)
	(segment
		(start 9.1186 -433.324)
		(end 3.773932 -433.324)
		(width 0.17145)
		(layer "F.Cu")
		(net "SSD0_PWREN")
	)
	(segment
		(start 3.556 -433.541932)
		(end 2.249932 -433.541932)
		(width 0.17145)
		(layer "F.Cu")
		(net "SSD0_PWREN")
	)
	(segment
		(start 193.418206 -498.667278)
		(end 194.243706 -498.667278)
		(width 0.17145)
		(layer "F.Cu")
		(net "SSD0_PWREN")
	)
	(segment
		(start 195.386706 -498.667278)
		(end 194.243706 -498.667278)
		(width 0.17145)
		(layer "F.Cu")
		(net "SSD0_PWREN")
	)
	(segment
		(start 201.000106 -497.206778)
		(end 199.044306 -497.206778)
		(width 0.17145)
		(layer "F.Cu")
		(net "SSD0_PWREN")
	)
	(segment
		(start 3.773932 -433.324)
		(end 3.556 -433.541932)
		(width 0.17145)
		(layer "F.Cu")
		(net "SSD0_PWREN")
	)
	(segment
		(start 201.349356 -496.127278)
		(end 201.349356 -496.857528)
		(width 0.17145)
		(layer "F.Cu")
		(net "SSD0_PWREN")
	)
	(segment
		(start 192.02273 -499.943628)
		(end 193.081656 -499.943628)
		(width 0.17145)
		(layer "F.Cu")
		(net "SSD0_PWREN")
	)
	(segment
		(start 201.349356 -496.857528)
		(end 201.000106 -497.206778)
		(width 0.17145)
		(layer "F.Cu")
		(net "SSD0_PWREN")
	)
	(segment
		(start 193.081656 -499.943628)
		(end 193.081656 -499.003828)
		(width 0.17145)
		(layer "F.Cu")
		(net "SSD0_PWREN")
	)
	(segment
		(start 199.044306 -497.206778)
		(end 197.583806 -498.667278)
		(width 0.17145)
		(layer "F.Cu")
		(net "SSD0_PWREN")
	)
	(via
		(at 9.1186 -433.324)
		(size 0.508)
		(drill 0.254)
		(layers "F.Cu" "B.Cu")
		(net "SSD0_PWREN")
	)
	(via
		(at 34.798 -438.785)
		(size 0.508)
		(drill 0.254)
		(layers "F.Cu" "B.Cu")
		(net "SSD0_PWREN")
	)
	(via
		(at 192.02273 -499.943628)
		(size 0.508)
		(drill 0.254)
		(layers "F.Cu" "B.Cu")
		(net "SSD0_PWREN")
	)
	(via
		(at 30.988 -438.785)
		(size 0.7112)
		(drill 0.3556)
		(layers "F.Cu" "B.Cu")
		(net "SSD0_PWREN")
	)
	(segment
		(start 34.798 -438.785)
		(end 30.988 -438.785)
		(width 0.17145)
		(layer "B.Cu")
		(net "SSD0_PWREN")
	)
	(segment
		(start 21.793962 -438.19445)
		(end 24.93645 -438.19445)
		(width 0.17145)
		(layer "B.Cu")
		(net "SSD0_PWREN")
	)
	(segment
		(start 11.245342 -433.324)
		(end 15.29588 -437.374538)
		(width 0.17145)
		(layer "B.Cu")
		(net "SSD0_PWREN")
	)
	(segment
		(start 29.8196 -438.785)
		(end 30.988 -438.785)
		(width 0.17145)
		(layer "B.Cu")
		(net "SSD0_PWREN")
	)
	(segment
		(start 9.1186 -433.324)
		(end 11.245342 -433.324)
		(width 0.17145)
		(layer "B.Cu")
		(net "SSD0_PWREN")
	)
	(segment
		(start 20.974812 -437.3753)
		(end 21.793962 -438.19445)
		(width 0.17145)
		(layer "B.Cu")
		(net "SSD0_PWREN")
	)
	(segment
		(start 26.206196 -439.464196)
		(end 29.140404 -439.464196)
		(width 0.17145)
		(layer "B.Cu")
		(net "SSD0_PWREN")
	)
	(segment
		(start 24.93645 -438.19445)
		(end 26.206196 -439.464196)
		(width 0.17145)
		(layer "B.Cu")
		(net "SSD0_PWREN")
	)
	(segment
		(start 20.960842 -437.374538)
		(end 20.961604 -437.3753)
		(width 0.17145)
		(layer "B.Cu")
		(net "SSD0_PWREN")
	)
	(segment
		(start 20.961604 -437.3753)
		(end 20.974812 -437.3753)
		(width 0.17145)
		(layer "B.Cu")
		(net "SSD0_PWREN")
	)
	(segment
		(start 15.29588 -437.374538)
		(end 20.960842 -437.374538)
		(width 0.17145)
		(layer "B.Cu")
		(net "SSD0_PWREN")
	)
	(segment
		(start 29.140404 -439.464196)
		(end 29.8196 -438.785)
		(width 0.17145)
		(layer "B.Cu")
		(net "SSD0_PWREN")
	)
	(segment
		(start 231.6988 -486.3592)
		(end 226.8474 -491.2106)
		(width 0.1524)
		(layer "In5.Cu")
		(net "SSD0_PWREN")
	)
	(segment
		(start 216.3318 -443.9158)
		(end 219.01531 -446.59931)
		(width 0.1524)
		(layer "In5.Cu")
		(net "SSD0_PWREN")
	)
	(segment
		(start 172.593 -429.768)
		(end 186.7408 -443.9158)
		(width 0.1524)
		(layer "In5.Cu")
		(net "SSD0_PWREN")
	)
	(segment
		(start 192.274952 -500.19585)
		(end 192.02273 -499.943628)
		(width 0.1524)
		(layer "In5.Cu")
		(net "SSD0_PWREN")
	)
	(segment
		(start 65.08242 -438.3024)
		(end 67.69862 -440.9186)
		(width 0.1524)
		(layer "In5.Cu")
		(net "SSD0_PWREN")
	)
	(segment
		(start 106.299 -444.119)
		(end 120.65 -429.768)
		(width 0.1524)
		(layer "In5.Cu")
		(net "SSD0_PWREN")
	)
	(segment
		(start 231.6988 -455.73442)
		(end 231.6988 -486.3592)
		(width 0.1524)
		(layer "In5.Cu")
		(net "SSD0_PWREN")
	)
	(segment
		(start 218.7956 -499.0592)
		(end 217.65895 -500.19585)
		(width 0.1524)
		(layer "In5.Cu")
		(net "SSD0_PWREN")
	)
	(segment
		(start 92.445078 -444.119)
		(end 106.299 -444.119)
		(width 0.1524)
		(layer "In5.Cu")
		(net "SSD0_PWREN")
	)
	(segment
		(start 85.65134 -445.4144)
		(end 91.149678 -445.4144)
		(width 0.1524)
		(layer "In5.Cu")
		(net "SSD0_PWREN")
	)
	(segment
		(start 120.65 -429.768)
		(end 172.593 -429.768)
		(width 0.1524)
		(layer "In5.Cu")
		(net "SSD0_PWREN")
	)
	(segment
		(start 186.7408 -443.9158)
		(end 216.3318 -443.9158)
		(width 0.1524)
		(layer "In5.Cu")
		(net "SSD0_PWREN")
	)
	(segment
		(start 84.35594 -444.119)
		(end 85.65134 -445.4144)
		(width 0.1524)
		(layer "In5.Cu")
		(net "SSD0_PWREN")
	)
	(segment
		(start 67.69862 -440.9186)
		(end 76.42733 -440.9186)
		(width 0.1524)
		(layer "In5.Cu")
		(net "SSD0_PWREN")
	)
	(segment
		(start 76.42733 -440.9186)
		(end 79.62773 -444.119)
		(width 0.1524)
		(layer "In5.Cu")
		(net "SSD0_PWREN")
	)
	(segment
		(start 54.03342 -438.3024)
		(end 65.08242 -438.3024)
		(width 0.1524)
		(layer "In5.Cu")
		(net "SSD0_PWREN")
	)
	(segment
		(start 91.149678 -445.4144)
		(end 92.445078 -444.119)
		(width 0.1524)
		(layer "In5.Cu")
		(net "SSD0_PWREN")
	)
	(segment
		(start 53.57622 -437.8452)
		(end 54.03342 -438.3024)
		(width 0.1524)
		(layer "In5.Cu")
		(net "SSD0_PWREN")
	)
	(segment
		(start 79.62773 -444.119)
		(end 84.35594 -444.119)
		(width 0.1524)
		(layer "In5.Cu")
		(net "SSD0_PWREN")
	)
	(segment
		(start 219.01531 -446.59931)
		(end 222.56369 -446.59931)
		(width 0.1524)
		(layer "In5.Cu")
		(net "SSD0_PWREN")
	)
	(segment
		(start 222.8342 -499.0592)
		(end 218.7956 -499.0592)
		(width 0.1524)
		(layer "In5.Cu")
		(net "SSD0_PWREN")
	)
	(segment
		(start 217.65895 -500.19585)
		(end 192.274952 -500.19585)
		(width 0.1524)
		(layer "In5.Cu")
		(net "SSD0_PWREN")
	)
	(segment
		(start 226.8474 -495.046)
		(end 222.8342 -499.0592)
		(width 0.1524)
		(layer "In5.Cu")
		(net "SSD0_PWREN")
	)
	(segment
		(start 226.8474 -491.2106)
		(end 226.8474 -495.046)
		(width 0.1524)
		(layer "In5.Cu")
		(net "SSD0_PWREN")
	)
	(segment
		(start 34.798 -438.785)
		(end 37.465 -438.785)
		(width 0.1524)
		(layer "In5.Cu")
		(net "SSD0_PWREN")
	)
	(segment
		(start 37.465 -438.785)
		(end 38.4048 -437.8452)
		(width 0.1524)
		(layer "In5.Cu")
		(net "SSD0_PWREN")
	)
	(segment
		(start 222.56369 -446.59931)
		(end 231.6988 -455.73442)
		(width 0.1524)
		(layer "In5.Cu")
		(net "SSD0_PWREN")
	)
	(segment
		(start 38.4048 -437.8452)
		(end 53.57622 -437.8452)
		(width 0.1524)
		(layer "In5.Cu")
		(net "SSD0_PWREN")
	)
	(segment
		(start 228.501194 -475.790006)
		(end 228.9048 -475.3864)
		(width 0.17145)
		(layer "F.Cu")
		(net "SSD0_PERST_N")
	)
	(segment
		(start 227.389944 -475.790006)
		(end 228.501194 -475.790006)
		(width 0.17145)
		(layer "F.Cu")
		(net "SSD0_PERST_N")
	)
	(segment
		(start 8.213598 -417.382706)
		(end 8.213598 -405.45258)
		(width 0.17145)
		(layer "F.Cu")
		(net "SSD0_PERST_N")
	)
	(segment
		(start 8.213598 -405.45258)
		(end 9.88695 -403.779228)
		(width 0.17145)
		(layer "F.Cu")
		(net "SSD0_PERST_N")
	)
	(segment
		(start 227.389944 -474.99016)
		(end 228.50856 -474.99016)
		(width 0.17145)
		(layer "F.Cu")
		(net "SSD0_PERST_N")
	)
	(segment
		(start 7.910322 -417.685982)
		(end 8.213598 -417.382706)
		(width 0.17145)
		(layer "F.Cu")
		(net "SSD0_PERST_N")
	)
	(segment
		(start 2.249932 -418.34181)
		(end 3.6322 -418.34181)
		(width 0.17145)
		(layer "F.Cu")
		(net "SSD0_PERST_N")
	)
	(segment
		(start 228.50856 -474.99016)
		(end 228.9048 -475.3864)
		(width 0.17145)
		(layer "F.Cu")
		(net "SSD0_PERST_N")
	)
	(segment
		(start 3.818382 -418.527992)
		(end 7.092696 -418.527992)
		(width 0.17145)
		(layer "F.Cu")
		(net "SSD0_PERST_N")
	)
	(segment
		(start 7.910322 -417.710366)
		(end 7.910322 -417.685982)
		(width 0.17145)
		(layer "F.Cu")
		(net "SSD0_PERST_N")
	)
	(segment
		(start 3.6322 -418.34181)
		(end 3.818382 -418.527992)
		(width 0.17145)
		(layer "F.Cu")
		(net "SSD0_PERST_N")
	)
	(segment
		(start 9.88695 -403.779228)
		(end 10.901426 -402.764752)
		(width 0.17145)
		(layer "F.Cu")
		(net "SSD0_PERST_N")
	)
	(segment
		(start 10.901426 -402.764752)
		(end 10.901426 -402.12645)
		(width 0.17145)
		(layer "F.Cu")
		(net "SSD0_PERST_N")
	)
	(segment
		(start 7.092696 -418.527992)
		(end 7.910322 -417.710366)
		(width 0.17145)
		(layer "F.Cu")
		(net "SSD0_PERST_N")
	)
	(via
		(at 10.901426 -402.12645)
		(size 0.508)
		(drill 0.254)
		(layers "F.Cu" "B.Cu")
		(net "SSD0_PERST_N")
	)
	(via
		(at 228.9048 -475.3864)
		(size 0.508)
		(drill 0.254)
		(layers "F.Cu" "B.Cu")
		(net "SSD0_PERST_N")
	)
	(via
		(at 9.88695 -403.779228)
		(size 0.7112)
		(drill 0.3556)
		(layers "F.Cu" "B.Cu")
		(net "SSD0_PERST_N")
	)
	(via
		(at 34.671 -440.182)
		(size 0.508)
		(drill 0.254)
		(layers "F.Cu" "B.Cu")
		(net "SSD0_PERST_N")
	)
	(segment
		(start 25.081992 -439.9026)
		(end 21.939504 -439.9026)
		(width 0.17145)
		(layer "B.Cu")
		(net "SSD0_PERST_N")
	)
	(segment
		(start 25.748488 -440.569096)
		(end 25.081992 -439.9026)
		(width 0.17145)
		(layer "B.Cu")
		(net "SSD0_PERST_N")
	)
	(segment
		(start 7.244842 -423.154094)
		(end 7.244842 -419.178994)
		(width 0.17145)
		(layer "B.Cu")
		(net "SSD0_PERST_N")
	)
	(segment
		(start 14.153896 -438.4802)
		(end 10.673334 -434.999638)
		(width 0.17145)
		(layer "B.Cu")
		(net "SSD0_PERST_N")
	)
	(segment
		(start 32.004 -440.182)
		(end 31.616904 -440.569096)
		(width 0.17145)
		(layer "B.Cu")
		(net "SSD0_PERST_N")
	)
	(segment
		(start 21.939504 -439.9026)
		(end 20.517104 -438.4802)
		(width 0.17145)
		(layer "B.Cu")
		(net "SSD0_PERST_N")
	)
	(segment
		(start 8.568436 -404.45944)
		(end 10.901426 -402.12645)
		(width 0.17145)
		(layer "B.Cu")
		(net "SSD0_PERST_N")
	)
	(segment
		(start 8.062468 -423.97172)
		(end 7.244842 -423.154094)
		(width 0.17145)
		(layer "B.Cu")
		(net "SSD0_PERST_N")
	)
	(segment
		(start 8.700008 -434.999638)
		(end 8.062468 -434.362098)
		(width 0.17145)
		(layer "B.Cu")
		(net "SSD0_PERST_N")
	)
	(segment
		(start 34.671 -440.182)
		(end 32.004 -440.182)
		(width 0.17145)
		(layer "B.Cu")
		(net "SSD0_PERST_N")
	)
	(segment
		(start 8.568436 -417.8554)
		(end 8.568436 -404.45944)
		(width 0.17145)
		(layer "B.Cu")
		(net "SSD0_PERST_N")
	)
	(segment
		(start 8.062468 -434.362098)
		(end 8.062468 -423.97172)
		(width 0.17145)
		(layer "B.Cu")
		(net "SSD0_PERST_N")
	)
	(segment
		(start 7.244842 -419.178994)
		(end 8.568436 -417.8554)
		(width 0.17145)
		(layer "B.Cu")
		(net "SSD0_PERST_N")
	)
	(segment
		(start 20.517104 -438.4802)
		(end 14.153896 -438.4802)
		(width 0.17145)
		(layer "B.Cu")
		(net "SSD0_PERST_N")
	)
	(segment
		(start 10.673334 -434.999638)
		(end 8.700008 -434.999638)
		(width 0.17145)
		(layer "B.Cu")
		(net "SSD0_PERST_N")
	)
	(segment
		(start 31.616904 -440.569096)
		(end 25.748488 -440.569096)
		(width 0.17145)
		(layer "B.Cu")
		(net "SSD0_PERST_N")
	)
	(segment
		(start 38.84676 -438.912)
		(end 37.57676 -440.182)
		(width 0.1524)
		(layer "In5.Cu")
		(net "SSD0_PERST_N")
	)
	(segment
		(start 37.57676 -440.182)
		(end 34.671 -440.182)
		(width 0.1524)
		(layer "In5.Cu")
		(net "SSD0_PERST_N")
	)
	(segment
		(start 64.64046 -439.3692)
		(end 53.591206 -439.3692)
		(width 0.1524)
		(layer "In5.Cu")
		(net "SSD0_PERST_N")
	)
	(segment
		(start 83.909916 -445.1858)
		(end 78.826614 -445.1858)
		(width 0.1524)
		(layer "In5.Cu")
		(net "SSD0_PERST_N")
	)
	(segment
		(start 75.626214 -441.9854)
		(end 67.25666 -441.9854)
		(width 0.1524)
		(layer "In5.Cu")
		(net "SSD0_PERST_N")
	)
	(segment
		(start 223.651064 -452.743824)
		(end 215.88984 -444.9826)
		(width 0.1524)
		(layer "In5.Cu")
		(net "SSD0_PERST_N")
	)
	(segment
		(start 91.021408 -447.05143)
		(end 85.775546 -447.05143)
		(width 0.1524)
		(layer "In5.Cu")
		(net "SSD0_PERST_N")
	)
	(segment
		(start 172.15104 -430.8348)
		(end 121.09196 -430.8348)
		(width 0.1524)
		(layer "In5.Cu")
		(net "SSD0_PERST_N")
	)
	(segment
		(start 228.9048 -475.3864)
		(end 223.651064 -470.132664)
		(width 0.1524)
		(layer "In5.Cu")
		(net "SSD0_PERST_N")
	)
	(segment
		(start 85.775546 -447.05143)
		(end 83.909916 -445.1858)
		(width 0.1524)
		(layer "In5.Cu")
		(net "SSD0_PERST_N")
	)
	(segment
		(start 186.29884 -444.9826)
		(end 172.15104 -430.8348)
		(width 0.1524)
		(layer "In5.Cu")
		(net "SSD0_PERST_N")
	)
	(segment
		(start 53.591206 -439.3692)
		(end 53.134006 -438.912)
		(width 0.1524)
		(layer "In5.Cu")
		(net "SSD0_PERST_N")
	)
	(segment
		(start 121.09196 -430.8348)
		(end 106.74096 -445.1858)
		(width 0.1524)
		(layer "In5.Cu")
		(net "SSD0_PERST_N")
	)
	(segment
		(start 223.651064 -470.132664)
		(end 223.651064 -452.743824)
		(width 0.1524)
		(layer "In5.Cu")
		(net "SSD0_PERST_N")
	)
	(segment
		(start 106.74096 -445.1858)
		(end 92.887038 -445.1858)
		(width 0.1524)
		(layer "In5.Cu")
		(net "SSD0_PERST_N")
	)
	(segment
		(start 67.25666 -441.9854)
		(end 64.64046 -439.3692)
		(width 0.1524)
		(layer "In5.Cu")
		(net "SSD0_PERST_N")
	)
	(segment
		(start 53.134006 -438.912)
		(end 38.84676 -438.912)
		(width 0.1524)
		(layer "In5.Cu")
		(net "SSD0_PERST_N")
	)
	(segment
		(start 215.88984 -444.9826)
		(end 186.29884 -444.9826)
		(width 0.1524)
		(layer "In5.Cu")
		(net "SSD0_PERST_N")
	)
	(segment
		(start 78.826614 -445.1858)
		(end 75.626214 -441.9854)
		(width 0.1524)
		(layer "In5.Cu")
		(net "SSD0_PERST_N")
	)
	(segment
		(start 92.887038 -445.1858)
		(end 91.021408 -447.05143)
		(width 0.1524)
		(layer "In5.Cu")
		(net "SSD0_PERST_N")
	)
	(segment
		(start 178.273202 -436.356506)
		(end 110.314994 -436.356506)
		(width 0.17145)
		(layer "F.Cu")
		(net "SSD0_CLK0_OE_N")
	)
	(segment
		(start 107.8865 -436.499)
		(end 108.9025 -436.499)
		(width 0.17145)
		(layer "F.Cu")
		(net "SSD0_CLK0_OE_N")
	)
	(segment
		(start 214.05977 -449.834)
		(end 191.750696 -449.834)
		(width 0.17145)
		(layer "F.Cu")
		(net "SSD0_CLK0_OE_N")
	)
	(segment
		(start 229.743 -462.788)
		(end 222.25 -462.788)
		(width 0.17145)
		(layer "F.Cu")
		(net "SSD0_CLK0_OE_N")
	)
	(segment
		(start 220.797628 -456.571858)
		(end 214.05977 -449.834)
		(width 0.17145)
		(layer "F.Cu")
		(net "SSD0_CLK0_OE_N")
	)
	(segment
		(start 231.73055 -478.429574)
		(end 231.73055 -464.77555)
		(width 0.17145)
		(layer "F.Cu")
		(net "SSD0_CLK0_OE_N")
	)
	(segment
		(start 226.974908 -481.57511)
		(end 228.585014 -481.57511)
		(width 0.17145)
		(layer "F.Cu")
		(net "SSD0_CLK0_OE_N")
	)
	(segment
		(start 191.750696 -449.834)
		(end 178.273202 -436.356506)
		(width 0.17145)
		(layer "F.Cu")
		(net "SSD0_CLK0_OE_N")
	)
	(segment
		(start 228.585014 -481.57511)
		(end 231.73055 -478.429574)
		(width 0.17145)
		(layer "F.Cu")
		(net "SSD0_CLK0_OE_N")
	)
	(segment
		(start 222.25 -462.788)
		(end 220.797628 -461.335628)
		(width 0.17145)
		(layer "F.Cu")
		(net "SSD0_CLK0_OE_N")
	)
	(segment
		(start 110.236 -436.4355)
		(end 108.966 -436.4355)
		(width 0.17145)
		(layer "F.Cu")
		(net "SSD0_CLK0_OE_N")
	)
	(segment
		(start 220.797628 -461.335628)
		(end 220.797628 -456.571858)
		(width 0.17145)
		(layer "F.Cu")
		(net "SSD0_CLK0_OE_N")
	)
	(segment
		(start 231.73055 -464.77555)
		(end 229.743 -462.788)
		(width 0.17145)
		(layer "F.Cu")
		(net "SSD0_CLK0_OE_N")
	)
	(segment
		(start 108.9025 -436.499)
		(end 108.966 -436.4355)
		(width 0.17145)
		(layer "F.Cu")
		(net "SSD0_CLK0_OE_N")
	)
	(segment
		(start 110.314994 -436.356506)
		(end 110.236 -436.4355)
		(width 0.17145)
		(layer "F.Cu")
		(net "SSD0_CLK0_OE_N")
	)
	(via
		(at 110.236 -436.4355)
		(size 0.7112)
		(drill 0.3556)
		(layers "F.Cu" "B.Cu")
		(net "SSD0_CLK0_OE_N")
	)
	(segment
		(start 87.5665 -90.4875)
		(end 87.5665 -89.535)
		(width 0.17145)
		(layer "F.Cu")
		(net "SSD_PRSNT9")
	)
	(segment
		(start 91.23045 -97.17659)
		(end 91.23045 -96.18345)
		(width 0.17145)
		(layer "F.Cu")
		(net "SSD_PRSNT9")
	)
	(segment
		(start 91.23045 -96.18345)
		(end 88.590628 -93.543628)
		(width 0.17145)
		(layer "F.Cu")
		(net "SSD_PRSNT9")
	)
	(segment
		(start 87.63 -89.4715)
		(end 87.5665 -89.535)
		(width 0.17145)
		(layer "F.Cu")
		(net "SSD_PRSNT9")
	)
	(segment
		(start 88.590628 -91.511628)
		(end 87.884 -90.805)
		(width 0.17145)
		(layer "F.Cu")
		(net "SSD_PRSNT9")
	)
	(segment
		(start 87.884 -90.805)
		(end 87.5665 -90.4875)
		(width 0.17145)
		(layer "F.Cu")
		(net "SSD_PRSNT9")
	)
	(segment
		(start 87.63 -88.5825)
		(end 87.63 -89.4715)
		(width 0.17145)
		(layer "F.Cu")
		(net "SSD_PRSNT9")
	)
	(segment
		(start 88.590628 -93.543628)
		(end 88.590628 -91.511628)
		(width 0.17145)
		(layer "F.Cu")
		(net "SSD_PRSNT9")
	)
	(via
		(at 87.884 -90.805)
		(size 0.7112)
		(drill 0.3556)
		(layers "F.Cu" "B.Cu")
		(net "SSD_PRSNT9")
	)
	(segment
		(start 98.226372 -111.688372)
		(end 98.226372 -109.219492)
		(width 0.17145)
		(layer "F.Cu")
		(net "SSD_PRSNT8")
	)
	(segment
		(start 98.933 -112.395)
		(end 98.226372 -111.688372)
		(width 0.17145)
		(layer "F.Cu")
		(net "SSD_PRSNT8")
	)
	(segment
		(start 96.23044 -107.22356)
		(end 96.23044 -106.02341)
		(width 0.17145)
		(layer "F.Cu")
		(net "SSD_PRSNT8")
	)
	(segment
		(start 98.226372 -109.219492)
		(end 96.23044 -107.22356)
		(width 0.17145)
		(layer "F.Cu")
		(net "SSD_PRSNT8")
	)
	(segment
		(start 99.187 -114.6175)
		(end 99.187 -113.7285)
		(width 0.17145)
		(layer "F.Cu")
		(net "SSD_PRSNT8")
	)
	(segment
		(start 98.933 -112.395)
		(end 99.2505 -112.7125)
		(width 0.17145)
		(layer "F.Cu")
		(net "SSD_PRSNT8")
	)
	(segment
		(start 99.187 -113.7285)
		(end 99.2505 -113.665)
		(width 0.17145)
		(layer "F.Cu")
		(net "SSD_PRSNT8")
	)
	(segment
		(start 99.2505 -112.7125)
		(end 99.2505 -113.665)
		(width 0.17145)
		(layer "F.Cu")
		(net "SSD_PRSNT8")
	)
	(via
		(at 98.933 -112.395)
		(size 0.7112)
		(drill 0.3556)
		(layers "F.Cu" "B.Cu")
		(net "SSD_PRSNT8")
	)
	(segment
		(start 98.21545 -220.89745)
		(end 98.933 -221.615)
		(width 0.17145)
		(layer "F.Cu")
		(net "SSD_PRSNT7")
	)
	(segment
		(start 98.21545 -218.42857)
		(end 98.21545 -220.89745)
		(width 0.17145)
		(layer "F.Cu")
		(net "SSD_PRSNT7")
	)
	(segment
		(start 99.187 -223.8375)
		(end 99.187 -222.9485)
		(width 0.17145)
		(layer "F.Cu")
		(net "SSD_PRSNT7")
	)
	(segment
		(start 98.933 -221.615)
		(end 99.2505 -221.9325)
		(width 0.17145)
		(layer "F.Cu")
		(net "SSD_PRSNT7")
	)
	(segment
		(start 96.23044 -216.44356)
		(end 98.21545 -218.42857)
		(width 0.17145)
		(layer "F.Cu")
		(net "SSD_PRSNT7")
	)
	(segment
		(start 96.23044 -215.24341)
		(end 96.23044 -216.44356)
		(width 0.17145)
		(layer "F.Cu")
		(net "SSD_PRSNT7")
	)
	(segment
		(start 99.187 -222.9485)
		(end 99.2505 -222.885)
		(width 0.17145)
		(layer "F.Cu")
		(net "SSD_PRSNT7")
	)
	(segment
		(start 99.2505 -221.9325)
		(end 99.2505 -222.885)
		(width 0.17145)
		(layer "F.Cu")
		(net "SSD_PRSNT7")
	)
	(via
		(at 98.933 -221.615)
		(size 0.7112)
		(drill 0.3556)
		(layers "F.Cu" "B.Cu")
		(net "SSD_PRSNT7")
	)
	(segment
		(start 98.171 -312.74512)
		(end 98.171 -315.214)
		(width 0.17145)
		(layer "F.Cu")
		(net "SSD_PRSNT6")
	)
	(segment
		(start 96.23044 -310.80456)
		(end 98.171 -312.74512)
		(width 0.17145)
		(layer "F.Cu")
		(net "SSD_PRSNT6")
	)
	(segment
		(start 96.23044 -309.60441)
		(end 96.23044 -310.80456)
		(width 0.17145)
		(layer "F.Cu")
		(net "SSD_PRSNT6")
	)
	(segment
		(start 99.187 -318.1985)
		(end 99.187 -317.3095)
		(width 0.17145)
		(layer "F.Cu")
		(net "SSD_PRSNT6")
	)
	(segment
		(start 98.933 -315.976)
		(end 99.2505 -316.2935)
		(width 0.17145)
		(layer "F.Cu")
		(net "SSD_PRSNT6")
	)
	(segment
		(start 98.171 -315.214)
		(end 98.933 -315.976)
		(width 0.17145)
		(layer "F.Cu")
		(net "SSD_PRSNT6")
	)
	(segment
		(start 99.2505 -316.2935)
		(end 99.2505 -317.246)
		(width 0.17145)
		(layer "F.Cu")
		(net "SSD_PRSNT6")
	)
	(segment
		(start 99.187 -317.3095)
		(end 99.2505 -317.246)
		(width 0.17145)
		(layer "F.Cu")
		(net "SSD_PRSNT6")
	)
	(via
		(at 98.933 -315.976)
		(size 0.7112)
		(drill 0.3556)
		(layers "F.Cu" "B.Cu")
		(net "SSD_PRSNT6")
	)
	(segment
		(start 90.17 -444.8175)
		(end 90.17 -443.9285)
		(width 0.17145)
		(layer "F.Cu")
		(net "SSD_PRSNT5")
	)
	(segment
		(start 90.17 -443.9285)
		(end 90.2335 -443.865)
		(width 0.17145)
		(layer "F.Cu")
		(net "SSD_PRSNT5")
	)
	(segment
		(start 89.154 -439.674)
		(end 89.154 -441.833)
		(width 0.17145)
		(layer "F.Cu")
		(net "SSD_PRSNT5")
	)
	(segment
		(start 89.916 -442.595)
		(end 90.2335 -442.9125)
		(width 0.17145)
		(layer "F.Cu")
		(net "SSD_PRSNT5")
	)
	(segment
		(start 89.154 -441.833)
		(end 89.916 -442.595)
		(width 0.17145)
		(layer "F.Cu")
		(net "SSD_PRSNT5")
	)
	(segment
		(start 91.72956 -436.22341)
		(end 91.72956 -437.09844)
		(width 0.17145)
		(layer "F.Cu")
		(net "SSD_PRSNT5")
	)
	(segment
		(start 90.2335 -442.9125)
		(end 90.2335 -443.865)
		(width 0.17145)
		(layer "F.Cu")
		(net "SSD_PRSNT5")
	)
	(segment
		(start 91.72956 -437.09844)
		(end 89.154 -439.674)
		(width 0.17145)
		(layer "F.Cu")
		(net "SSD_PRSNT5")
	)
	(via
		(at 89.916 -442.595)
		(size 0.7112)
		(drill 0.3556)
		(layers "F.Cu" "B.Cu")
		(net "SSD_PRSNT5")
	)
	(segment
		(start 94.9325 -199.7329)
		(end 95.2754 -200.0758)
		(width 0.17145)
		(layer "F.Cu")
		(net "SSD_PRSNT4")
	)
	(segment
		(start 95.6056 -203.74356)
		(end 95.73006 -203.86802)
		(width 0.17145)
		(layer "F.Cu")
		(net "SSD_PRSNT4")
	)
	(segment
		(start 95.2754 -200.0758)
		(end 95.6056 -200.406)
		(width 0.17145)
		(layer "F.Cu")
		(net "SSD_PRSNT4")
	)
	(segment
		(start 95.6056 -200.406)
		(end 95.6056 -203.74356)
		(width 0.17145)
		(layer "F.Cu")
		(net "SSD_PRSNT4")
	)
	(segment
		(start 95.73006 -203.86802)
		(end 95.73006 -206.39659)
		(width 0.17145)
		(layer "F.Cu")
		(net "SSD_PRSNT4")
	)
	(segment
		(start 94.996 -197.8025)
		(end 94.996 -198.6915)
		(width 0.17145)
		(layer "F.Cu")
		(net "SSD_PRSNT4")
	)
	(segment
		(start 94.996 -198.6915)
		(end 94.9325 -198.755)
		(width 0.17145)
		(layer "F.Cu")
		(net "SSD_PRSNT4")
	)
	(segment
		(start 94.9325 -198.755)
		(end 94.9325 -199.7329)
		(width 0.17145)
		(layer "F.Cu")
		(net "SSD_PRSNT4")
	)
	(via
		(at 95.2754 -200.0758)
		(size 0.7112)
		(drill 0.3556)
		(layers "F.Cu" "B.Cu")
		(net "SSD_PRSNT4")
	)
	(segment
		(start 99.60356 -208.56956)
		(end 98.40341 -208.56956)
		(width 0.17145)
		(layer "F.Cu")
		(net "SSD_PRSNT3")
	)
	(segment
		(start 104.775 -205.867)
		(end 105.0925 -205.5495)
		(width 0.17145)
		(layer "F.Cu")
		(net "SSD_PRSNT3")
	)
	(segment
		(start 106.9975 -205.613)
		(end 106.1085 -205.613)
		(width 0.17145)
		(layer "F.Cu")
		(net "SSD_PRSNT3")
	)
	(segment
		(start 105.0925 -205.5495)
		(end 106.045 -205.5495)
		(width 0.17145)
		(layer "F.Cu")
		(net "SSD_PRSNT3")
	)
	(segment
		(start 104.775 -205.867)
		(end 104.14 -206.502)
		(width 0.17145)
		(layer "F.Cu")
		(net "SSD_PRSNT3")
	)
	(segment
		(start 106.1085 -205.613)
		(end 106.045 -205.5495)
		(width 0.17145)
		(layer "F.Cu")
		(net "SSD_PRSNT3")
	)
	(segment
		(start 101.67112 -206.502)
		(end 99.60356 -208.56956)
		(width 0.17145)
		(layer "F.Cu")
		(net "SSD_PRSNT3")
	)
	(segment
		(start 104.14 -206.502)
		(end 101.67112 -206.502)
		(width 0.17145)
		(layer "F.Cu")
		(net "SSD_PRSNT3")
	)
	(via
		(at 104.775 -205.867)
		(size 0.7112)
		(drill 0.3556)
		(layers "F.Cu" "B.Cu")
		(net "SSD_PRSNT3")
	)
	(segment
		(start 96.647 -293.0525)
		(end 96.5835 -293.116)
		(width 0.17145)
		(layer "F.Cu")
		(net "SSD_PRSNT2")
	)
	(segment
		(start 96.901 -294.386)
		(end 97.3328 -294.8178)
		(width 0.17145)
		(layer "F.Cu")
		(net "SSD_PRSNT2")
	)
	(segment
		(start 96.5835 -293.116)
		(end 96.5835 -294.0685)
		(width 0.17145)
		(layer "F.Cu")
		(net "SSD_PRSNT2")
	)
	(segment
		(start 97.3328 -297.94962)
		(end 95.73006 -299.55236)
		(width 0.17145)
		(layer "F.Cu")
		(net "SSD_PRSNT2")
	)
	(segment
		(start 95.73006 -299.55236)
		(end 95.73006 -300.75759)
		(width 0.17145)
		(layer "F.Cu")
		(net "SSD_PRSNT2")
	)
	(segment
		(start 96.647 -292.1635)
		(end 96.647 -293.0525)
		(width 0.17145)
		(layer "F.Cu")
		(net "SSD_PRSNT2")
	)
	(segment
		(start 96.5835 -294.0685)
		(end 96.901 -294.386)
		(width 0.17145)
		(layer "F.Cu")
		(net "SSD_PRSNT2")
	)
	(segment
		(start 97.3328 -294.8178)
		(end 97.3328 -297.94962)
		(width 0.17145)
		(layer "F.Cu")
		(net "SSD_PRSNT2")
	)
	(via
		(at 96.901 -294.386)
		(size 0.7112)
		(drill 0.3556)
		(layers "F.Cu" "B.Cu")
		(net "SSD_PRSNT2")
	)
	(segment
		(start 96.647 -89.4715)
		(end 96.5835 -89.535)
		(width 0.17145)
		(layer "F.Cu")
		(net "SSD_PRSNT14")
	)
	(segment
		(start 96.647 -88.5825)
		(end 96.647 -89.4715)
		(width 0.17145)
		(layer "F.Cu")
		(net "SSD_PRSNT14")
	)
	(segment
		(start 97.282 -91.186)
		(end 96.901 -90.805)
		(width 0.17145)
		(layer "F.Cu")
		(net "SSD_PRSNT14")
	)
	(segment
		(start 97.282 -94.44482)
		(end 97.282 -91.186)
		(width 0.17145)
		(layer "F.Cu")
		(net "SSD_PRSNT14")
	)
	(segment
		(start 95.73006 -97.17659)
		(end 95.73006 -95.99676)
		(width 0.17145)
		(layer "F.Cu")
		(net "SSD_PRSNT14")
	)
	(segment
		(start 95.73006 -95.99676)
		(end 97.282 -94.44482)
		(width 0.17145)
		(layer "F.Cu")
		(net "SSD_PRSNT14")
	)
	(segment
		(start 96.5835 -89.535)
		(end 96.5835 -90.4875)
		(width 0.17145)
		(layer "F.Cu")
		(net "SSD_PRSNT14")
	)
	(segment
		(start 96.5835 -90.4875)
		(end 96.901 -90.805)
		(width 0.17145)
		(layer "F.Cu")
		(net "SSD_PRSNT14")
	)
	(via
		(at 96.901 -90.805)
		(size 0.7112)
		(drill 0.3556)
		(layers "F.Cu" "B.Cu")
		(net "SSD_PRSNT14")
	)
	(segment
		(start 90.17 -113.7285)
		(end 90.2335 -113.665)
		(width 0.17145)
		(layer "F.Cu")
		(net "SSD_PRSNT13")
	)
	(segment
		(start 89.209372 -111.688372)
		(end 89.916 -112.395)
		(width 0.17145)
		(layer "F.Cu")
		(net "SSD_PRSNT13")
	)
	(segment
		(start 90.17 -114.6175)
		(end 90.17 -113.7285)
		(width 0.17145)
		(layer "F.Cu")
		(net "SSD_PRSNT13")
	)
	(segment
		(start 89.209372 -109.520228)
		(end 89.209372 -111.688372)
		(width 0.17145)
		(layer "F.Cu")
		(net "SSD_PRSNT13")
	)
	(segment
		(start 91.72956 -106.02341)
		(end 91.72956 -107.00004)
		(width 0.17145)
		(layer "F.Cu")
		(net "SSD_PRSNT13")
	)
	(segment
		(start 90.2335 -112.7125)
		(end 90.2335 -113.665)
		(width 0.17145)
		(layer "F.Cu")
		(net "SSD_PRSNT13")
	)
	(segment
		(start 91.72956 -107.00004)
		(end 89.209372 -109.520228)
		(width 0.17145)
		(layer "F.Cu")
		(net "SSD_PRSNT13")
	)
	(segment
		(start 89.916 -112.395)
		(end 90.2335 -112.7125)
		(width 0.17145)
		(layer "F.Cu")
		(net "SSD_PRSNT13")
	)
	(via
		(at 89.916 -112.395)
		(size 0.7112)
		(drill 0.3556)
		(layers "F.Cu" "B.Cu")
		(net "SSD_PRSNT13")
	)
	(segment
		(start 91.72956 -216.24544)
		(end 89.209372 -218.765628)
		(width 0.17145)
		(layer "F.Cu")
		(net "SSD_PRSNT12")
	)
	(segment
		(start 90.17 -222.9485)
		(end 90.2335 -222.885)
		(width 0.17145)
		(layer "F.Cu")
		(net "SSD_PRSNT12")
	)
	(segment
		(start 89.209372 -220.908372)
		(end 89.916 -221.615)
		(width 0.17145)
		(layer "F.Cu")
		(net "SSD_PRSNT12")
	)
	(segment
		(start 90.2335 -221.9325)
		(end 90.2335 -222.885)
		(width 0.17145)
		(layer "F.Cu")
		(net "SSD_PRSNT12")
	)
	(segment
		(start 89.916 -221.615)
		(end 90.2335 -221.9325)
		(width 0.17145)
		(layer "F.Cu")
		(net "SSD_PRSNT12")
	)
	(segment
		(start 89.209372 -218.765628)
		(end 89.209372 -220.908372)
		(width 0.17145)
		(layer "F.Cu")
		(net "SSD_PRSNT12")
	)
	(segment
		(start 91.72956 -215.24341)
		(end 91.72956 -216.24544)
		(width 0.17145)
		(layer "F.Cu")
		(net "SSD_PRSNT12")
	)
	(segment
		(start 90.17 -223.8375)
		(end 90.17 -222.9485)
		(width 0.17145)
		(layer "F.Cu")
		(net "SSD_PRSNT12")
	)
	(via
		(at 89.916 -221.615)
		(size 0.7112)
		(drill 0.3556)
		(layers "F.Cu" "B.Cu")
		(net "SSD_PRSNT12")
	)
	(segment
		(start 90.17 -317.3095)
		(end 90.2335 -317.246)
		(width 0.17145)
		(layer "F.Cu")
		(net "SSD_PRSNT11")
	)
	(segment
		(start 89.916 -315.976)
		(end 90.2335 -316.2935)
		(width 0.17145)
		(layer "F.Cu")
		(net "SSD_PRSNT11")
	)
	(segment
		(start 89.154 -315.214)
		(end 89.916 -315.976)
		(width 0.17145)
		(layer "F.Cu")
		(net "SSD_PRSNT11")
	)
	(segment
		(start 89.154 -313.055)
		(end 89.154 -315.214)
		(width 0.17145)
		(layer "F.Cu")
		(net "SSD_PRSNT11")
	)
	(segment
		(start 90.17 -318.1985)
		(end 90.17 -317.3095)
		(width 0.17145)
		(layer "F.Cu")
		(net "SSD_PRSNT11")
	)
	(segment
		(start 91.72956 -310.47944)
		(end 89.154 -313.055)
		(width 0.17145)
		(layer "F.Cu")
		(net "SSD_PRSNT11")
	)
	(segment
		(start 90.2335 -316.2935)
		(end 90.2335 -317.246)
		(width 0.17145)
		(layer "F.Cu")
		(net "SSD_PRSNT11")
	)
	(segment
		(start 91.72956 -309.60441)
		(end 91.72956 -310.47944)
		(width 0.17145)
		(layer "F.Cu")
		(net "SSD_PRSNT11")
	)
	(via
		(at 89.916 -315.976)
		(size 0.7112)
		(drill 0.3556)
		(layers "F.Cu" "B.Cu")
		(net "SSD_PRSNT11")
	)
	(segment
		(start 87.884 -421.005)
		(end 87.5665 -420.6875)
		(width 0.17145)
		(layer "F.Cu")
		(net "SSD_PRSNT10")
	)
	(segment
		(start 87.884 -421.005)
		(end 88.590628 -421.711628)
		(width 0.17145)
		(layer "F.Cu")
		(net "SSD_PRSNT10")
	)
	(segment
		(start 87.63 -419.6715)
		(end 87.5665 -419.735)
		(width 0.17145)
		(layer "F.Cu")
		(net "SSD_PRSNT10")
	)
	(segment
		(start 88.590628 -423.537888)
		(end 91.23045 -426.17771)
		(width 0.17145)
		(layer "F.Cu")
		(net "SSD_PRSNT10")
	)
	(segment
		(start 91.23045 -426.17771)
		(end 91.23045 -427.37659)
		(width 0.17145)
		(layer "F.Cu")
		(net "SSD_PRSNT10")
	)
	(segment
		(start 88.590628 -421.711628)
		(end 88.590628 -423.537888)
		(width 0.17145)
		(layer "F.Cu")
		(net "SSD_PRSNT10")
	)
	(segment
		(start 87.5665 -420.6875)
		(end 87.5665 -419.735)
		(width 0.17145)
		(layer "F.Cu")
		(net "SSD_PRSNT10")
	)
	(segment
		(start 87.63 -418.7825)
		(end 87.63 -419.6715)
		(width 0.17145)
		(layer "F.Cu")
		(net "SSD_PRSNT10")
	)
	(via
		(at 87.884 -421.005)
		(size 0.7112)
		(drill 0.3556)
		(layers "F.Cu" "B.Cu")
		(net "SSD_PRSNT10")
	)
	(segment
		(start 106.9975 -307.848)
		(end 106.1085 -307.848)
		(width 0.17145)
		(layer "F.Cu")
		(net "SSD_PRSNT1")
	)
	(segment
		(start 104.394 -308.483)
		(end 100.95738 -308.483)
		(width 0.17145)
		(layer "F.Cu")
		(net "SSD_PRSNT1")
	)
	(segment
		(start 104.775 -308.102)
		(end 105.0925 -307.7845)
		(width 0.17145)
		(layer "F.Cu")
		(net "SSD_PRSNT1")
	)
	(segment
		(start 99.40544 -306.93106)
		(end 98.40341 -306.93106)
		(width 0.17145)
		(layer "F.Cu")
		(net "SSD_PRSNT1")
	)
	(segment
		(start 100.95738 -308.483)
		(end 99.40544 -306.93106)
		(width 0.17145)
		(layer "F.Cu")
		(net "SSD_PRSNT1")
	)
	(segment
		(start 104.775 -308.102)
		(end 104.394 -308.483)
		(width 0.17145)
		(layer "F.Cu")
		(net "SSD_PRSNT1")
	)
	(segment
		(start 106.1085 -307.848)
		(end 106.045 -307.7845)
		(width 0.17145)
		(layer "F.Cu")
		(net "SSD_PRSNT1")
	)
	(segment
		(start 105.0925 -307.7845)
		(end 106.045 -307.7845)
		(width 0.17145)
		(layer "F.Cu")
		(net "SSD_PRSNT1")
	)
	(via
		(at 104.775 -308.102)
		(size 0.7112)
		(drill 0.3556)
		(layers "F.Cu" "B.Cu")
		(net "SSD_PRSNT1")
	)
	(segment
		(start 104.775 -434.721)
		(end 105.0925 -434.4035)
		(width 0.17145)
		(layer "F.Cu")
		(net "SSD_PRSNT0")
	)
	(segment
		(start 105.0925 -434.4035)
		(end 106.045 -434.4035)
		(width 0.17145)
		(layer "F.Cu")
		(net "SSD_PRSNT0")
	)
	(segment
		(start 98.40341 -433.55006)
		(end 99.74326 -433.55006)
		(width 0.17145)
		(layer "F.Cu")
		(net "SSD_PRSNT0")
	)
	(segment
		(start 106.9975 -434.467)
		(end 106.1085 -434.467)
		(width 0.17145)
		(layer "F.Cu")
		(net "SSD_PRSNT0")
	)
	(segment
		(start 99.74326 -433.55006)
		(end 101.2952 -435.102)
		(width 0.17145)
		(layer "F.Cu")
		(net "SSD_PRSNT0")
	)
	(segment
		(start 104.394 -435.102)
		(end 104.775 -434.721)
		(width 0.17145)
		(layer "F.Cu")
		(net "SSD_PRSNT0")
	)
	(segment
		(start 101.2952 -435.102)
		(end 104.394 -435.102)
		(width 0.17145)
		(layer "F.Cu")
		(net "SSD_PRSNT0")
	)
	(segment
		(start 106.1085 -434.467)
		(end 106.045 -434.4035)
		(width 0.17145)
		(layer "F.Cu")
		(net "SSD_PRSNT0")
	)
	(via
		(at 104.775 -434.721)
		(size 0.7112)
		(drill 0.3556)
		(layers "F.Cu" "B.Cu")
		(net "SSD_PRSNT0")
	)
	(segment
		(start 47.426118 -60.142882)
		(end 47.426118 -73.35393)
		(width 0.17145)
		(layer "F.Cu")
		(net "SSD_PRSNT_NET9")
	)
	(segment
		(start 87.5665 -85.3694)
		(end 87.5665 -86.614)
		(width 0.17145)
		(layer "F.Cu")
		(net "SSD_PRSNT_NET9")
	)
	(segment
		(start 87.5665 -72.89673)
		(end 73.828656 -59.158886)
		(width 0.17145)
		(layer "F.Cu")
		(net "SSD_PRSNT_NET9")
	)
	(segment
		(start 48.410114 -59.158886)
		(end 47.426118 -60.142882)
		(width 0.17145)
		(layer "F.Cu")
		(net "SSD_PRSNT_NET9")
	)
	(segment
		(start 47.426118 -73.35393)
		(end 43.58513 -77.194918)
		(width 0.17145)
		(layer "F.Cu")
		(net "SSD_PRSNT_NET9")
	)
	(segment
		(start 87.5665 -85.3694)
		(end 87.5665 -72.89673)
		(width 0.17145)
		(layer "F.Cu")
		(net "SSD_PRSNT_NET9")
	)
	(segment
		(start 87.63 -86.6775)
		(end 87.5665 -86.614)
		(width 0.17145)
		(layer "F.Cu")
		(net "SSD_PRSNT_NET9")
	)
	(segment
		(start 87.63 -87.6935)
		(end 87.63 -86.6775)
		(width 0.17145)
		(layer "F.Cu")
		(net "SSD_PRSNT_NET9")
	)
	(segment
		(start 73.828656 -59.158886)
		(end 48.410114 -59.158886)
		(width 0.17145)
		(layer "F.Cu")
		(net "SSD_PRSNT_NET9")
	)
	(segment
		(start 43.58513 -77.194918)
		(end 41.975024 -77.194918)
		(width 0.17145)
		(layer "F.Cu")
		(net "SSD_PRSNT_NET9")
	)
	(via
		(at 87.5665 -85.3694)
		(size 0.7112)
		(drill 0.3556)
		(layers "F.Cu" "B.Cu")
		(net "SSD_PRSNT_NET9")
	)
	(segment
		(start 43.58513 -180.194966)
		(end 47.28845 -176.491646)
		(width 0.17145)
		(layer "F.Cu")
		(net "SSD_PRSNT_NET8")
	)
	(segment
		(start 73.48347 -131.307078)
		(end 84.719922 -131.307078)
		(width 0.17145)
		(layer "F.Cu")
		(net "SSD_PRSNT_NET8")
	)
	(segment
		(start 41.975024 -180.194966)
		(end 43.58513 -180.194966)
		(width 0.17145)
		(layer "F.Cu")
		(net "SSD_PRSNT_NET8")
	)
	(segment
		(start 98.1964 -117.8306)
		(end 99.2505 -117.8306)
		(width 0.17145)
		(layer "F.Cu")
		(net "SSD_PRSNT_NET8")
	)
	(segment
		(start 47.28845 -157.502098)
		(end 73.48347 -131.307078)
		(width 0.17145)
		(layer "F.Cu")
		(net "SSD_PRSNT_NET8")
	)
	(segment
		(start 47.28845 -176.491646)
		(end 47.28845 -157.502098)
		(width 0.17145)
		(layer "F.Cu")
		(net "SSD_PRSNT_NET8")
	)
	(segment
		(start 99.187 -116.5225)
		(end 99.2505 -116.586)
		(width 0.17145)
		(layer "F.Cu")
		(net "SSD_PRSNT_NET8")
	)
	(segment
		(start 84.719922 -131.307078)
		(end 98.1964 -117.8306)
		(width 0.17145)
		(layer "F.Cu")
		(net "SSD_PRSNT_NET8")
	)
	(segment
		(start 99.2505 -116.586)
		(end 99.2505 -117.8306)
		(width 0.17145)
		(layer "F.Cu")
		(net "SSD_PRSNT_NET8")
	)
	(segment
		(start 99.187 -115.5065)
		(end 99.187 -116.5225)
		(width 0.17145)
		(layer "F.Cu")
		(net "SSD_PRSNT_NET8")
	)
	(via
		(at 99.2505 -117.8306)
		(size 0.7112)
		(drill 0.3556)
		(layers "F.Cu" "B.Cu")
		(net "SSD_PRSNT_NET8")
	)
	(segment
		(start 99.2505 -227.07473)
		(end 99.2505 -227.0506)
		(width 0.17145)
		(layer "F.Cu")
		(net "SSD_PRSNT_NET7")
	)
	(segment
		(start 41.975024 -283.195014)
		(end 43.58513 -283.195014)
		(width 0.17145)
		(layer "F.Cu")
		(net "SSD_PRSNT_NET7")
	)
	(segment
		(start 47.438564 -279.34158)
		(end 47.438564 -260.163056)
		(width 0.17145)
		(layer "F.Cu")
		(net "SSD_PRSNT_NET7")
	)
	(segment
		(start 99.2505 -227.0506)
		(end 99.2505 -225.806)
		(width 0.17145)
		(layer "F.Cu")
		(net "SSD_PRSNT_NET7")
	)
	(segment
		(start 99.187 -224.7265)
		(end 99.187 -225.7425)
		(width 0.17145)
		(layer "F.Cu")
		(net "SSD_PRSNT_NET7")
	)
	(segment
		(start 99.187 -225.7425)
		(end 99.2505 -225.806)
		(width 0.17145)
		(layer "F.Cu")
		(net "SSD_PRSNT_NET7")
	)
	(segment
		(start 47.438564 -260.163056)
		(end 65.587372 -242.014248)
		(width 0.17145)
		(layer "F.Cu")
		(net "SSD_PRSNT_NET7")
	)
	(segment
		(start 65.587372 -242.014248)
		(end 84.310982 -242.014248)
		(width 0.17145)
		(layer "F.Cu")
		(net "SSD_PRSNT_NET7")
	)
	(segment
		(start 84.310982 -242.014248)
		(end 99.2505 -227.07473)
		(width 0.17145)
		(layer "F.Cu")
		(net "SSD_PRSNT_NET7")
	)
	(segment
		(start 43.58513 -283.195014)
		(end 47.438564 -279.34158)
		(width 0.17145)
		(layer "F.Cu")
		(net "SSD_PRSNT_NET7")
	)
	(via
		(at 99.2505 -227.0506)
		(size 0.7112)
		(drill 0.3556)
		(layers "F.Cu" "B.Cu")
		(net "SSD_PRSNT_NET7")
	)
	(segment
		(start 47.244 -363.54639)
		(end 47.244 -382.536192)
		(width 0.17145)
		(layer "F.Cu")
		(net "SSD_PRSNT_NET6")
	)
	(segment
		(start 99.187 -319.0875)
		(end 99.187 -320.1035)
		(width 0.17145)
		(layer "F.Cu")
		(net "SSD_PRSNT_NET6")
	)
	(segment
		(start 99.187 -320.1035)
		(end 99.2505 -320.167)
		(width 0.17145)
		(layer "F.Cu")
		(net "SSD_PRSNT_NET6")
	)
	(segment
		(start 98.966274 -321.695826)
		(end 97.804478 -321.695826)
		(width 0.17145)
		(layer "F.Cu")
		(net "SSD_PRSNT_NET6")
	)
	(segment
		(start 43.58513 -386.195062)
		(end 41.975024 -386.195062)
		(width 0.17145)
		(layer "F.Cu")
		(net "SSD_PRSNT_NET6")
	)
	(segment
		(start 74.805286 -344.695018)
		(end 66.095372 -344.695018)
		(width 0.17145)
		(layer "F.Cu")
		(net "SSD_PRSNT_NET6")
	)
	(segment
		(start 97.804478 -321.695826)
		(end 74.805286 -344.695018)
		(width 0.17145)
		(layer "F.Cu")
		(net "SSD_PRSNT_NET6")
	)
	(segment
		(start 66.095372 -344.695018)
		(end 47.244 -363.54639)
		(width 0.17145)
		(layer "F.Cu")
		(net "SSD_PRSNT_NET6")
	)
	(segment
		(start 99.2505 -321.4116)
		(end 98.966274 -321.695826)
		(width 0.17145)
		(layer "F.Cu")
		(net "SSD_PRSNT_NET6")
	)
	(segment
		(start 99.2505 -321.4116)
		(end 99.2505 -320.167)
		(width 0.17145)
		(layer "F.Cu")
		(net "SSD_PRSNT_NET6")
	)
	(segment
		(start 47.244 -382.536192)
		(end 43.58513 -386.195062)
		(width 0.17145)
		(layer "F.Cu")
		(net "SSD_PRSNT_NET6")
	)
	(via
		(at 99.2505 -321.4116)
		(size 0.7112)
		(drill 0.3556)
		(layers "F.Cu" "B.Cu")
		(net "SSD_PRSNT_NET6")
	)
	(segment
		(start 90.2335 -448.0306)
		(end 90.2335 -452.409306)
		(width 0.17145)
		(layer "F.Cu")
		(net "SSD_PRSNT_NET5")
	)
	(segment
		(start 90.2335 -452.409306)
		(end 71.1454 -471.497406)
		(width 0.17145)
		(layer "F.Cu")
		(net "SSD_PRSNT_NET5")
	)
	(segment
		(start 43.58513 -489.19511)
		(end 41.975024 -489.19511)
		(width 0.17145)
		(layer "F.Cu")
		(net "SSD_PRSNT_NET5")
	)
	(segment
		(start 90.17 -446.7225)
		(end 90.2335 -446.786)
		(width 0.17145)
		(layer "F.Cu")
		(net "SSD_PRSNT_NET5")
	)
	(segment
		(start 47.152306 -485.627934)
		(end 43.58513 -489.19511)
		(width 0.17145)
		(layer "F.Cu")
		(net "SSD_PRSNT_NET5")
	)
	(segment
		(start 90.17 -445.7065)
		(end 90.17 -446.7225)
		(width 0.17145)
		(layer "F.Cu")
		(net "SSD_PRSNT_NET5")
	)
	(segment
		(start 47.515526 -471.497406)
		(end 47.152306 -471.860626)
		(width 0.17145)
		(layer "F.Cu")
		(net "SSD_PRSNT_NET5")
	)
	(segment
		(start 90.2335 -448.0306)
		(end 90.2335 -446.786)
		(width 0.17145)
		(layer "F.Cu")
		(net "SSD_PRSNT_NET5")
	)
	(segment
		(start 71.1454 -471.497406)
		(end 47.515526 -471.497406)
		(width 0.17145)
		(layer "F.Cu")
		(net "SSD_PRSNT_NET5")
	)
	(segment
		(start 47.152306 -471.860626)
		(end 47.152306 -485.627934)
		(width 0.17145)
		(layer "F.Cu")
		(net "SSD_PRSNT_NET5")
	)
	(via
		(at 90.2335 -448.0306)
		(size 0.7112)
		(drill 0.3556)
		(layers "F.Cu" "B.Cu")
		(net "SSD_PRSNT_NET5")
	)
	(segment
		(start 218.533472 -50.292)
		(end 229.743 -50.292)
		(width 0.17145)
		(layer "F.Cu")
		(net "SSD_PRSNT_NET4")
	)
	(segment
		(start 94.996 -196.9135)
		(end 94.996 -195.8975)
		(width 0.17145)
		(layer "F.Cu")
		(net "SSD_PRSNT_NET4")
	)
	(segment
		(start 94.9325 -195.834)
		(end 94.9325 -194.5894)
		(width 0.17145)
		(layer "F.Cu")
		(net "SSD_PRSNT_NET4")
	)
	(segment
		(start 232.283 -73.496932)
		(end 228.585014 -77.194918)
		(width 0.17145)
		(layer "F.Cu")
		(net "SSD_PRSNT_NET4")
	)
	(segment
		(start 94.9325 -173.892972)
		(end 218.533472 -50.292)
		(width 0.17145)
		(layer "F.Cu")
		(net "SSD_PRSNT_NET4")
	)
	(segment
		(start 228.585014 -77.194918)
		(end 226.974908 -77.194918)
		(width 0.17145)
		(layer "F.Cu")
		(net "SSD_PRSNT_NET4")
	)
	(segment
		(start 232.283 -52.832)
		(end 232.283 -73.496932)
		(width 0.17145)
		(layer "F.Cu")
		(net "SSD_PRSNT_NET4")
	)
	(segment
		(start 229.743 -50.292)
		(end 232.283 -52.832)
		(width 0.17145)
		(layer "F.Cu")
		(net "SSD_PRSNT_NET4")
	)
	(segment
		(start 94.9325 -194.5894)
		(end 94.9325 -173.892972)
		(width 0.17145)
		(layer "F.Cu")
		(net "SSD_PRSNT_NET4")
	)
	(segment
		(start 94.996 -195.8975)
		(end 94.9325 -195.834)
		(width 0.17145)
		(layer "F.Cu")
		(net "SSD_PRSNT_NET4")
	)
	(via
		(at 94.9325 -194.5894)
		(size 0.7112)
		(drill 0.3556)
		(layers "F.Cu" "B.Cu")
		(net "SSD_PRSNT_NET4")
	)
	(segment
		(start 232.438448 -155.984448)
		(end 232.438448 -176.341532)
		(width 0.17145)
		(layer "F.Cu")
		(net "SSD_PRSNT_NET3")
	)
	(segment
		(start 110.2106 -205.5495)
		(end 108.966 -205.5495)
		(width 0.17145)
		(layer "F.Cu")
		(net "SSD_PRSNT_NET3")
	)
	(segment
		(start 108.9025 -205.613)
		(end 108.966 -205.5495)
		(width 0.17145)
		(layer "F.Cu")
		(net "SSD_PRSNT_NET3")
	)
	(segment
		(start 228.585014 -180.194966)
		(end 226.974908 -180.194966)
		(width 0.17145)
		(layer "F.Cu")
		(net "SSD_PRSNT_NET3")
	)
	(segment
		(start 124.120656 -153.289)
		(end 229.743 -153.289)
		(width 0.17145)
		(layer "F.Cu")
		(net "SSD_PRSNT_NET3")
	)
	(segment
		(start 113.208054 -164.201602)
		(end 124.120656 -153.289)
		(width 0.17145)
		(layer "F.Cu")
		(net "SSD_PRSNT_NET3")
	)
	(segment
		(start 232.438448 -176.341532)
		(end 228.585014 -180.194966)
		(width 0.17145)
		(layer "F.Cu")
		(net "SSD_PRSNT_NET3")
	)
	(segment
		(start 107.8865 -205.613)
		(end 108.9025 -205.613)
		(width 0.17145)
		(layer "F.Cu")
		(net "SSD_PRSNT_NET3")
	)
	(segment
		(start 229.743 -153.289)
		(end 232.438448 -155.984448)
		(width 0.17145)
		(layer "F.Cu")
		(net "SSD_PRSNT_NET3")
	)
	(segment
		(start 110.2106 -205.5495)
		(end 113.208054 -202.552046)
		(width 0.17145)
		(layer "F.Cu")
		(net "SSD_PRSNT_NET3")
	)
	(segment
		(start 113.208054 -202.552046)
		(end 113.208054 -164.201602)
		(width 0.17145)
		(layer "F.Cu")
		(net "SSD_PRSNT_NET3")
	)
	(via
		(at 110.2106 -205.5495)
		(size 0.7112)
		(drill 0.3556)
		(layers "F.Cu" "B.Cu")
		(net "SSD_PRSNT_NET3")
	)
	(segment
		(start 96.5835 -284.143196)
		(end 124.358146 -256.36855)
		(width 0.17145)
		(layer "F.Cu")
		(net "SSD_PRSNT_NET2")
	)
	(segment
		(start 96.5835 -288.9504)
		(end 96.5835 -284.143196)
		(width 0.17145)
		(layer "F.Cu")
		(net "SSD_PRSNT_NET2")
	)
	(segment
		(start 232.438448 -258.454144)
		(end 232.438448 -279.34158)
		(width 0.17145)
		(layer "F.Cu")
		(net "SSD_PRSNT_NET2")
	)
	(segment
		(start 96.647 -290.2585)
		(end 96.5835 -290.195)
		(width 0.17145)
		(layer "F.Cu")
		(net "SSD_PRSNT_NET2")
	)
	(segment
		(start 96.647 -291.2745)
		(end 96.647 -290.2585)
		(width 0.17145)
		(layer "F.Cu")
		(net "SSD_PRSNT_NET2")
	)
	(segment
		(start 232.438448 -279.34158)
		(end 228.585014 -283.195014)
		(width 0.17145)
		(layer "F.Cu")
		(net "SSD_PRSNT_NET2")
	)
	(segment
		(start 228.585014 -283.195014)
		(end 226.974908 -283.195014)
		(width 0.17145)
		(layer "F.Cu")
		(net "SSD_PRSNT_NET2")
	)
	(segment
		(start 124.358146 -256.36855)
		(end 230.352854 -256.36855)
		(width 0.17145)
		(layer "F.Cu")
		(net "SSD_PRSNT_NET2")
	)
	(segment
		(start 96.5835 -290.195)
		(end 96.5835 -288.9504)
		(width 0.17145)
		(layer "F.Cu")
		(net "SSD_PRSNT_NET2")
	)
	(segment
		(start 230.352854 -256.36855)
		(end 232.438448 -258.454144)
		(width 0.17145)
		(layer "F.Cu")
		(net "SSD_PRSNT_NET2")
	)
	(via
		(at 96.5835 -288.9504)
		(size 0.7112)
		(drill 0.3556)
		(layers "F.Cu" "B.Cu")
		(net "SSD_PRSNT_NET2")
	)
	(segment
		(start 31.286196 -30.901132)
		(end 60.726828 -30.901132)
		(width 0.17145)
		(layer "F.Cu")
		(net "SSD_PRSNT_NET14")
	)
	(segment
		(start 14.351 -19.939)
		(end 14.351 -42.418)
		(width 0.17145)
		(layer "F.Cu")
		(net "SSD_PRSNT_NET14")
	)
	(segment
		(start 26.126694 -46.811438)
		(end 31.65475 -41.283382)
		(width 0.17145)
		(layer "F.Cu")
		(net "SSD_PRSNT_NET14")
	)
	(segment
		(start 31.65475 -41.283382)
		(end 31.65475 -36.0426)
		(width 0.17145)
		(layer "F.Cu")
		(net "SSD_PRSNT_NET14")
	)
	(segment
		(start 96.5835 -66.757804)
		(end 96.5835 -85.3694)
		(width 0.17145)
		(layer "F.Cu")
		(net "SSD_PRSNT_NET14")
	)
	(segment
		(start 60.726828 -30.901132)
		(end 96.5835 -66.757804)
		(width 0.17145)
		(layer "F.Cu")
		(net "SSD_PRSNT_NET14")
	)
	(segment
		(start 14.351 -42.418)
		(end 16.451834 -44.518834)
		(width 0.17145)
		(layer "F.Cu")
		(net "SSD_PRSNT_NET14")
	)
	(segment
		(start 20.30603 -46.811438)
		(end 26.126694 -46.811438)
		(width 0.17145)
		(layer "F.Cu")
		(net "SSD_PRSNT_NET14")
	)
	(segment
		(start 20.025106 -16.804894)
		(end 17.485106 -16.804894)
		(width 0.17145)
		(layer "F.Cu")
		(net "SSD_PRSNT_NET14")
	)
	(segment
		(start 30.6324 -31.554928)
		(end 31.286196 -30.901132)
		(width 0.17145)
		(layer "F.Cu")
		(net "SSD_PRSNT_NET14")
	)
	(segment
		(start 96.647 -87.6935)
		(end 96.647 -86.6775)
		(width 0.17145)
		(layer "F.Cu")
		(net "SSD_PRSNT_NET14")
	)
	(segment
		(start 30.6324 -35.02025)
		(end 30.6324 -31.554928)
		(width 0.17145)
		(layer "F.Cu")
		(net "SSD_PRSNT_NET14")
	)
	(segment
		(start 31.65475 -36.0426)
		(end 30.6324 -35.02025)
		(width 0.17145)
		(layer "F.Cu")
		(net "SSD_PRSNT_NET14")
	)
	(segment
		(start 96.5835 -86.614)
		(end 96.5835 -85.3694)
		(width 0.17145)
		(layer "F.Cu")
		(net "SSD_PRSNT_NET14")
	)
	(segment
		(start 18.013426 -44.518834)
		(end 20.30603 -46.811438)
		(width 0.17145)
		(layer "F.Cu")
		(net "SSD_PRSNT_NET14")
	)
	(segment
		(start 16.451834 -44.518834)
		(end 18.013426 -44.518834)
		(width 0.17145)
		(layer "F.Cu")
		(net "SSD_PRSNT_NET14")
	)
	(segment
		(start 96.647 -86.6775)
		(end 96.5835 -86.614)
		(width 0.17145)
		(layer "F.Cu")
		(net "SSD_PRSNT_NET14")
	)
	(segment
		(start 17.485106 -16.804894)
		(end 14.351 -19.939)
		(width 0.17145)
		(layer "F.Cu")
		(net "SSD_PRSNT_NET14")
	)
	(via
		(at 96.5835 -85.3694)
		(size 0.7112)
		(drill 0.3556)
		(layers "F.Cu" "B.Cu")
		(net "SSD_PRSNT_NET14")
	)
	(segment
		(start 17.526 -146.685)
		(end 15.32255 -144.48155)
		(width 0.17145)
		(layer "F.Cu")
		(net "SSD_PRSNT_NET13")
	)
	(segment
		(start 17.983454 -146.685254)
		(end 17.9832 -146.685)
		(width 0.17145)
		(layer "F.Cu")
		(net "SSD_PRSNT_NET13")
	)
	(segment
		(start 28.448 -146.685254)
		(end 17.983454 -146.685254)
		(width 0.17145)
		(layer "F.Cu")
		(net "SSD_PRSNT_NET13")
	)
	(segment
		(start 90.17 -116.5225)
		(end 90.2335 -116.586)
		(width 0.17145)
		(layer "F.Cu")
		(net "SSD_PRSNT_NET13")
	)
	(segment
		(start 15.32255 -144.48155)
		(end 15.32255 -122.897392)
		(width 0.17145)
		(layer "F.Cu")
		(net "SSD_PRSNT_NET13")
	)
	(segment
		(start 18.415 -119.804942)
		(end 20.025106 -119.804942)
		(width 0.17145)
		(layer "F.Cu")
		(net "SSD_PRSNT_NET13")
	)
	(segment
		(start 90.17 -115.5065)
		(end 90.17 -116.5225)
		(width 0.17145)
		(layer "F.Cu")
		(net "SSD_PRSNT_NET13")
	)
	(segment
		(start 28.771596 -146.361658)
		(end 28.448 -146.685254)
		(width 0.17145)
		(layer "F.Cu")
		(net "SSD_PRSNT_NET13")
	)
	(segment
		(start 90.2335 -117.8306)
		(end 89.466928 -117.8306)
		(width 0.17145)
		(layer "F.Cu")
		(net "SSD_PRSNT_NET13")
	)
	(segment
		(start 28.771596 -146.361404)
		(end 28.771596 -146.361658)
		(width 0.17145)
		(layer "F.Cu")
		(net "SSD_PRSNT_NET13")
	)
	(segment
		(start 30.215078 -134.975854)
		(end 30.215078 -144.917922)
		(width 0.17145)
		(layer "F.Cu")
		(net "SSD_PRSNT_NET13")
	)
	(segment
		(start 17.9832 -146.685)
		(end 17.526 -146.685)
		(width 0.17145)
		(layer "F.Cu")
		(net "SSD_PRSNT_NET13")
	)
	(segment
		(start 90.2335 -116.586)
		(end 90.2335 -117.8306)
		(width 0.17145)
		(layer "F.Cu")
		(net "SSD_PRSNT_NET13")
	)
	(segment
		(start 30.215078 -144.917922)
		(end 28.771596 -146.361404)
		(width 0.17145)
		(layer "F.Cu")
		(net "SSD_PRSNT_NET13")
	)
	(segment
		(start 89.466928 -117.8306)
		(end 81.567528 -125.73)
		(width 0.17145)
		(layer "F.Cu")
		(net "SSD_PRSNT_NET13")
	)
	(segment
		(start 81.567528 -125.73)
		(end 39.460932 -125.73)
		(width 0.17145)
		(layer "F.Cu")
		(net "SSD_PRSNT_NET13")
	)
	(segment
		(start 15.32255 -122.897392)
		(end 18.415 -119.804942)
		(width 0.17145)
		(layer "F.Cu")
		(net "SSD_PRSNT_NET13")
	)
	(segment
		(start 39.460932 -125.73)
		(end 30.215078 -134.975854)
		(width 0.17145)
		(layer "F.Cu")
		(net "SSD_PRSNT_NET13")
	)
	(via
		(at 90.2335 -117.8306)
		(size 0.7112)
		(drill 0.3556)
		(layers "F.Cu" "B.Cu")
		(net "SSD_PRSNT_NET13")
	)
	(segment
		(start 90.17 -224.7265)
		(end 90.17 -225.7425)
		(width 0.17145)
		(layer "F.Cu")
		(net "SSD_PRSNT_NET12")
	)
	(segment
		(start 17.35201 -222.80499)
		(end 15.489428 -224.667572)
		(width 0.17145)
		(layer "F.Cu")
		(net "SSD_PRSNT_NET12")
	)
	(segment
		(start 20.025106 -222.80499)
		(end 17.35201 -222.80499)
		(width 0.17145)
		(layer "F.Cu")
		(net "SSD_PRSNT_NET12")
	)
	(segment
		(start 81.4451 -235.839)
		(end 90.2335 -227.0506)
		(width 0.17145)
		(layer "F.Cu")
		(net "SSD_PRSNT_NET12")
	)
	(segment
		(start 21.639276 -256.160524)
		(end 41.9608 -235.839)
		(width 0.17145)
		(layer "F.Cu")
		(net "SSD_PRSNT_NET12")
	)
	(segment
		(start 15.489428 -224.667572)
		(end 15.489428 -254.704342)
		(width 0.17145)
		(layer "F.Cu")
		(net "SSD_PRSNT_NET12")
	)
	(segment
		(start 21.315934 -256.48412)
		(end 21.639276 -256.160778)
		(width 0.17145)
		(layer "F.Cu")
		(net "SSD_PRSNT_NET12")
	)
	(segment
		(start 15.489428 -254.704342)
		(end 17.269206 -256.48412)
		(width 0.17145)
		(layer "F.Cu")
		(net "SSD_PRSNT_NET12")
	)
	(segment
		(start 17.269206 -256.48412)
		(end 21.315934 -256.48412)
		(width 0.17145)
		(layer "F.Cu")
		(net "SSD_PRSNT_NET12")
	)
	(segment
		(start 90.17 -225.7425)
		(end 90.2335 -225.806)
		(width 0.17145)
		(layer "F.Cu")
		(net "SSD_PRSNT_NET12")
	)
	(segment
		(start 41.9608 -235.839)
		(end 81.4451 -235.839)
		(width 0.17145)
		(layer "F.Cu")
		(net "SSD_PRSNT_NET12")
	)
	(segment
		(start 90.2335 -227.0506)
		(end 90.2335 -225.806)
		(width 0.17145)
		(layer "F.Cu")
		(net "SSD_PRSNT_NET12")
	)
	(segment
		(start 21.639276 -256.160778)
		(end 21.639276 -256.160524)
		(width 0.17145)
		(layer "F.Cu")
		(net "SSD_PRSNT_NET12")
	)
	(via
		(at 90.2335 -227.0506)
		(size 0.7112)
		(drill 0.3556)
		(layers "F.Cu" "B.Cu")
		(net "SSD_PRSNT_NET12")
	)
	(segment
		(start 89.27719 -321.601338)
		(end 89.988136 -321.601338)
		(width 0.17145)
		(layer "F.Cu")
		(net "SSD_PRSNT_NET11")
	)
	(segment
		(start 15.748 -337.0072)
		(end 15.748 -351.809304)
		(width 0.17145)
		(layer "F.Cu")
		(net "SSD_PRSNT_NET11")
	)
	(segment
		(start 17.653 -326.567038)
		(end 17.653 -333.375)
		(width 0.17145)
		(layer "F.Cu")
		(net "SSD_PRSNT_NET11")
	)
	(segment
		(start 90.17 -320.1035)
		(end 90.2335 -320.167)
		(width 0.17145)
		(layer "F.Cu")
		(net "SSD_PRSNT_NET11")
	)
	(segment
		(start 16.6624 -352.723704)
		(end 17.1196 -352.723704)
		(width 0.17145)
		(layer "F.Cu")
		(net "SSD_PRSNT_NET11")
	)
	(segment
		(start 33.999424 -336.840576)
		(end 74.037952 -336.840576)
		(width 0.17145)
		(layer "F.Cu")
		(net "SSD_PRSNT_NET11")
	)
	(segment
		(start 90.2335 -320.167)
		(end 90.2335 -321.355974)
		(width 0.17145)
		(layer "F.Cu")
		(net "SSD_PRSNT_NET11")
	)
	(segment
		(start 20.025106 -325.805038)
		(end 18.415 -325.805038)
		(width 0.17145)
		(layer "F.Cu")
		(net "SSD_PRSNT_NET11")
	)
	(segment
		(start 16.3576 -334.6704)
		(end 16.3576 -336.3976)
		(width 0.17145)
		(layer "F.Cu")
		(net "SSD_PRSNT_NET11")
	)
	(segment
		(start 18.415 -325.805038)
		(end 17.653 -326.567038)
		(width 0.17145)
		(layer "F.Cu")
		(net "SSD_PRSNT_NET11")
	)
	(segment
		(start 17.653 -333.375)
		(end 16.3576 -334.6704)
		(width 0.17145)
		(layer "F.Cu")
		(net "SSD_PRSNT_NET11")
	)
	(segment
		(start 15.748 -351.809304)
		(end 16.6624 -352.723704)
		(width 0.17145)
		(layer "F.Cu")
		(net "SSD_PRSNT_NET11")
	)
	(segment
		(start 74.037952 -336.840576)
		(end 89.27719 -321.601338)
		(width 0.17145)
		(layer "F.Cu")
		(net "SSD_PRSNT_NET11")
	)
	(segment
		(start 30.520132 -349.991172)
		(end 30.520132 -340.319868)
		(width 0.17145)
		(layer "F.Cu")
		(net "SSD_PRSNT_NET11")
	)
	(segment
		(start 90.2335 -321.355974)
		(end 90.177366 -321.412108)
		(width 0.17145)
		(layer "F.Cu")
		(net "SSD_PRSNT_NET11")
	)
	(segment
		(start 27.787854 -352.72345)
		(end 30.520132 -349.991172)
		(width 0.17145)
		(layer "F.Cu")
		(net "SSD_PRSNT_NET11")
	)
	(segment
		(start 90.17 -319.0875)
		(end 90.17 -320.1035)
		(width 0.17145)
		(layer "F.Cu")
		(net "SSD_PRSNT_NET11")
	)
	(segment
		(start 17.1196 -352.723704)
		(end 17.119854 -352.72345)
		(width 0.17145)
		(layer "F.Cu")
		(net "SSD_PRSNT_NET11")
	)
	(segment
		(start 17.119854 -352.72345)
		(end 27.787854 -352.72345)
		(width 0.17145)
		(layer "F.Cu")
		(net "SSD_PRSNT_NET11")
	)
	(segment
		(start 16.3576 -336.3976)
		(end 15.748 -337.0072)
		(width 0.17145)
		(layer "F.Cu")
		(net "SSD_PRSNT_NET11")
	)
	(segment
		(start 30.520132 -340.319868)
		(end 33.999424 -336.840576)
		(width 0.17145)
		(layer "F.Cu")
		(net "SSD_PRSNT_NET11")
	)
	(segment
		(start 89.988136 -321.601338)
		(end 90.177366 -321.412108)
		(width 0.17145)
		(layer "F.Cu")
		(net "SSD_PRSNT_NET11")
	)
	(via
		(at 90.177366 -321.412108)
		(size 0.7112)
		(drill 0.3556)
		(layers "F.Cu" "B.Cu")
		(net "SSD_PRSNT_NET11")
	)
	(segment
		(start 87.5665 -416.814)
		(end 87.5665 -415.5694)
		(width 0.17145)
		(layer "F.Cu")
		(net "SSD_PRSNT_NET10")
	)
	(segment
		(start 87.63 -417.8935)
		(end 87.63 -416.8775)
		(width 0.17145)
		(layer "F.Cu")
		(net "SSD_PRSNT_NET10")
	)
	(segment
		(start 15.83055 -453.39635)
		(end 15.83055 -435.637432)
		(width 0.17145)
		(layer "F.Cu")
		(net "SSD_PRSNT_NET10")
	)
	(segment
		(start 17.526 -433.941982)
		(end 17.526 -429.694086)
		(width 0.17145)
		(layer "F.Cu")
		(net "SSD_PRSNT_NET10")
	)
	(segment
		(start 15.83055 -435.637432)
		(end 17.526 -433.941982)
		(width 0.17145)
		(layer "F.Cu")
		(net "SSD_PRSNT_NET10")
	)
	(segment
		(start 87.0331 -415.036)
		(end 52.959 -415.036)
		(width 0.17145)
		(layer "F.Cu")
		(net "SSD_PRSNT_NET10")
	)
	(segment
		(start 18.02765 -455.59345)
		(end 15.83055 -453.39635)
		(width 0.17145)
		(layer "F.Cu")
		(net "SSD_PRSNT_NET10")
	)
	(segment
		(start 28.255722 -455.59345)
		(end 18.02765 -455.59345)
		(width 0.17145)
		(layer "F.Cu")
		(net "SSD_PRSNT_NET10")
	)
	(segment
		(start 52.959 -415.036)
		(end 30.52445 -437.47055)
		(width 0.17145)
		(layer "F.Cu")
		(net "SSD_PRSNT_NET10")
	)
	(segment
		(start 18.415 -428.805086)
		(end 20.025106 -428.805086)
		(width 0.17145)
		(layer "F.Cu")
		(net "SSD_PRSNT_NET10")
	)
	(segment
		(start 17.526 -429.694086)
		(end 18.415 -428.805086)
		(width 0.17145)
		(layer "F.Cu")
		(net "SSD_PRSNT_NET10")
	)
	(segment
		(start 87.5665 -415.5694)
		(end 87.0331 -415.036)
		(width 0.17145)
		(layer "F.Cu")
		(net "SSD_PRSNT_NET10")
	)
	(segment
		(start 30.52445 -437.47055)
		(end 30.52445 -453.324722)
		(width 0.17145)
		(layer "F.Cu")
		(net "SSD_PRSNT_NET10")
	)
	(segment
		(start 30.52445 -453.324722)
		(end 28.255722 -455.59345)
		(width 0.17145)
		(layer "F.Cu")
		(net "SSD_PRSNT_NET10")
	)
	(segment
		(start 87.63 -416.8775)
		(end 87.5665 -416.814)
		(width 0.17145)
		(layer "F.Cu")
		(net "SSD_PRSNT_NET10")
	)
	(via
		(at 87.5665 -415.5694)
		(size 0.7112)
		(drill 0.3556)
		(layers "F.Cu" "B.Cu")
		(net "SSD_PRSNT_NET10")
	)
	(segment
		(start 232.438448 -382.341628)
		(end 228.585014 -386.195062)
		(width 0.17145)
		(layer "F.Cu")
		(net "SSD_PRSNT_NET1")
	)
	(segment
		(start 232.438448 -361.851448)
		(end 232.438448 -382.341628)
		(width 0.17145)
		(layer "F.Cu")
		(net "SSD_PRSNT_NET1")
	)
	(segment
		(start 128.2065 -307.7845)
		(end 179.832 -359.41)
		(width 0.17145)
		(layer "F.Cu")
		(net "SSD_PRSNT_NET1")
	)
	(segment
		(start 179.832 -359.41)
		(end 229.997 -359.41)
		(width 0.17145)
		(layer "F.Cu")
		(net "SSD_PRSNT_NET1")
	)
	(segment
		(start 108.9025 -307.848)
		(end 108.966 -307.7845)
		(width 0.17145)
		(layer "F.Cu")
		(net "SSD_PRSNT_NET1")
	)
	(segment
		(start 107.8865 -307.848)
		(end 108.9025 -307.848)
		(width 0.17145)
		(layer "F.Cu")
		(net "SSD_PRSNT_NET1")
	)
	(segment
		(start 228.585014 -386.195062)
		(end 226.974908 -386.195062)
		(width 0.17145)
		(layer "F.Cu")
		(net "SSD_PRSNT_NET1")
	)
	(segment
		(start 229.997 -359.41)
		(end 232.438448 -361.851448)
		(width 0.17145)
		(layer "F.Cu")
		(net "SSD_PRSNT_NET1")
	)
	(segment
		(start 110.2106 -307.7845)
		(end 108.966 -307.7845)
		(width 0.17145)
		(layer "F.Cu")
		(net "SSD_PRSNT_NET1")
	)
	(segment
		(start 110.2106 -307.7845)
		(end 128.2065 -307.7845)
		(width 0.17145)
		(layer "F.Cu")
		(net "SSD_PRSNT_NET1")
	)
	(via
		(at 110.2106 -307.7845)
		(size 0.7112)
		(drill 0.3556)
		(layers "F.Cu" "B.Cu")
		(net "SSD_PRSNT_NET1")
	)
	(segment
		(start 114.061748 -435.804056)
		(end 112.661192 -434.4035)
		(width 0.17145)
		(layer "F.Cu")
		(net "SSD_PRSNT_NET0")
	)
	(segment
		(start 226.974908 -489.19511)
		(end 228.585014 -489.19511)
		(width 0.17145)
		(layer "F.Cu")
		(net "SSD_PRSNT_NET0")
	)
	(segment
		(start 110.2106 -434.4035)
		(end 108.966 -434.4035)
		(width 0.17145)
		(layer "F.Cu")
		(net "SSD_PRSNT_NET0")
	)
	(segment
		(start 108.9025 -434.467)
		(end 108.966 -434.4035)
		(width 0.17145)
		(layer "F.Cu")
		(net "SSD_PRSNT_NET0")
	)
	(segment
		(start 112.661192 -434.4035)
		(end 110.2106 -434.4035)
		(width 0.17145)
		(layer "F.Cu")
		(net "SSD_PRSNT_NET0")
	)
	(segment
		(start 107.8865 -434.467)
		(end 108.9025 -434.467)
		(width 0.17145)
		(layer "F.Cu")
		(net "SSD_PRSNT_NET0")
	)
	(segment
		(start 214.7824 -449.199)
		(end 191.897 -449.199)
		(width 0.17145)
		(layer "F.Cu")
		(net "SSD_PRSNT_NET0")
	)
	(segment
		(start 232.283 -485.497124)
		(end 232.283 -464.546696)
		(width 0.17145)
		(layer "F.Cu")
		(net "SSD_PRSNT_NET0")
	)
	(segment
		(start 229.971854 -462.23555)
		(end 222.478854 -462.23555)
		(width 0.17145)
		(layer "F.Cu")
		(net "SSD_PRSNT_NET0")
	)
	(segment
		(start 228.585014 -489.19511)
		(end 232.283 -485.497124)
		(width 0.17145)
		(layer "F.Cu")
		(net "SSD_PRSNT_NET0")
	)
	(segment
		(start 232.283 -464.546696)
		(end 229.971854 -462.23555)
		(width 0.17145)
		(layer "F.Cu")
		(net "SSD_PRSNT_NET0")
	)
	(segment
		(start 178.502056 -435.804056)
		(end 114.061748 -435.804056)
		(width 0.17145)
		(layer "F.Cu")
		(net "SSD_PRSNT_NET0")
	)
	(segment
		(start 221.350078 -455.766678)
		(end 214.7824 -449.199)
		(width 0.17145)
		(layer "F.Cu")
		(net "SSD_PRSNT_NET0")
	)
	(segment
		(start 221.350078 -461.106774)
		(end 221.350078 -455.766678)
		(width 0.17145)
		(layer "F.Cu")
		(net "SSD_PRSNT_NET0")
	)
	(segment
		(start 222.478854 -462.23555)
		(end 221.350078 -461.106774)
		(width 0.17145)
		(layer "F.Cu")
		(net "SSD_PRSNT_NET0")
	)
	(segment
		(start 191.897 -449.199)
		(end 178.502056 -435.804056)
		(width 0.17145)
		(layer "F.Cu")
		(net "SSD_PRSNT_NET0")
	)
	(via
		(at 110.2106 -434.4035)
		(size 0.7112)
		(drill 0.3556)
		(layers "F.Cu" "B.Cu")
		(net "SSD_PRSNT_NET0")
	)
	(segment
		(start 44.5516 -38.608)
		(end 44.959016 -38.608)
		(width 0.17145)
		(layer "F.Cu")
		(net "SSD_ACT_DR9")
	)
	(segment
		(start 41.975024 -78.464918)
		(end 43.58513 -78.464918)
		(width 0.17145)
		(layer "F.Cu")
		(net "SSD_ACT_DR9")
	)
	(segment
		(start 43.282108 -38.405562)
		(end 42.493692 -38.405562)
		(width 0.17145)
		(layer "F.Cu")
		(net "SSD_ACT_DR9")
	)
	(segment
		(start 43.731688 -38.405562)
		(end 43.282108 -38.405562)
		(width 0.17145)
		(layer "F.Cu")
		(net "SSD_ACT_DR9")
	)
	(segment
		(start 44.959016 -38.608)
		(end 45.187616 -38.3794)
		(width 0.17145)
		(layer "F.Cu")
		(net "SSD_ACT_DR9")
	)
	(segment
		(start 43.934126 -38.608)
		(end 43.731688 -38.405562)
		(width 0.17145)
		(layer "F.Cu")
		(net "SSD_ACT_DR9")
	)
	(segment
		(start 45.187616 -38.3794)
		(end 45.187616 -37.453062)
		(width 0.17145)
		(layer "F.Cu")
		(net "SSD_ACT_DR9")
	)
	(segment
		(start 44.5516 -38.608)
		(end 43.934126 -38.608)
		(width 0.17145)
		(layer "F.Cu")
		(net "SSD_ACT_DR9")
	)
	(via
		(at 44.5516 -38.608)
		(size 0.7112)
		(drill 0.3556)
		(layers "F.Cu" "B.Cu")
		(net "SSD_ACT_DR9")
	)
	(via
		(at 42.493692 -38.405562)
		(size 0.508)
		(drill 0.254)
		(layers "F.Cu" "B.Cu")
		(net "SSD_ACT_DR9")
	)
	(via
		(at 43.58513 -78.464918)
		(size 0.508)
		(drill 0.254)
		(layers "F.Cu" "B.Cu")
		(net "SSD_ACT_DR9")
	)
	(segment
		(start 44.979082 -78.464918)
		(end 43.58513 -78.464918)
		(width 0.1524)
		(layer "In5.Cu")
		(net "SSD_ACT_DR9")
	)
	(segment
		(start 52.832 -41.3512)
		(end 52.832 -70.612)
		(width 0.1524)
		(layer "In5.Cu")
		(net "SSD_ACT_DR9")
	)
	(segment
		(start 42.493692 -38.405562)
		(end 49.886362 -38.405562)
		(width 0.1524)
		(layer "In5.Cu")
		(net "SSD_ACT_DR9")
	)
	(segment
		(start 52.832 -70.612)
		(end 44.979082 -78.464918)
		(width 0.1524)
		(layer "In5.Cu")
		(net "SSD_ACT_DR9")
	)
	(segment
		(start 49.886362 -38.405562)
		(end 52.832 -41.3512)
		(width 0.1524)
		(layer "In5.Cu")
		(net "SSD_ACT_DR9")
	)
	(segment
		(start 53.1495 -145.7579)
		(end 53.1495 -144.526)
		(width 0.17145)
		(layer "F.Cu")
		(net "SSD_ACT_DR8")
	)
	(segment
		(start 51.7525 -145.81505)
		(end 51.7525 -144.526)
		(width 0.17145)
		(layer "F.Cu")
		(net "SSD_ACT_DR8")
	)
	(segment
		(start 52.5018 -146.05)
		(end 51.98745 -146.05)
		(width 0.17145)
		(layer "F.Cu")
		(net "SSD_ACT_DR8")
	)
	(segment
		(start 51.98745 -146.05)
		(end 51.7525 -145.81505)
		(width 0.17145)
		(layer "F.Cu")
		(net "SSD_ACT_DR8")
	)
	(segment
		(start 52.8574 -146.05)
		(end 53.1495 -145.7579)
		(width 0.17145)
		(layer "F.Cu")
		(net "SSD_ACT_DR8")
	)
	(segment
		(start 52.5018 -146.05)
		(end 52.8574 -146.05)
		(width 0.17145)
		(layer "F.Cu")
		(net "SSD_ACT_DR8")
	)
	(segment
		(start 41.975024 -181.464966)
		(end 43.58513 -181.464966)
		(width 0.17145)
		(layer "F.Cu")
		(net "SSD_ACT_DR8")
	)
	(via
		(at 52.5018 -146.05)
		(size 0.5588)
		(drill 0.3048)
		(layers "F.Cu" "B.Cu")
		(net "SSD_ACT_DR8")
	)
	(via
		(at 43.58513 -181.464966)
		(size 0.508)
		(drill 0.254)
		(layers "F.Cu" "B.Cu")
		(net "SSD_ACT_DR8")
	)
	(segment
		(start 52.832 -172.218096)
		(end 52.832 -146.3802)
		(width 0.1524)
		(layer "In5.Cu")
		(net "SSD_ACT_DR8")
	)
	(segment
		(start 43.58513 -181.464966)
		(end 52.832 -172.218096)
		(width 0.1524)
		(layer "In5.Cu")
		(net "SSD_ACT_DR8")
	)
	(segment
		(start 52.832 -146.3802)
		(end 52.5018 -146.05)
		(width 0.1524)
		(layer "In5.Cu")
		(net "SSD_ACT_DR8")
	)
	(segment
		(start 43.307 -241.9985)
		(end 43.095418 -242.210082)
		(width 0.17145)
		(layer "F.Cu")
		(net "SSD_ACT_DR7")
	)
	(segment
		(start 43.86707 -241.9985)
		(end 43.307 -241.9985)
		(width 0.17145)
		(layer "F.Cu")
		(net "SSD_ACT_DR7")
	)
	(segment
		(start 44.323 -243.84)
		(end 43.095418 -243.84)
		(width 0.17145)
		(layer "F.Cu")
		(net "SSD_ACT_DR7")
	)
	(segment
		(start 43.095418 -242.210082)
		(end 43.095418 -243.84)
		(width 0.17145)
		(layer "F.Cu")
		(net "SSD_ACT_DR7")
	)
	(segment
		(start 41.975024 -284.465014)
		(end 43.58513 -284.465014)
		(width 0.17145)
		(layer "F.Cu")
		(net "SSD_ACT_DR7")
	)
	(segment
		(start 45.212 -241.9985)
		(end 43.86707 -241.9985)
		(width 0.17145)
		(layer "F.Cu")
		(net "SSD_ACT_DR7")
	)
	(via
		(at 43.86707 -241.9985)
		(size 0.7112)
		(drill 0.3556)
		(layers "F.Cu" "B.Cu")
		(net "SSD_ACT_DR7")
	)
	(via
		(at 44.323 -243.84)
		(size 0.508)
		(drill 0.254)
		(layers "F.Cu" "B.Cu")
		(net "SSD_ACT_DR7")
	)
	(via
		(at 43.58513 -284.465014)
		(size 0.508)
		(drill 0.254)
		(layers "F.Cu" "B.Cu")
		(net "SSD_ACT_DR7")
	)
	(segment
		(start 44.323 -243.84)
		(end 52.2224 -251.7394)
		(width 0.1524)
		(layer "In5.Cu")
		(net "SSD_ACT_DR7")
	)
	(segment
		(start 52.2224 -251.7394)
		(end 52.2224 -275.827744)
		(width 0.1524)
		(layer "In5.Cu")
		(net "SSD_ACT_DR7")
	)
	(segment
		(start 52.2224 -275.827744)
		(end 43.58513 -284.465014)
		(width 0.1524)
		(layer "In5.Cu")
		(net "SSD_ACT_DR7")
	)
	(segment
		(start 43.981116 -347.151452)
		(end 44.08805 -347.258386)
		(width 0.17145)
		(layer "F.Cu")
		(net "SSD_ACT_DR6")
	)
	(segment
		(start 43.282108 -347.151452)
		(end 42.519854 -347.151452)
		(width 0.17145)
		(layer "F.Cu")
		(net "SSD_ACT_DR6")
	)
	(segment
		(start 44.93133 -347.258386)
		(end 44.590716 -347.258386)
		(width 0.17145)
		(layer "F.Cu")
		(net "SSD_ACT_DR6")
	)
	(segment
		(start 45.187616 -346.071952)
		(end 45.187616 -347.0021)
		(width 0.17145)
		(layer "F.Cu")
		(net "SSD_ACT_DR6")
	)
	(segment
		(start 43.282108 -347.151452)
		(end 43.981116 -347.151452)
		(width 0.17145)
		(layer "F.Cu")
		(net "SSD_ACT_DR6")
	)
	(segment
		(start 44.08805 -347.258386)
		(end 44.590716 -347.258386)
		(width 0.17145)
		(layer "F.Cu")
		(net "SSD_ACT_DR6")
	)
	(segment
		(start 41.975024 -387.465062)
		(end 43.58513 -387.465062)
		(width 0.17145)
		(layer "F.Cu")
		(net "SSD_ACT_DR6")
	)
	(segment
		(start 45.187616 -347.0021)
		(end 44.93133 -347.258386)
		(width 0.17145)
		(layer "F.Cu")
		(net "SSD_ACT_DR6")
	)
	(segment
		(start 42.519854 -347.151452)
		(end 42.494454 -347.176852)
		(width 0.17145)
		(layer "F.Cu")
		(net "SSD_ACT_DR6")
	)
	(via
		(at 44.590716 -347.258386)
		(size 0.7112)
		(drill 0.3556)
		(layers "F.Cu" "B.Cu")
		(net "SSD_ACT_DR6")
	)
	(via
		(at 42.494454 -347.176852)
		(size 0.508)
		(drill 0.254)
		(layers "F.Cu" "B.Cu")
		(net "SSD_ACT_DR6")
	)
	(via
		(at 43.58513 -387.465062)
		(size 0.508)
		(drill 0.254)
		(layers "F.Cu" "B.Cu")
		(net "SSD_ACT_DR6")
	)
	(segment
		(start 42.494454 -347.176852)
		(end 48.498252 -347.176852)
		(width 0.1524)
		(layer "In5.Cu")
		(net "SSD_ACT_DR6")
	)
	(segment
		(start 52.832 -351.5106)
		(end 52.832 -378.218192)
		(width 0.1524)
		(layer "In5.Cu")
		(net "SSD_ACT_DR6")
	)
	(segment
		(start 52.832 -378.218192)
		(end 43.58513 -387.465062)
		(width 0.1524)
		(layer "In5.Cu")
		(net "SSD_ACT_DR6")
	)
	(segment
		(start 48.498252 -347.176852)
		(end 52.832 -351.5106)
		(width 0.1524)
		(layer "In5.Cu")
		(net "SSD_ACT_DR6")
	)
	(segment
		(start 51.383946 -446.7225)
		(end 51.637946 -446.9765)
		(width 0.17145)
		(layer "F.Cu")
		(net "SSD_ACT_DR5")
	)
	(segment
		(start 49.4665 -445.262)
		(end 49.861216 -445.262)
		(width 0.17145)
		(layer "F.Cu")
		(net "SSD_ACT_DR5")
	)
	(segment
		(start 50.242216 -444.881)
		(end 51.167538 -444.881)
		(width 0.17145)
		(layer "F.Cu")
		(net "SSD_ACT_DR5")
	)
	(segment
		(start 50.850292 -446.7225)
		(end 51.383946 -446.7225)
		(width 0.17145)
		(layer "F.Cu")
		(net "SSD_ACT_DR5")
	)
	(segment
		(start 51.167538 -445.887348)
		(end 51.167538 -444.881)
		(width 0.17145)
		(layer "F.Cu")
		(net "SSD_ACT_DR5")
	)
	(segment
		(start 41.975024 -490.46511)
		(end 43.58513 -490.46511)
		(width 0.17145)
		(layer "F.Cu")
		(net "SSD_ACT_DR5")
	)
	(segment
		(start 49.861216 -445.262)
		(end 50.242216 -444.881)
		(width 0.17145)
		(layer "F.Cu")
		(net "SSD_ACT_DR5")
	)
	(segment
		(start 50.850292 -446.7225)
		(end 50.850292 -446.204594)
		(width 0.17145)
		(layer "F.Cu")
		(net "SSD_ACT_DR5")
	)
	(segment
		(start 50.850292 -446.204594)
		(end 51.167538 -445.887348)
		(width 0.17145)
		(layer "F.Cu")
		(net "SSD_ACT_DR5")
	)
	(via
		(at 51.167538 -444.881)
		(size 0.7112)
		(drill 0.3556)
		(layers "F.Cu" "B.Cu")
		(net "SSD_ACT_DR5")
	)
	(via
		(at 51.637946 -446.9765)
		(size 0.508)
		(drill 0.254)
		(layers "F.Cu" "B.Cu")
		(net "SSD_ACT_DR5")
	)
	(via
		(at 43.58513 -490.46511)
		(size 0.508)
		(drill 0.254)
		(layers "F.Cu" "B.Cu")
		(net "SSD_ACT_DR5")
	)
	(segment
		(start 51.637946 -446.9765)
		(end 52.1462 -447.484754)
		(width 0.1524)
		(layer "In5.Cu")
		(net "SSD_ACT_DR5")
	)
	(segment
		(start 52.1462 -447.484754)
		(end 52.1462 -452.7296)
		(width 0.1524)
		(layer "In5.Cu")
		(net "SSD_ACT_DR5")
	)
	(segment
		(start 52.1462 -452.7296)
		(end 52.832 -453.4154)
		(width 0.1524)
		(layer "In5.Cu")
		(net "SSD_ACT_DR5")
	)
	(segment
		(start 43.58513 -488.46867)
		(end 43.58513 -490.46511)
		(width 0.1524)
		(layer "In5.Cu")
		(net "SSD_ACT_DR5")
	)
	(segment
		(start 52.832 -453.4154)
		(end 52.832 -479.2218)
		(width 0.1524)
		(layer "In5.Cu")
		(net "SSD_ACT_DR5")
	)
	(segment
		(start 52.832 -479.2218)
		(end 43.58513 -488.46867)
		(width 0.1524)
		(layer "In5.Cu")
		(net "SSD_ACT_DR5")
	)
	(segment
		(start 226.974908 -78.464918)
		(end 228.585014 -78.464918)
		(width 0.17145)
		(layer "F.Cu")
		(net "SSD_ACT_DR4")
	)
	(segment
		(start 230.1875 -38.399974)
		(end 230.4415 -38.145974)
		(width 0.17145)
		(layer "F.Cu")
		(net "SSD_ACT_DR4")
	)
	(segment
		(start 228.510592 -38.278562)
		(end 227.748338 -38.278562)
		(width 0.17145)
		(layer "F.Cu")
		(net "SSD_ACT_DR4")
	)
	(segment
		(start 230.4415 -38.145974)
		(end 230.4415 -37.199062)
		(width 0.17145)
		(layer "F.Cu")
		(net "SSD_ACT_DR4")
	)
	(segment
		(start 229.800912 -38.399974)
		(end 230.1875 -38.399974)
		(width 0.17145)
		(layer "F.Cu")
		(net "SSD_ACT_DR4")
	)
	(segment
		(start 229.800912 -38.399974)
		(end 229.25532 -38.399974)
		(width 0.17145)
		(layer "F.Cu")
		(net "SSD_ACT_DR4")
	)
	(segment
		(start 229.133908 -38.278562)
		(end 228.510592 -38.278562)
		(width 0.17145)
		(layer "F.Cu")
		(net "SSD_ACT_DR4")
	)
	(segment
		(start 229.25532 -38.399974)
		(end 229.133908 -38.278562)
		(width 0.17145)
		(layer "F.Cu")
		(net "SSD_ACT_DR4")
	)
	(segment
		(start 227.748338 -38.278562)
		(end 227.722938 -38.303962)
		(width 0.17145)
		(layer "F.Cu")
		(net "SSD_ACT_DR4")
	)
	(via
		(at 227.722938 -38.303962)
		(size 0.508)
		(drill 0.254)
		(layers "F.Cu" "B.Cu")
		(net "SSD_ACT_DR4")
	)
	(via
		(at 229.800912 -38.399974)
		(size 0.7112)
		(drill 0.3556)
		(layers "F.Cu" "B.Cu")
		(net "SSD_ACT_DR4")
	)
	(via
		(at 228.585014 -78.464918)
		(size 0.508)
		(drill 0.254)
		(layers "F.Cu" "B.Cu")
		(net "SSD_ACT_DR4")
	)
	(segment
		(start 235.164884 -49.110138)
		(end 235.164884 -71.885048)
		(width 0.1524)
		(layer "In5.Cu")
		(net "SSD_ACT_DR4")
	)
	(segment
		(start 227.722938 -41.668192)
		(end 235.164884 -49.110138)
		(width 0.1524)
		(layer "In5.Cu")
		(net "SSD_ACT_DR4")
	)
	(segment
		(start 235.164884 -71.885048)
		(end 228.585014 -78.464918)
		(width 0.1524)
		(layer "In5.Cu")
		(net "SSD_ACT_DR4")
	)
	(segment
		(start 227.722938 -38.303962)
		(end 227.722938 -41.668192)
		(width 0.1524)
		(layer "In5.Cu")
		(net "SSD_ACT_DR4")
	)
	(segment
		(start 226.974908 -181.464966)
		(end 228.585014 -181.464966)
		(width 0.17145)
		(layer "F.Cu")
		(net "SSD_ACT_DR3")
	)
	(segment
		(start 228.848666 -141.27861)
		(end 228.283516 -141.27861)
		(width 0.17145)
		(layer "F.Cu")
		(net "SSD_ACT_DR3")
	)
	(segment
		(start 228.283516 -141.27861)
		(end 227.494338 -141.27861)
		(width 0.17145)
		(layer "F.Cu")
		(net "SSD_ACT_DR3")
	)
	(segment
		(start 229.546912 -141.400022)
		(end 229.996492 -141.400022)
		(width 0.17145)
		(layer "F.Cu")
		(net "SSD_ACT_DR3")
	)
	(segment
		(start 230.1875 -141.209014)
		(end 230.1875 -140.19911)
		(width 0.17145)
		(layer "F.Cu")
		(net "SSD_ACT_DR3")
	)
	(segment
		(start 229.996492 -141.400022)
		(end 230.1875 -141.209014)
		(width 0.17145)
		(layer "F.Cu")
		(net "SSD_ACT_DR3")
	)
	(segment
		(start 228.970078 -141.400022)
		(end 228.848666 -141.27861)
		(width 0.17145)
		(layer "F.Cu")
		(net "SSD_ACT_DR3")
	)
	(segment
		(start 229.546912 -141.400022)
		(end 228.970078 -141.400022)
		(width 0.17145)
		(layer "F.Cu")
		(net "SSD_ACT_DR3")
	)
	(segment
		(start 227.494338 -141.27861)
		(end 227.468938 -141.30401)
		(width 0.17145)
		(layer "F.Cu")
		(net "SSD_ACT_DR3")
	)
	(via
		(at 227.468938 -141.30401)
		(size 0.508)
		(drill 0.254)
		(layers "F.Cu" "B.Cu")
		(net "SSD_ACT_DR3")
	)
	(via
		(at 228.585014 -181.464966)
		(size 0.508)
		(drill 0.254)
		(layers "F.Cu" "B.Cu")
		(net "SSD_ACT_DR3")
	)
	(via
		(at 229.546912 -141.400022)
		(size 0.7112)
		(drill 0.3556)
		(layers "F.Cu" "B.Cu")
		(net "SSD_ACT_DR3")
	)
	(segment
		(start 228.585014 -181.464966)
		(end 234.7722 -175.27778)
		(width 0.1524)
		(layer "In5.Cu")
		(net "SSD_ACT_DR3")
	)
	(segment
		(start 227.468938 -142.633192)
		(end 227.468938 -141.30401)
		(width 0.1524)
		(layer "In5.Cu")
		(net "SSD_ACT_DR3")
	)
	(segment
		(start 234.7722 -175.27778)
		(end 234.7722 -149.936454)
		(width 0.1524)
		(layer "In5.Cu")
		(net "SSD_ACT_DR3")
	)
	(segment
		(start 234.7722 -149.936454)
		(end 227.468938 -142.633192)
		(width 0.1524)
		(layer "In5.Cu")
		(net "SSD_ACT_DR3")
	)
	(segment
		(start 229.9335 -244.40007)
		(end 230.1875 -244.14607)
		(width 0.17145)
		(layer "F.Cu")
		(net "SSD_ACT_DR2")
	)
	(segment
		(start 228.896418 -244.278658)
		(end 229.01783 -244.40007)
		(width 0.17145)
		(layer "F.Cu")
		(net "SSD_ACT_DR2")
	)
	(segment
		(start 229.01783 -244.40007)
		(end 229.546912 -244.40007)
		(width 0.17145)
		(layer "F.Cu")
		(net "SSD_ACT_DR2")
	)
	(segment
		(start 230.1875 -244.14607)
		(end 230.1875 -243.199158)
		(width 0.17145)
		(layer "F.Cu")
		(net "SSD_ACT_DR2")
	)
	(segment
		(start 227.494338 -244.278658)
		(end 227.468938 -244.304058)
		(width 0.17145)
		(layer "F.Cu")
		(net "SSD_ACT_DR2")
	)
	(segment
		(start 228.256592 -244.278658)
		(end 227.494338 -244.278658)
		(width 0.17145)
		(layer "F.Cu")
		(net "SSD_ACT_DR2")
	)
	(segment
		(start 229.546912 -244.40007)
		(end 229.9335 -244.40007)
		(width 0.17145)
		(layer "F.Cu")
		(net "SSD_ACT_DR2")
	)
	(segment
		(start 228.256592 -244.278658)
		(end 228.896418 -244.278658)
		(width 0.17145)
		(layer "F.Cu")
		(net "SSD_ACT_DR2")
	)
	(segment
		(start 226.974908 -284.465014)
		(end 228.585014 -284.465014)
		(width 0.17145)
		(layer "F.Cu")
		(net "SSD_ACT_DR2")
	)
	(via
		(at 228.585014 -284.465014)
		(size 0.508)
		(drill 0.254)
		(layers "F.Cu" "B.Cu")
		(net "SSD_ACT_DR2")
	)
	(via
		(at 229.546912 -244.40007)
		(size 0.7112)
		(drill 0.3556)
		(layers "F.Cu" "B.Cu")
		(net "SSD_ACT_DR2")
	)
	(via
		(at 227.468938 -244.304058)
		(size 0.508)
		(drill 0.254)
		(layers "F.Cu" "B.Cu")
		(net "SSD_ACT_DR2")
	)
	(segment
		(start 231.558084 -281.491944)
		(end 231.558084 -248.393204)
		(width 0.1524)
		(layer "In5.Cu")
		(net "SSD_ACT_DR2")
	)
	(segment
		(start 228.585014 -284.465014)
		(end 231.558084 -281.491944)
		(width 0.1524)
		(layer "In5.Cu")
		(net "SSD_ACT_DR2")
	)
	(segment
		(start 231.558084 -248.393204)
		(end 227.468938 -244.304058)
		(width 0.1524)
		(layer "In5.Cu")
		(net "SSD_ACT_DR2")
	)
	(segment
		(start 19.4945 -60.004452)
		(end 19.4945 -59.517788)
		(width 0.17145)
		(layer "F.Cu")
		(net "SSD_ACT_DR14")
	)
	(segment
		(start 19.939 -60.448952)
		(end 19.4945 -60.004452)
		(width 0.17145)
		(layer "F.Cu")
		(net "SSD_ACT_DR14")
	)
	(segment
		(start 20.025106 -15.534894)
		(end 18.415 -15.534894)
		(width 0.17145)
		(layer "F.Cu")
		(net "SSD_ACT_DR14")
	)
	(segment
		(start 17.907 -62.353952)
		(end 17.907 -61.718952)
		(width 0.17145)
		(layer "F.Cu")
		(net "SSD_ACT_DR14")
	)
	(segment
		(start 18.1356 -62.582552)
		(end 17.907 -62.353952)
		(width 0.17145)
		(layer "F.Cu")
		(net "SSD_ACT_DR14")
	)
	(segment
		(start 19.939 -60.88761)
		(end 19.939 -60.448952)
		(width 0.17145)
		(layer "F.Cu")
		(net "SSD_ACT_DR14")
	)
	(segment
		(start 19.7104 -62.582552)
		(end 18.976594 -62.582552)
		(width 0.17145)
		(layer "F.Cu")
		(net "SSD_ACT_DR14")
	)
	(segment
		(start 19.939 -60.88761)
		(end 19.939 -62.353952)
		(width 0.17145)
		(layer "F.Cu")
		(net "SSD_ACT_DR14")
	)
	(segment
		(start 18.976594 -62.582552)
		(end 18.1356 -62.582552)
		(width 0.17145)
		(layer "F.Cu")
		(net "SSD_ACT_DR14")
	)
	(segment
		(start 19.939 -62.353952)
		(end 19.7104 -62.582552)
		(width 0.17145)
		(layer "F.Cu")
		(net "SSD_ACT_DR14")
	)
	(via
		(at 18.415 -15.534894)
		(size 0.508)
		(drill 0.254)
		(layers "F.Cu" "B.Cu")
		(net "SSD_ACT_DR14")
	)
	(via
		(at 17.907 -61.718952)
		(size 0.508)
		(drill 0.254)
		(layers "F.Cu" "B.Cu")
		(net "SSD_ACT_DR14")
	)
	(via
		(at 18.976594 -62.582552)
		(size 0.7112)
		(drill 0.3556)
		(layers "F.Cu" "B.Cu")
		(net "SSD_ACT_DR14")
	)
	(segment
		(start 17.907 -60.071)
		(end 16.256 -58.42)
		(width 0.1524)
		(layer "In5.Cu")
		(net "SSD_ACT_DR14")
	)
	(segment
		(start 16.256 -17.693894)
		(end 18.415 -15.534894)
		(width 0.1524)
		(layer "In5.Cu")
		(net "SSD_ACT_DR14")
	)
	(segment
		(start 16.256 -58.42)
		(end 16.256 -17.693894)
		(width 0.1524)
		(layer "In5.Cu")
		(net "SSD_ACT_DR14")
	)
	(segment
		(start 17.907 -61.718952)
		(end 17.907 -60.071)
		(width 0.1524)
		(layer "In5.Cu")
		(net "SSD_ACT_DR14")
	)
	(segment
		(start 19.939 -163.887658)
		(end 19.939 -165.354)
		(width 0.17145)
		(layer "F.Cu")
		(net "SSD_ACT_DR13")
	)
	(segment
		(start 19.7104 -165.5826)
		(end 18.976594 -165.5826)
		(width 0.17145)
		(layer "F.Cu")
		(net "SSD_ACT_DR13")
	)
	(segment
		(start 19.4945 -163.0045)
		(end 19.939 -163.449)
		(width 0.17145)
		(layer "F.Cu")
		(net "SSD_ACT_DR13")
	)
	(segment
		(start 18.976594 -165.5826)
		(end 18.1356 -165.5826)
		(width 0.17145)
		(layer "F.Cu")
		(net "SSD_ACT_DR13")
	)
	(segment
		(start 18.1356 -165.5826)
		(end 17.907 -165.354)
		(width 0.17145)
		(layer "F.Cu")
		(net "SSD_ACT_DR13")
	)
	(segment
		(start 19.4945 -162.517836)
		(end 19.4945 -163.0045)
		(width 0.17145)
		(layer "F.Cu")
		(net "SSD_ACT_DR13")
	)
	(segment
		(start 20.025106 -118.534942)
		(end 18.415 -118.534942)
		(width 0.17145)
		(layer "F.Cu")
		(net "SSD_ACT_DR13")
	)
	(segment
		(start 19.939 -163.449)
		(end 19.939 -163.887658)
		(width 0.17145)
		(layer "F.Cu")
		(net "SSD_ACT_DR13")
	)
	(segment
		(start 19.939 -165.354)
		(end 19.7104 -165.5826)
		(width 0.17145)
		(layer "F.Cu")
		(net "SSD_ACT_DR13")
	)
	(segment
		(start 17.907 -165.354)
		(end 17.907 -164.719)
		(width 0.17145)
		(layer "F.Cu")
		(net "SSD_ACT_DR13")
	)
	(via
		(at 17.907 -164.719)
		(size 0.508)
		(drill 0.254)
		(layers "F.Cu" "B.Cu")
		(net "SSD_ACT_DR13")
	)
	(via
		(at 18.976594 -165.5826)
		(size 0.7112)
		(drill 0.3556)
		(layers "F.Cu" "B.Cu")
		(net "SSD_ACT_DR13")
	)
	(via
		(at 18.415 -118.534942)
		(size 0.508)
		(drill 0.254)
		(layers "F.Cu" "B.Cu")
		(net "SSD_ACT_DR13")
	)
	(segment
		(start 22.987 -123.106942)
		(end 18.415 -118.534942)
		(width 0.1524)
		(layer "In5.Cu")
		(net "SSD_ACT_DR13")
	)
	(segment
		(start 17.907 -164.719)
		(end 17.907 -161.036)
		(width 0.1524)
		(layer "In5.Cu")
		(net "SSD_ACT_DR13")
	)
	(segment
		(start 22.987 -151.97582)
		(end 22.987 -123.106942)
		(width 0.1524)
		(layer "In5.Cu")
		(net "SSD_ACT_DR13")
	)
	(segment
		(start 17.907 -161.036)
		(end 19.494754 -159.448246)
		(width 0.1524)
		(layer "In5.Cu")
		(net "SSD_ACT_DR13")
	)
	(segment
		(start 19.494754 -155.468066)
		(end 22.987 -151.97582)
		(width 0.1524)
		(layer "In5.Cu")
		(net "SSD_ACT_DR13")
	)
	(segment
		(start 19.494754 -159.448246)
		(end 19.494754 -155.468066)
		(width 0.1524)
		(layer "In5.Cu")
		(net "SSD_ACT_DR13")
	)
	(segment
		(start 20.025106 -221.53499)
		(end 18.415 -221.53499)
		(width 0.17145)
		(layer "F.Cu")
		(net "SSD_ACT_DR12")
	)
	(segment
		(start 19.7485 -266.544044)
		(end 19.275044 -266.544044)
		(width 0.17145)
		(layer "F.Cu")
		(net "SSD_ACT_DR12")
	)
	(segment
		(start 19.275044 -266.544044)
		(end 18.796 -266.065)
		(width 0.17145)
		(layer "F.Cu")
		(net "SSD_ACT_DR12")
	)
	(segment
		(start 19.7485 -265.26363)
		(end 19.7485 -266.544044)
		(width 0.17145)
		(layer "F.Cu")
		(net "SSD_ACT_DR12")
	)
	(via
		(at 18.796 -266.065)
		(size 0.508)
		(drill 0.254)
		(layers "F.Cu" "B.Cu")
		(net "SSD_ACT_DR12")
	)
	(via
		(at 16.637 -235.585)
		(size 0.508)
		(drill 0.254)
		(layers "F.Cu" "B.Cu")
		(net "SSD_ACT_DR12")
	)
	(via
		(at 18.415 -221.53499)
		(size 0.508)
		(drill 0.254)
		(layers "F.Cu" "B.Cu")
		(net "SSD_ACT_DR12")
	)
	(via
		(at 14.224 -245.618)
		(size 0.7112)
		(drill 0.3556)
		(layers "F.Cu" "B.Cu")
		(net "SSD_ACT_DR12")
	)
	(segment
		(start 18.796 -266.065)
		(end 19.4945 -265.3665)
		(width 0.17145)
		(layer "B.Cu")
		(net "SSD_ACT_DR12")
	)
	(segment
		(start 16.646398 -257.737864)
		(end 16.056864 -257.737864)
		(width 0.17145)
		(layer "B.Cu")
		(net "SSD_ACT_DR12")
	)
	(segment
		(start 14.224 -237.998)
		(end 16.637 -235.585)
		(width 0.17145)
		(layer "B.Cu")
		(net "SSD_ACT_DR12")
	)
	(segment
		(start 16.056864 -257.737864)
		(end 14.224 -255.905)
		(width 0.17145)
		(layer "B.Cu")
		(net "SSD_ACT_DR12")
	)
	(segment
		(start 14.224 -255.905)
		(end 14.224 -245.618)
		(width 0.17145)
		(layer "B.Cu")
		(net "SSD_ACT_DR12")
	)
	(segment
		(start 14.224 -245.618)
		(end 14.224 -237.998)
		(width 0.17145)
		(layer "B.Cu")
		(net "SSD_ACT_DR12")
	)
	(segment
		(start 19.4945 -265.3665)
		(end 19.4945 -260.585966)
		(width 0.17145)
		(layer "B.Cu")
		(net "SSD_ACT_DR12")
	)
	(segment
		(start 19.4945 -260.585966)
		(end 16.646398 -257.737864)
		(width 0.17145)
		(layer "B.Cu")
		(net "SSD_ACT_DR12")
	)
	(segment
		(start 16.637 -223.31299)
		(end 18.415 -221.53499)
		(width 0.1524)
		(layer "In5.Cu")
		(net "SSD_ACT_DR12")
	)
	(segment
		(start 16.637 -235.585)
		(end 16.637 -223.31299)
		(width 0.1524)
		(layer "In5.Cu")
		(net "SSD_ACT_DR12")
	)
	(segment
		(start 20.025106 -324.535038)
		(end 18.415 -324.535038)
		(width 0.17145)
		(layer "F.Cu")
		(net "SSD_ACT_DR11")
	)
	(segment
		(start 19.4945 -369.5954)
		(end 19.4945 -368.517678)
		(width 0.17145)
		(layer "F.Cu")
		(net "SSD_ACT_DR11")
	)
	(segment
		(start 18.542 -369.5954)
		(end 19.4945 -369.5954)
		(width 0.17145)
		(layer "F.Cu")
		(net "SSD_ACT_DR11")
	)
	(via
		(at 18.542 -369.5954)
		(size 0.508)
		(drill 0.254)
		(layers "F.Cu" "B.Cu")
		(net "SSD_ACT_DR11")
	)
	(via
		(at 18.415 -324.535038)
		(size 0.508)
		(drill 0.254)
		(layers "F.Cu" "B.Cu")
		(net "SSD_ACT_DR11")
	)
	(via
		(at 20.16506 -337.078828)
		(size 0.7112)
		(drill 0.3556)
		(layers "F.Cu" "B.Cu")
		(net "SSD_ACT_DR11")
	)
	(segment
		(start 18.542 -369.5954)
		(end 19.048984 -369.088416)
		(width 0.17145)
		(layer "B.Cu")
		(net "SSD_ACT_DR11")
	)
	(segment
		(start 15.113 -341.63)
		(end 16.764 -339.979)
		(width 0.17145)
		(layer "B.Cu")
		(net "SSD_ACT_DR11")
	)
	(segment
		(start 15.113 -358.173274)
		(end 15.113 -341.63)
		(width 0.17145)
		(layer "B.Cu")
		(net "SSD_ACT_DR11")
	)
	(segment
		(start 21.941536 -365.00181)
		(end 15.113 -358.173274)
		(width 0.17145)
		(layer "B.Cu")
		(net "SSD_ACT_DR11")
	)
	(segment
		(start 21.941536 -368.113818)
		(end 21.941536 -365.00181)
		(width 0.17145)
		(layer "B.Cu")
		(net "SSD_ACT_DR11")
	)
	(segment
		(start 20.16506 -326.285098)
		(end 18.415 -324.535038)
		(width 0.17145)
		(layer "B.Cu")
		(net "SSD_ACT_DR11")
	)
	(segment
		(start 20.966938 -369.088416)
		(end 21.941536 -368.113818)
		(width 0.17145)
		(layer "B.Cu")
		(net "SSD_ACT_DR11")
	)
	(segment
		(start 16.764 -339.979)
		(end 18.669 -339.979)
		(width 0.17145)
		(layer "B.Cu")
		(net "SSD_ACT_DR11")
	)
	(segment
		(start 19.048984 -369.088416)
		(end 20.966938 -369.088416)
		(width 0.17145)
		(layer "B.Cu")
		(net "SSD_ACT_DR11")
	)
	(segment
		(start 20.16506 -337.078828)
		(end 20.16506 -326.285098)
		(width 0.17145)
		(layer "B.Cu")
		(net "SSD_ACT_DR11")
	)
	(segment
		(start 18.669 -339.979)
		(end 20.16506 -338.48294)
		(width 0.17145)
		(layer "B.Cu")
		(net "SSD_ACT_DR11")
	)
	(segment
		(start 20.16506 -338.48294)
		(end 20.16506 -337.078828)
		(width 0.17145)
		(layer "B.Cu")
		(net "SSD_ACT_DR11")
	)
	(segment
		(start 20.025106 -427.535086)
		(end 18.415 -427.535086)
		(width 0.17145)
		(layer "F.Cu")
		(net "SSD_ACT_DR10")
	)
	(segment
		(start 25.8699 -467.3346)
		(end 24.8539 -467.3346)
		(width 0.17145)
		(layer "F.Cu")
		(net "SSD_ACT_DR10")
	)
	(segment
		(start 24.892 -469.5952)
		(end 24.8539 -469.5571)
		(width 0.17145)
		(layer "F.Cu")
		(net "SSD_ACT_DR10")
	)
	(segment
		(start 24.8539 -469.5571)
		(end 24.8539 -467.3346)
		(width 0.17145)
		(layer "F.Cu")
		(net "SSD_ACT_DR10")
	)
	(via
		(at 24.892 -469.5952)
		(size 0.508)
		(drill 0.254)
		(layers "F.Cu" "B.Cu")
		(net "SSD_ACT_DR10")
	)
	(via
		(at 14.097 -447.802)
		(size 0.7112)
		(drill 0.3556)
		(layers "F.Cu" "B.Cu")
		(net "SSD_ACT_DR10")
	)
	(via
		(at 17.018 -441.452)
		(size 0.508)
		(drill 0.254)
		(layers "F.Cu" "B.Cu")
		(net "SSD_ACT_DR10")
	)
	(via
		(at 18.415 -427.535086)
		(size 0.508)
		(drill 0.254)
		(layers "F.Cu" "B.Cu")
		(net "SSD_ACT_DR10")
	)
	(segment
		(start 17.399 -453.0852)
		(end 14.097 -449.7832)
		(width 0.17145)
		(layer "B.Cu")
		(net "SSD_ACT_DR10")
	)
	(segment
		(start 14.097 -442.595)
		(end 14.097 -447.802)
		(width 0.17145)
		(layer "B.Cu")
		(net "SSD_ACT_DR10")
	)
	(segment
		(start 15.24 -441.452)
		(end 14.097 -442.595)
		(width 0.17145)
		(layer "B.Cu")
		(net "SSD_ACT_DR10")
	)
	(segment
		(start 14.097 -449.7832)
		(end 14.097 -447.802)
		(width 0.17145)
		(layer "B.Cu")
		(net "SSD_ACT_DR10")
	)
	(segment
		(start 24.892 -469.5952)
		(end 24.886158 -469.589358)
		(width 0.17145)
		(layer "B.Cu")
		(net "SSD_ACT_DR10")
	)
	(segment
		(start 24.3586 -457.454)
		(end 19.9898 -453.0852)
		(width 0.17145)
		(layer "B.Cu")
		(net "SSD_ACT_DR10")
	)
	(segment
		(start 24.886158 -465.621116)
		(end 24.3586 -465.093558)
		(width 0.17145)
		(layer "B.Cu")
		(net "SSD_ACT_DR10")
	)
	(segment
		(start 24.3586 -465.093558)
		(end 24.3586 -457.454)
		(width 0.17145)
		(layer "B.Cu")
		(net "SSD_ACT_DR10")
	)
	(segment
		(start 17.018 -441.452)
		(end 15.24 -441.452)
		(width 0.17145)
		(layer "B.Cu")
		(net "SSD_ACT_DR10")
	)
	(segment
		(start 24.886158 -469.589358)
		(end 24.886158 -465.621116)
		(width 0.17145)
		(layer "B.Cu")
		(net "SSD_ACT_DR10")
	)
	(segment
		(start 19.9898 -453.0852)
		(end 17.399 -453.0852)
		(width 0.17145)
		(layer "B.Cu")
		(net "SSD_ACT_DR10")
	)
	(segment
		(start 17.018 -441.452)
		(end 17.653 -440.817)
		(width 0.1524)
		(layer "In5.Cu")
		(net "SSD_ACT_DR10")
	)
	(segment
		(start 17.653 -440.817)
		(end 17.653 -428.297086)
		(width 0.1524)
		(layer "In5.Cu")
		(net "SSD_ACT_DR10")
	)
	(segment
		(start 17.653 -428.297086)
		(end 18.415 -427.535086)
		(width 0.1524)
		(layer "In5.Cu")
		(net "SSD_ACT_DR10")
	)
	(segment
		(start 228.281992 -347.278452)
		(end 228.981 -347.278452)
		(width 0.17145)
		(layer "F.Cu")
		(net "SSD_ACT_DR1")
	)
	(segment
		(start 228.981 -347.278452)
		(end 229.087934 -347.385386)
		(width 0.17145)
		(layer "F.Cu")
		(net "SSD_ACT_DR1")
	)
	(segment
		(start 228.281992 -347.278452)
		(end 227.519738 -347.278452)
		(width 0.17145)
		(layer "F.Cu")
		(net "SSD_ACT_DR1")
	)
	(segment
		(start 229.087934 -347.385386)
		(end 229.5906 -347.385386)
		(width 0.17145)
		(layer "F.Cu")
		(net "SSD_ACT_DR1")
	)
	(segment
		(start 230.1875 -347.1291)
		(end 230.1875 -346.198952)
		(width 0.17145)
		(layer "F.Cu")
		(net "SSD_ACT_DR1")
	)
	(segment
		(start 227.519738 -347.278452)
		(end 227.494338 -347.303852)
		(width 0.17145)
		(layer "F.Cu")
		(net "SSD_ACT_DR1")
	)
	(segment
		(start 226.974908 -387.465062)
		(end 228.585014 -387.465062)
		(width 0.17145)
		(layer "F.Cu")
		(net "SSD_ACT_DR1")
	)
	(segment
		(start 229.5906 -347.385386)
		(end 229.931214 -347.385386)
		(width 0.17145)
		(layer "F.Cu")
		(net "SSD_ACT_DR1")
	)
	(segment
		(start 229.931214 -347.385386)
		(end 230.1875 -347.1291)
		(width 0.17145)
		(layer "F.Cu")
		(net "SSD_ACT_DR1")
	)
	(via
		(at 227.494338 -347.303852)
		(size 0.508)
		(drill 0.254)
		(layers "F.Cu" "B.Cu")
		(net "SSD_ACT_DR1")
	)
	(via
		(at 229.5906 -347.385386)
		(size 0.7112)
		(drill 0.3556)
		(layers "F.Cu" "B.Cu")
		(net "SSD_ACT_DR1")
	)
	(via
		(at 228.585014 -387.465062)
		(size 0.508)
		(drill 0.254)
		(layers "F.Cu" "B.Cu")
		(net "SSD_ACT_DR1")
	)
	(segment
		(start 235.2802 -380.769876)
		(end 228.585014 -387.465062)
		(width 0.1524)
		(layer "In5.Cu")
		(net "SSD_ACT_DR1")
	)
	(segment
		(start 235.2802 -355.089714)
		(end 235.2802 -380.769876)
		(width 0.1524)
		(layer "In5.Cu")
		(net "SSD_ACT_DR1")
	)
	(segment
		(start 227.494338 -347.303852)
		(end 235.2802 -355.089714)
		(width 0.1524)
		(layer "In5.Cu")
		(net "SSD_ACT_DR1")
	)
	(segment
		(start 229.108 -450.399912)
		(end 229.546912 -450.399912)
		(width 0.17145)
		(layer "F.Cu")
		(net "SSD_ACT_DR0")
	)
	(segment
		(start 227.494338 -450.2785)
		(end 227.468938 -450.3039)
		(width 0.17145)
		(layer "F.Cu")
		(net "SSD_ACT_DR0")
	)
	(segment
		(start 229.9335 -450.399912)
		(end 230.1875 -450.145912)
		(width 0.17145)
		(layer "F.Cu")
		(net "SSD_ACT_DR0")
	)
	(segment
		(start 228.986588 -450.2785)
		(end 229.108 -450.399912)
		(width 0.17145)
		(layer "F.Cu")
		(net "SSD_ACT_DR0")
	)
	(segment
		(start 228.2952 -450.2785)
		(end 228.986588 -450.2785)
		(width 0.17145)
		(layer "F.Cu")
		(net "SSD_ACT_DR0")
	)
	(segment
		(start 230.1875 -450.145912)
		(end 230.1875 -449.199)
		(width 0.17145)
		(layer "F.Cu")
		(net "SSD_ACT_DR0")
	)
	(segment
		(start 229.546912 -450.399912)
		(end 229.9335 -450.399912)
		(width 0.17145)
		(layer "F.Cu")
		(net "SSD_ACT_DR0")
	)
	(segment
		(start 228.2952 -450.2785)
		(end 227.494338 -450.2785)
		(width 0.17145)
		(layer "F.Cu")
		(net "SSD_ACT_DR0")
	)
	(segment
		(start 226.974908 -490.46511)
		(end 228.585014 -490.46511)
		(width 0.17145)
		(layer "F.Cu")
		(net "SSD_ACT_DR0")
	)
	(via
		(at 227.468938 -450.3039)
		(size 0.508)
		(drill 0.254)
		(layers "F.Cu" "B.Cu")
		(net "SSD_ACT_DR0")
	)
	(via
		(at 228.585014 -490.46511)
		(size 0.508)
		(drill 0.254)
		(layers "F.Cu" "B.Cu")
		(net "SSD_ACT_DR0")
	)
	(via
		(at 229.546912 -450.399912)
		(size 0.7112)
		(drill 0.3556)
		(layers "F.Cu" "B.Cu")
		(net "SSD_ACT_DR0")
	)
	(segment
		(start 228.585014 -490.46511)
		(end 232.2576 -486.792524)
		(width 0.1524)
		(layer "In5.Cu")
		(net "SSD_ACT_DR0")
	)
	(segment
		(start 232.2576 -486.792524)
		(end 232.2576 -455.092562)
		(width 0.1524)
		(layer "In5.Cu")
		(net "SSD_ACT_DR0")
	)
	(segment
		(start 232.2576 -455.092562)
		(end 227.468938 -450.3039)
		(width 0.1524)
		(layer "In5.Cu")
		(net "SSD_ACT_DR0")
	)
	(segment
		(start 12.192 -479.204782)
		(end 11.904472 -479.49231)
		(width 0.17145)
		(layer "F.Cu")
		(net "SELF_TRAY_PRESENT")
	)
	(segment
		(start 12.192 -478.5995)
		(end 12.192 -479.204782)
		(width 0.17145)
		(layer "F.Cu")
		(net "SELF_TRAY_PRESENT")
	)
	(via
		(at 11.904472 -479.49231)
		(size 0.508)
		(drill 0.254)
		(layers "F.Cu" "B.Cu")
		(net "SELF_TRAY_PRESENT")
	)
	(via
		(at 17.9451 -482.039168)
		(size 0.7112)
		(drill 0.3556)
		(layers "F.Cu" "B.Cu")
		(net "SELF_TRAY_PRESENT")
	)
	(segment
		(start 240.62055 -427.69155)
		(end 238.379 -425.45)
		(width 0.17145)
		(layer "B.Cu")
		(net "SELF_TRAY_PRESENT")
	)
	(segment
		(start 17.9451 -482.039168)
		(end 19.905726 -482.039168)
		(width 0.17145)
		(layer "B.Cu")
		(net "SELF_TRAY_PRESENT")
	)
	(segment
		(start 238.379 -425.45)
		(end 238.379 -419.354)
		(width 0.17145)
		(layer "B.Cu")
		(net "SELF_TRAY_PRESENT")
	)
	(segment
		(start 253.847092 -418.109908)
		(end 256.093976 -418.109908)
		(width 0.17145)
		(layer "B.Cu")
		(net "SELF_TRAY_PRESENT")
	)
	(segment
		(start 184.960006 -496.062)
		(end 221.44355 -459.578456)
		(width 0.17145)
		(layer "B.Cu")
		(net "SELF_TRAY_PRESENT")
	)
	(segment
		(start 33.928558 -496.062)
		(end 184.960006 -496.062)
		(width 0.17145)
		(layer "B.Cu")
		(net "SELF_TRAY_PRESENT")
	)
	(segment
		(start 238.379 -419.354)
		(end 238.905542 -418.827458)
		(width 0.17145)
		(layer "B.Cu")
		(net "SELF_TRAY_PRESENT")
	)
	(segment
		(start 17.9451 -482.039168)
		(end 13.658088 -482.039168)
		(width 0.17145)
		(layer "B.Cu")
		(net "SELF_TRAY_PRESENT")
	)
	(segment
		(start 229.638606 -446.0494)
		(end 236.877606 -446.0494)
		(width 0.17145)
		(layer "B.Cu")
		(net "SELF_TRAY_PRESENT")
	)
	(segment
		(start 238.905542 -418.827458)
		(end 253.129542 -418.827458)
		(width 0.17145)
		(layer "B.Cu")
		(net "SELF_TRAY_PRESENT")
	)
	(segment
		(start 253.129542 -418.827458)
		(end 253.847092 -418.109908)
		(width 0.17145)
		(layer "B.Cu")
		(net "SELF_TRAY_PRESENT")
	)
	(segment
		(start 221.44355 -459.578456)
		(end 221.44355 -454.244456)
		(width 0.17145)
		(layer "B.Cu")
		(net "SELF_TRAY_PRESENT")
	)
	(segment
		(start 11.904472 -480.285552)
		(end 11.904472 -479.49231)
		(width 0.17145)
		(layer "B.Cu")
		(net "SELF_TRAY_PRESENT")
	)
	(segment
		(start 13.658088 -482.039168)
		(end 11.904472 -480.285552)
		(width 0.17145)
		(layer "B.Cu")
		(net "SELF_TRAY_PRESENT")
	)
	(segment
		(start 240.62055 -442.306456)
		(end 240.62055 -427.69155)
		(width 0.17145)
		(layer "B.Cu")
		(net "SELF_TRAY_PRESENT")
	)
	(segment
		(start 221.44355 -454.244456)
		(end 229.638606 -446.0494)
		(width 0.17145)
		(layer "B.Cu")
		(net "SELF_TRAY_PRESENT")
	)
	(segment
		(start 19.905726 -482.039168)
		(end 33.928558 -496.062)
		(width 0.17145)
		(layer "B.Cu")
		(net "SELF_TRAY_PRESENT")
	)
	(segment
		(start 236.877606 -446.0494)
		(end 240.62055 -442.306456)
		(width 0.17145)
		(layer "B.Cu")
		(net "SELF_TRAY_PRESENT")
	)
	(segment
		(start 247.83161 -427.30039)
		(end 250.672092 -424.459908)
		(width 0.17145)
		(layer "F.Cu")
		(net "SELF_1A&2A_HB")
	)
	(segment
		(start 250.672092 -424.459908)
		(end 256.474976 -424.459908)
		(width 0.17145)
		(layer "F.Cu")
		(net "SELF_1A&2A_HB")
	)
	(segment
		(start 237.44555 -427.30039)
		(end 247.83161 -427.30039)
		(width 0.17145)
		(layer "F.Cu")
		(net "SELF_1A&2A_HB")
	)
	(via
		(at 237.44555 -427.30039)
		(size 0.508)
		(drill 0.254)
		(layers "F.Cu" "B.Cu")
		(net "SELF_1A&2A_HB")
	)
	(via
		(at 238.633 -431.292)
		(size 0.7112)
		(drill 0.3556)
		(layers "F.Cu" "B.Cu")
		(net "SELF_1A&2A_HB")
	)
	(segment
		(start 32.07131 -491.744)
		(end 20.423886 -480.096576)
		(width 0.17145)
		(layer "B.Cu")
		(net "SELF_1A&2A_HB")
	)
	(segment
		(start 237.44555 -427.30039)
		(end 238.633 -428.48784)
		(width 0.17145)
		(layer "B.Cu")
		(net "SELF_1A&2A_HB")
	)
	(segment
		(start 35.635946 -494.32845)
		(end 33.051496 -491.744)
		(width 0.17145)
		(layer "B.Cu")
		(net "SELF_1A&2A_HB")
	)
	(segment
		(start 3.943858 -453.67575)
		(end 3.81 -453.541892)
		(width 0.17145)
		(layer "B.Cu")
		(net "SELF_1A&2A_HB")
	)
	(segment
		(start 219.62745 -458.825854)
		(end 184.124854 -494.32845)
		(width 0.17145)
		(layer "B.Cu")
		(net "SELF_1A&2A_HB")
	)
	(segment
		(start 184.124854 -494.32845)
		(end 35.635946 -494.32845)
		(width 0.17145)
		(layer "B.Cu")
		(net "SELF_1A&2A_HB")
	)
	(segment
		(start 219.62745 -453.491854)
		(end 219.62745 -458.825854)
		(width 0.17145)
		(layer "B.Cu")
		(net "SELF_1A&2A_HB")
	)
	(segment
		(start 14.3129 -477.342708)
		(end 14.659102 -476.996506)
		(width 0.17145)
		(layer "B.Cu")
		(net "SELF_1A&2A_HB")
	)
	(segment
		(start 14.659102 -473.23121)
		(end 14.636496 -473.208604)
		(width 0.17145)
		(layer "B.Cu")
		(net "SELF_1A&2A_HB")
	)
	(segment
		(start 236.042454 -444.31585)
		(end 228.803454 -444.31585)
		(width 0.17145)
		(layer "B.Cu")
		(net "SELF_1A&2A_HB")
	)
	(segment
		(start 238.633 -428.48784)
		(end 238.633 -431.292)
		(width 0.17145)
		(layer "B.Cu")
		(net "SELF_1A&2A_HB")
	)
	(segment
		(start 14.636496 -473.208604)
		(end 14.636242 -473.208604)
		(width 0.17145)
		(layer "B.Cu")
		(net "SELF_1A&2A_HB")
	)
	(segment
		(start 6.879336 -455.3458)
		(end 5.209286 -453.67575)
		(width 0.17145)
		(layer "B.Cu")
		(net "SELF_1A&2A_HB")
	)
	(segment
		(start 3.81 -453.541892)
		(end 1.868932 -453.541892)
		(width 0.17145)
		(layer "B.Cu")
		(net "SELF_1A&2A_HB")
	)
	(segment
		(start 238.633 -441.725304)
		(end 236.042454 -444.31585)
		(width 0.17145)
		(layer "B.Cu")
		(net "SELF_1A&2A_HB")
	)
	(segment
		(start 11.820906 -455.3458)
		(end 6.879336 -455.3458)
		(width 0.17145)
		(layer "B.Cu")
		(net "SELF_1A&2A_HB")
	)
	(segment
		(start 14.920976 -480.096576)
		(end 14.3129 -479.4885)
		(width 0.17145)
		(layer "B.Cu")
		(net "SELF_1A&2A_HB")
	)
	(segment
		(start 14.3129 -457.837794)
		(end 11.820906 -455.3458)
		(width 0.17145)
		(layer "B.Cu")
		(net "SELF_1A&2A_HB")
	)
	(segment
		(start 14.659102 -476.996506)
		(end 14.659102 -473.23121)
		(width 0.17145)
		(layer "B.Cu")
		(net "SELF_1A&2A_HB")
	)
	(segment
		(start 238.633 -431.292)
		(end 238.633 -441.725304)
		(width 0.17145)
		(layer "B.Cu")
		(net "SELF_1A&2A_HB")
	)
	(segment
		(start 14.3129 -472.885262)
		(end 14.3129 -457.837794)
		(width 0.17145)
		(layer "B.Cu")
		(net "SELF_1A&2A_HB")
	)
	(segment
		(start 5.209286 -453.67575)
		(end 3.943858 -453.67575)
		(width 0.17145)
		(layer "B.Cu")
		(net "SELF_1A&2A_HB")
	)
	(segment
		(start 20.423886 -480.096576)
		(end 14.920976 -480.096576)
		(width 0.17145)
		(layer "B.Cu")
		(net "SELF_1A&2A_HB")
	)
	(segment
		(start 33.051496 -491.744)
		(end 32.07131 -491.744)
		(width 0.17145)
		(layer "B.Cu")
		(net "SELF_1A&2A_HB")
	)
	(segment
		(start 14.3129 -479.4885)
		(end 14.3129 -477.342708)
		(width 0.17145)
		(layer "B.Cu")
		(net "SELF_1A&2A_HB")
	)
	(segment
		(start 228.803454 -444.31585)
		(end 219.62745 -453.491854)
		(width 0.17145)
		(layer "B.Cu")
		(net "SELF_1A&2A_HB")
	)
	(segment
		(start 14.636242 -473.208604)
		(end 14.3129 -472.885262)
		(width 0.17145)
		(layer "B.Cu")
		(net "SELF_1A&2A_HB")
	)
	(segment
		(start 19.346164 -97.61855)
		(end 18.137632 -96.410018)
		(width 0.17145)
		(layer "F.Cu")
		(net "SDA_DR9")
	)
	(segment
		(start 59.856624 -97.04324)
		(end 60.23864 -97.04324)
		(width 0.17145)
		(layer "F.Cu")
		(net "SDA_DR9")
	)
	(segment
		(start 48.768 -99.314)
		(end 47.07255 -97.61855)
		(width 0.17145)
		(layer "F.Cu")
		(net "SDA_DR9")
	)
	(segment
		(start 31.3055 -82.423)
		(end 31.6865 -82.804)
		(width 0.17145)
		(layer "F.Cu")
		(net "SDA_DR9")
	)
	(segment
		(start 60.23864 -97.04324)
		(end 60.43295 -97.23755)
		(width 0.17145)
		(layer "F.Cu")
		(net "SDA_DR9")
	)
	(segment
		(start 71.9201 -144.8054)
		(end 71.1835 -145.542)
		(width 0.17145)
		(layer "F.Cu")
		(net "SDA_DR9")
	)
	(segment
		(start 59.769248 -99.314)
		(end 48.768 -99.314)
		(width 0.17145)
		(layer "F.Cu")
		(net "SDA_DR9")
	)
	(segment
		(start 72.0852 -144.8054)
		(end 71.9201 -144.8054)
		(width 0.17145)
		(layer "F.Cu")
		(net "SDA_DR9")
	)
	(segment
		(start 68.797932 -144.79905)
		(end 70.44055 -144.79905)
		(width 0.17145)
		(layer "F.Cu")
		(net "SDA_DR9")
	)
	(segment
		(start 70.44055 -144.79905)
		(end 71.1835 -145.542)
		(width 0.17145)
		(layer "F.Cu")
		(net "SDA_DR9")
	)
	(segment
		(start 60.43295 -98.650298)
		(end 59.769248 -99.314)
		(width 0.17145)
		(layer "F.Cu")
		(net "SDA_DR9")
	)
	(segment
		(start 47.07255 -97.61855)
		(end 19.346164 -97.61855)
		(width 0.17145)
		(layer "F.Cu")
		(net "SDA_DR9")
	)
	(segment
		(start 18.137632 -88.769698)
		(end 24.48433 -82.423)
		(width 0.17145)
		(layer "F.Cu")
		(net "SDA_DR9")
	)
	(segment
		(start 68.58 -145.016982)
		(end 68.797932 -144.79905)
		(width 0.17145)
		(layer "F.Cu")
		(net "SDA_DR9")
	)
	(segment
		(start 74.1426 -146.8628)
		(end 72.0852 -144.8054)
		(width 0.17145)
		(layer "F.Cu")
		(net "SDA_DR9")
	)
	(segment
		(start 24.48433 -82.423)
		(end 31.3055 -82.423)
		(width 0.17145)
		(layer "F.Cu")
		(net "SDA_DR9")
	)
	(segment
		(start 60.43295 -97.23755)
		(end 60.43295 -98.650298)
		(width 0.17145)
		(layer "F.Cu")
		(net "SDA_DR9")
	)
	(segment
		(start 18.137632 -96.410018)
		(end 18.137632 -88.769698)
		(width 0.17145)
		(layer "F.Cu")
		(net "SDA_DR9")
	)
	(segment
		(start 74.1426 -147.467066)
		(end 74.1426 -146.8628)
		(width 0.17145)
		(layer "F.Cu")
		(net "SDA_DR9")
	)
	(via
		(at 59.856624 -97.04324)
		(size 0.5588)
		(drill 0.3048)
		(layers "F.Cu" "B.Cu")
		(net "SDA_DR9")
	)
	(via
		(at 68.58 -145.016982)
		(size 0.508)
		(drill 0.254)
		(layers "F.Cu" "B.Cu")
		(net "SDA_DR9")
	)
	(segment
		(start 68.58 -145.016982)
		(end 68.393818 -144.8308)
		(width 0.17145)
		(layer "B.Cu")
		(net "SDA_DR9")
	)
	(segment
		(start 64.774826 -144.8308)
		(end 60.658248 -140.714222)
		(width 0.17145)
		(layer "B.Cu")
		(net "SDA_DR9")
	)
	(segment
		(start 68.393818 -144.8308)
		(end 64.774826 -144.8308)
		(width 0.17145)
		(layer "B.Cu")
		(net "SDA_DR9")
	)
	(segment
		(start 60.658248 -140.714222)
		(end 60.658248 -97.21469)
		(width 0.17145)
		(layer "B.Cu")
		(net "SDA_DR9")
	)
	(segment
		(start 60.486798 -97.04324)
		(end 59.856624 -97.04324)
		(width 0.17145)
		(layer "B.Cu")
		(net "SDA_DR9")
	)
	(segment
		(start 60.658248 -97.21469)
		(end 60.486798 -97.04324)
		(width 0.17145)
		(layer "B.Cu")
		(net "SDA_DR9")
	)
	(segment
		(start 68.696332 -150.89505)
		(end 70.44055 -150.89505)
		(width 0.17145)
		(layer "F.Cu")
		(net "SDA_DR8")
	)
	(segment
		(start 74.1426 -149.966934)
		(end 73.780396 -149.966934)
		(width 0.17145)
		(layer "F.Cu")
		(net "SDA_DR8")
	)
	(segment
		(start 47.92345 -205.11135)
		(end 48.0949 -205.2828)
		(width 0.17145)
		(layer "F.Cu")
		(net "SDA_DR8")
	)
	(segment
		(start 68.5292 -151.062182)
		(end 68.696332 -150.89505)
		(width 0.17145)
		(layer "F.Cu")
		(net "SDA_DR8")
	)
	(segment
		(start 24.9936 -185.4454)
		(end 19.7612 -190.6778)
		(width 0.17145)
		(layer "F.Cu")
		(net "SDA_DR8")
	)
	(segment
		(start 31.6865 -185.801)
		(end 31.3309 -185.4454)
		(width 0.17145)
		(layer "F.Cu")
		(net "SDA_DR8")
	)
	(segment
		(start 48.0949 -205.2828)
		(end 48.474376 -205.2828)
		(width 0.17145)
		(layer "F.Cu")
		(net "SDA_DR8")
	)
	(segment
		(start 71.92645 -150.89505)
		(end 71.1835 -151.638)
		(width 0.17145)
		(layer "F.Cu")
		(net "SDA_DR8")
	)
	(segment
		(start 44.240704 -199.898)
		(end 47.92345 -203.580746)
		(width 0.17145)
		(layer "F.Cu")
		(net "SDA_DR8")
	)
	(segment
		(start 31.3309 -185.4454)
		(end 24.9936 -185.4454)
		(width 0.17145)
		(layer "F.Cu")
		(net "SDA_DR8")
	)
	(segment
		(start 72.85228 -150.89505)
		(end 71.92645 -150.89505)
		(width 0.17145)
		(layer "F.Cu")
		(net "SDA_DR8")
	)
	(segment
		(start 19.7612 -190.6778)
		(end 19.7612 -198.8312)
		(width 0.17145)
		(layer "F.Cu")
		(net "SDA_DR8")
	)
	(segment
		(start 47.92345 -203.580746)
		(end 47.92345 -205.11135)
		(width 0.17145)
		(layer "F.Cu")
		(net "SDA_DR8")
	)
	(segment
		(start 70.44055 -150.89505)
		(end 71.1835 -151.638)
		(width 0.17145)
		(layer "F.Cu")
		(net "SDA_DR8")
	)
	(segment
		(start 73.780396 -149.966934)
		(end 72.85228 -150.89505)
		(width 0.17145)
		(layer "F.Cu")
		(net "SDA_DR8")
	)
	(segment
		(start 19.7612 -198.8312)
		(end 20.828 -199.898)
		(width 0.17145)
		(layer "F.Cu")
		(net "SDA_DR8")
	)
	(segment
		(start 20.828 -199.898)
		(end 44.240704 -199.898)
		(width 0.17145)
		(layer "F.Cu")
		(net "SDA_DR8")
	)
	(via
		(at 48.474376 -205.2828)
		(size 0.5588)
		(drill 0.3048)
		(layers "F.Cu" "B.Cu")
		(net "SDA_DR8")
	)
	(via
		(at 68.5292 -151.062182)
		(size 0.508)
		(drill 0.254)
		(layers "F.Cu" "B.Cu")
		(net "SDA_DR8")
	)
	(segment
		(start 68.343018 -150.876)
		(end 68.5292 -151.062182)
		(width 0.17145)
		(layer "B.Cu")
		(net "SDA_DR8")
	)
	(segment
		(start 47.7774 -205.0542)
		(end 47.7774 -203.398374)
		(width 0.17145)
		(layer "B.Cu")
		(net "SDA_DR8")
	)
	(segment
		(start 48.474376 -205.2828)
		(end 48.006 -205.2828)
		(width 0.17145)
		(layer "B.Cu")
		(net "SDA_DR8")
	)
	(segment
		(start 47.7774 -203.398374)
		(end 61.388752 -189.787022)
		(width 0.17145)
		(layer "B.Cu")
		(net "SDA_DR8")
	)
	(segment
		(start 48.006 -205.2828)
		(end 47.7774 -205.0542)
		(width 0.17145)
		(layer "B.Cu")
		(net "SDA_DR8")
	)
	(segment
		(start 61.388752 -156.035248)
		(end 66.548 -150.876)
		(width 0.17145)
		(layer "B.Cu")
		(net "SDA_DR8")
	)
	(segment
		(start 61.388752 -189.787022)
		(end 61.388752 -156.035248)
		(width 0.17145)
		(layer "B.Cu")
		(net "SDA_DR8")
	)
	(segment
		(start 66.548 -150.876)
		(end 68.343018 -150.876)
		(width 0.17145)
		(layer "B.Cu")
		(net "SDA_DR8")
	)
	(segment
		(start 74.2188 -360.811064)
		(end 72.801734 -360.811064)
		(width 0.17145)
		(layer "F.Cu")
		(net "SDA_DR7")
	)
	(segment
		(start 21.77288 -303.48555)
		(end 20.316698 -302.029368)
		(width 0.17145)
		(layer "F.Cu")
		(net "SDA_DR7")
	)
	(segment
		(start 72.801734 -360.811064)
		(end 71.87692 -359.88625)
		(width 0.17145)
		(layer "F.Cu")
		(net "SDA_DR7")
	)
	(segment
		(start 71.1835 -360.553)
		(end 70.44055 -359.81005)
		(width 0.17145)
		(layer "F.Cu")
		(net "SDA_DR7")
	)
	(segment
		(start 67.12712 -303.48555)
		(end 21.77288 -303.48555)
		(width 0.17145)
		(layer "F.Cu")
		(net "SDA_DR7")
	)
	(segment
		(start 31.3055 -288.417)
		(end 31.6865 -288.798)
		(width 0.17145)
		(layer "F.Cu")
		(net "SDA_DR7")
	)
	(segment
		(start 69.0118 -301.60087)
		(end 67.12712 -303.48555)
		(width 0.17145)
		(layer "F.Cu")
		(net "SDA_DR7")
	)
	(segment
		(start 71.1835 -360.4133)
		(end 71.1835 -360.553)
		(width 0.17145)
		(layer "F.Cu")
		(net "SDA_DR7")
	)
	(segment
		(start 69.0118 -300.629574)
		(end 69.0118 -301.60087)
		(width 0.17145)
		(layer "F.Cu")
		(net "SDA_DR7")
	)
	(segment
		(start 68.879466 -300.49724)
		(end 69.0118 -300.629574)
		(width 0.17145)
		(layer "F.Cu")
		(net "SDA_DR7")
	)
	(segment
		(start 68.286376 -300.49724)
		(end 68.879466 -300.49724)
		(width 0.17145)
		(layer "F.Cu")
		(net "SDA_DR7")
	)
	(segment
		(start 71.87692 -359.88625)
		(end 71.71055 -359.88625)
		(width 0.17145)
		(layer "F.Cu")
		(net "SDA_DR7")
	)
	(segment
		(start 25.11933 -288.417)
		(end 31.3055 -288.417)
		(width 0.17145)
		(layer "F.Cu")
		(net "SDA_DR7")
	)
	(segment
		(start 71.71055 -359.88625)
		(end 71.1835 -360.4133)
		(width 0.17145)
		(layer "F.Cu")
		(net "SDA_DR7")
	)
	(segment
		(start 20.316698 -293.219632)
		(end 25.11933 -288.417)
		(width 0.17145)
		(layer "F.Cu")
		(net "SDA_DR7")
	)
	(segment
		(start 20.316698 -302.029368)
		(end 20.316698 -293.219632)
		(width 0.17145)
		(layer "F.Cu")
		(net "SDA_DR7")
	)
	(segment
		(start 70.44055 -359.81005)
		(end 68.772532 -359.81005)
		(width 0.17145)
		(layer "F.Cu")
		(net "SDA_DR7")
	)
	(segment
		(start 68.772532 -359.81005)
		(end 68.58 -360.002582)
		(width 0.17145)
		(layer "F.Cu")
		(net "SDA_DR7")
	)
	(via
		(at 68.58 -360.002582)
		(size 0.508)
		(drill 0.254)
		(layers "F.Cu" "B.Cu")
		(net "SDA_DR7")
	)
	(via
		(at 68.286376 -300.49724)
		(size 0.5588)
		(drill 0.3048)
		(layers "F.Cu" "B.Cu")
		(net "SDA_DR7")
	)
	(segment
		(start 69.088 -346.4814)
		(end 69.088 -300.66869)
		(width 0.17145)
		(layer "B.Cu")
		(net "SDA_DR7")
	)
	(segment
		(start 64.5922 -357.119174)
		(end 64.5922 -350.9772)
		(width 0.17145)
		(layer "B.Cu")
		(net "SDA_DR7")
	)
	(segment
		(start 68.91655 -300.49724)
		(end 68.286376 -300.49724)
		(width 0.17145)
		(layer "B.Cu")
		(net "SDA_DR7")
	)
	(segment
		(start 69.088 -300.66869)
		(end 68.91655 -300.49724)
		(width 0.17145)
		(layer "B.Cu")
		(net "SDA_DR7")
	)
	(segment
		(start 64.5922 -350.9772)
		(end 69.088 -346.4814)
		(width 0.17145)
		(layer "B.Cu")
		(net "SDA_DR7")
	)
	(segment
		(start 68.58 -360.002582)
		(end 68.368418 -359.791)
		(width 0.17145)
		(layer "B.Cu")
		(net "SDA_DR7")
	)
	(segment
		(start 68.368418 -359.791)
		(end 67.264026 -359.791)
		(width 0.17145)
		(layer "B.Cu")
		(net "SDA_DR7")
	)
	(segment
		(start 67.264026 -359.791)
		(end 64.5922 -357.119174)
		(width 0.17145)
		(layer "B.Cu")
		(net "SDA_DR7")
	)
	(segment
		(start 74.4474 -363.1184)
		(end 72.413876 -365.151924)
		(width 0.17145)
		(layer "F.Cu")
		(net "SDA_DR6")
	)
	(segment
		(start 31.6865 -391.795)
		(end 31.29915 -391.40765)
		(width 0.17145)
		(layer "F.Cu")
		(net "SDA_DR6")
	)
	(segment
		(start 74.950066 -363.1184)
		(end 74.4474 -363.1184)
		(width 0.17145)
		(layer "F.Cu")
		(net "SDA_DR6")
	)
	(segment
		(start 72.3138 -368.367818)
		(end 72.3138 -366.8141)
		(width 0.17145)
		(layer "F.Cu")
		(net "SDA_DR6")
	)
	(segment
		(start 29.816298 -391.544302)
		(end 29.816298 -392.1125)
		(width 0.17145)
		(layer "F.Cu")
		(net "SDA_DR6")
	)
	(segment
		(start 29.95295 -391.40765)
		(end 29.816298 -391.544302)
		(width 0.17145)
		(layer "F.Cu")
		(net "SDA_DR6")
	)
	(segment
		(start 72.413876 -365.440976)
		(end 73.0504 -366.0775)
		(width 0.17145)
		(layer "F.Cu")
		(net "SDA_DR6")
	)
	(segment
		(start 72.413876 -365.151924)
		(end 72.413876 -365.440976)
		(width 0.17145)
		(layer "F.Cu")
		(net "SDA_DR6")
	)
	(segment
		(start 72.601582 -368.6556)
		(end 72.3138 -368.367818)
		(width 0.17145)
		(layer "F.Cu")
		(net "SDA_DR6")
	)
	(segment
		(start 72.3138 -366.8141)
		(end 73.0504 -366.0775)
		(width 0.17145)
		(layer "F.Cu")
		(net "SDA_DR6")
	)
	(segment
		(start 31.29915 -391.40765)
		(end 29.95295 -391.40765)
		(width 0.17145)
		(layer "F.Cu")
		(net "SDA_DR6")
	)
	(via
		(at 29.816298 -392.1125)
		(size 0.5588)
		(drill 0.3048)
		(layers "F.Cu" "B.Cu")
		(net "SDA_DR6")
	)
	(via
		(at 72.601582 -368.6556)
		(size 0.508)
		(drill 0.254)
		(layers "F.Cu" "B.Cu")
		(net "SDA_DR6")
	)
	(segment
		(start 30.099 -391.4902)
		(end 29.816298 -391.772902)
		(width 0.17145)
		(layer "B.Cu")
		(net "SDA_DR6")
	)
	(segment
		(start 62.93485 -375.21515)
		(end 62.93485 -382.55448)
		(width 0.17145)
		(layer "B.Cu")
		(net "SDA_DR6")
	)
	(segment
		(start 72.40905 -370.18595)
		(end 71.27875 -371.31625)
		(width 0.17145)
		(layer "B.Cu")
		(net "SDA_DR6")
	)
	(segment
		(start 71.27875 -371.31625)
		(end 66.83375 -371.31625)
		(width 0.17145)
		(layer "B.Cu")
		(net "SDA_DR6")
	)
	(segment
		(start 66.83375 -371.31625)
		(end 62.93485 -375.21515)
		(width 0.17145)
		(layer "B.Cu")
		(net "SDA_DR6")
	)
	(segment
		(start 29.816298 -391.772902)
		(end 29.816298 -392.1125)
		(width 0.17145)
		(layer "B.Cu")
		(net "SDA_DR6")
	)
	(segment
		(start 33.280096 -391.4902)
		(end 30.099 -391.4902)
		(width 0.17145)
		(layer "B.Cu")
		(net "SDA_DR6")
	)
	(segment
		(start 72.601582 -368.6556)
		(end 72.40905 -368.848132)
		(width 0.17145)
		(layer "B.Cu")
		(net "SDA_DR6")
	)
	(segment
		(start 35.407346 -393.61745)
		(end 33.280096 -391.4902)
		(width 0.17145)
		(layer "B.Cu")
		(net "SDA_DR6")
	)
	(segment
		(start 51.87188 -393.61745)
		(end 35.407346 -393.61745)
		(width 0.17145)
		(layer "B.Cu")
		(net "SDA_DR6")
	)
	(segment
		(start 62.93485 -382.55448)
		(end 51.87188 -393.61745)
		(width 0.17145)
		(layer "B.Cu")
		(net "SDA_DR6")
	)
	(segment
		(start 72.40905 -368.848132)
		(end 72.40905 -370.18595)
		(width 0.17145)
		(layer "B.Cu")
		(net "SDA_DR6")
	)
	(segment
		(start 78.646782 -368.6302)
		(end 78.4098 -368.393218)
		(width 0.17145)
		(layer "F.Cu")
		(net "SDA_DR5")
	)
	(segment
		(start 60.26785 -440.232546)
		(end 58.902854 -438.86755)
		(width 0.17145)
		(layer "F.Cu")
		(net "SDA_DR5")
	)
	(segment
		(start 60.5409 -441.96)
		(end 60.26785 -441.68695)
		(width 0.17145)
		(layer "F.Cu")
		(net "SDA_DR5")
	)
	(segment
		(start 78.27645 -364.66145)
		(end 78.27645 -365.20755)
		(width 0.17145)
		(layer "F.Cu")
		(net "SDA_DR5")
	)
	(segment
		(start 50.995072 -438.86755)
		(end 38.15715 -451.705472)
		(width 0.17145)
		(layer "F.Cu")
		(net "SDA_DR5")
	)
	(segment
		(start 58.902854 -438.86755)
		(end 50.995072 -438.86755)
		(width 0.17145)
		(layer "F.Cu")
		(net "SDA_DR5")
	)
	(segment
		(start 38.15715 -451.705472)
		(end 38.15715 -454.888346)
		(width 0.17145)
		(layer "F.Cu")
		(net "SDA_DR5")
	)
	(segment
		(start 31.375858 -461.669638)
		(end 31.375858 -474.16593)
		(width 0.17145)
		(layer "F.Cu")
		(net "SDA_DR5")
	)
	(segment
		(start 60.26785 -441.68695)
		(end 60.26785 -440.232546)
		(width 0.17145)
		(layer "F.Cu")
		(net "SDA_DR5")
	)
	(segment
		(start 29.80055 -491.566454)
		(end 30.406594 -492.172498)
		(width 0.17145)
		(layer "F.Cu")
		(net "SDA_DR5")
	)
	(segment
		(start 60.920376 -441.96)
		(end 60.5409 -441.96)
		(width 0.17145)
		(layer "F.Cu")
		(net "SDA_DR5")
	)
	(segment
		(start 31.375858 -474.16593)
		(end 29.80055 -475.741238)
		(width 0.17145)
		(layer "F.Cu")
		(net "SDA_DR5")
	)
	(segment
		(start 38.15715 -454.888346)
		(end 31.375858 -461.669638)
		(width 0.17145)
		(layer "F.Cu")
		(net "SDA_DR5")
	)
	(segment
		(start 77.449934 -363.834934)
		(end 78.27645 -364.66145)
		(width 0.17145)
		(layer "F.Cu")
		(net "SDA_DR5")
	)
	(segment
		(start 77.449934 -363.1184)
		(end 77.449934 -363.834934)
		(width 0.17145)
		(layer "F.Cu")
		(net "SDA_DR5")
	)
	(segment
		(start 30.895798 -492.172498)
		(end 31.2547 -492.5314)
		(width 0.17145)
		(layer "F.Cu")
		(net "SDA_DR5")
	)
	(segment
		(start 78.4098 -368.393218)
		(end 78.4098 -366.8141)
		(width 0.17145)
		(layer "F.Cu")
		(net "SDA_DR5")
	)
	(segment
		(start 78.4098 -366.8141)
		(end 79.1464 -366.0775)
		(width 0.17145)
		(layer "F.Cu")
		(net "SDA_DR5")
	)
	(segment
		(start 78.27645 -365.20755)
		(end 79.1464 -366.0775)
		(width 0.17145)
		(layer "F.Cu")
		(net "SDA_DR5")
	)
	(segment
		(start 29.80055 -475.741238)
		(end 29.80055 -491.566454)
		(width 0.17145)
		(layer "F.Cu")
		(net "SDA_DR5")
	)
	(segment
		(start 30.406594 -492.172498)
		(end 30.895798 -492.172498)
		(width 0.17145)
		(layer "F.Cu")
		(net "SDA_DR5")
	)
	(via
		(at 60.920376 -441.96)
		(size 0.5588)
		(drill 0.3048)
		(layers "F.Cu" "B.Cu")
		(net "SDA_DR5")
	)
	(via
		(at 78.646782 -368.6302)
		(size 0.508)
		(drill 0.254)
		(layers "F.Cu" "B.Cu")
		(net "SDA_DR5")
	)
	(segment
		(start 60.26785 -399.186654)
		(end 78.4098 -381.044704)
		(width 0.17145)
		(layer "B.Cu")
		(net "SDA_DR5")
	)
	(segment
		(start 78.4098 -381.044704)
		(end 78.4098 -368.867182)
		(width 0.17145)
		(layer "B.Cu")
		(net "SDA_DR5")
	)
	(segment
		(start 60.5282 -441.96)
		(end 60.26785 -441.69965)
		(width 0.17145)
		(layer "B.Cu")
		(net "SDA_DR5")
	)
	(segment
		(start 60.26785 -441.69965)
		(end 60.26785 -399.186654)
		(width 0.17145)
		(layer "B.Cu")
		(net "SDA_DR5")
	)
	(segment
		(start 60.920376 -441.96)
		(end 60.5282 -441.96)
		(width 0.17145)
		(layer "B.Cu")
		(net "SDA_DR5")
	)
	(segment
		(start 78.4098 -368.867182)
		(end 78.646782 -368.6302)
		(width 0.17145)
		(layer "B.Cu")
		(net "SDA_DR5")
	)
	(segment
		(start 76.449936 -151.557736)
		(end 76.5048 -151.6126)
		(width 0.17145)
		(layer "F.Cu")
		(net "SDA_DR4")
	)
	(segment
		(start 141.14145 -134.411974)
		(end 143.358616 -134.411974)
		(width 0.17145)
		(layer "F.Cu")
		(net "SDA_DR4")
	)
	(segment
		(start 143.358616 -134.411974)
		(end 195.325492 -82.445098)
		(width 0.17145)
		(layer "F.Cu")
		(net "SDA_DR4")
	)
	(segment
		(start 76.5048 -151.6126)
		(end 76.5048 -153.0223)
		(width 0.17145)
		(layer "F.Cu")
		(net "SDA_DR4")
	)
	(segment
		(start 140.97 -134.583424)
		(end 141.14145 -134.411974)
		(width 0.17145)
		(layer "F.Cu")
		(net "SDA_DR4")
	)
	(segment
		(start 76.4794 -157.547818)
		(end 76.4794 -154.4701)
		(width 0.17145)
		(layer "F.Cu")
		(net "SDA_DR4")
	)
	(segment
		(start 140.97 -135.088376)
		(end 140.97 -134.583424)
		(width 0.17145)
		(layer "F.Cu")
		(net "SDA_DR4")
	)
	(segment
		(start 195.325492 -82.445098)
		(end 216.239598 -82.445098)
		(width 0.17145)
		(layer "F.Cu")
		(net "SDA_DR4")
	)
	(segment
		(start 216.239598 -82.445098)
		(end 216.5985 -82.804)
		(width 0.17145)
		(layer "F.Cu")
		(net "SDA_DR4")
	)
	(segment
		(start 76.5048 -153.0223)
		(end 77.216 -153.7335)
		(width 0.17145)
		(layer "F.Cu")
		(net "SDA_DR4")
	)
	(segment
		(start 76.665582 -157.734)
		(end 76.4794 -157.547818)
		(width 0.17145)
		(layer "F.Cu")
		(net "SDA_DR4")
	)
	(segment
		(start 76.449936 -150.6982)
		(end 76.449936 -151.557736)
		(width 0.17145)
		(layer "F.Cu")
		(net "SDA_DR4")
	)
	(segment
		(start 76.4794 -154.4701)
		(end 77.216 -153.7335)
		(width 0.17145)
		(layer "F.Cu")
		(net "SDA_DR4")
	)
	(via
		(at 140.97 -135.088376)
		(size 0.5588)
		(drill 0.3048)
		(layers "F.Cu" "B.Cu")
		(net "SDA_DR4")
	)
	(via
		(at 76.665582 -157.734)
		(size 0.508)
		(drill 0.254)
		(layers "F.Cu" "B.Cu")
		(net "SDA_DR4")
	)
	(segment
		(start 142.33525 -134.46125)
		(end 141.10335 -134.46125)
		(width 0.17145)
		(layer "B.Cu")
		(net "SDA_DR4")
	)
	(segment
		(start 143.002 -150.4696)
		(end 143.002 -135.128)
		(width 0.17145)
		(layer "B.Cu")
		(net "SDA_DR4")
	)
	(segment
		(start 132.6896 -160.782)
		(end 143.002 -150.4696)
		(width 0.17145)
		(layer "B.Cu")
		(net "SDA_DR4")
	)
	(segment
		(start 76.47305 -157.926532)
		(end 76.47305 -159.27705)
		(width 0.17145)
		(layer "B.Cu")
		(net "SDA_DR4")
	)
	(segment
		(start 76.665582 -157.734)
		(end 76.47305 -157.926532)
		(width 0.17145)
		(layer "B.Cu")
		(net "SDA_DR4")
	)
	(segment
		(start 76.47305 -159.27705)
		(end 77.978 -160.782)
		(width 0.17145)
		(layer "B.Cu")
		(net "SDA_DR4")
	)
	(segment
		(start 77.978 -160.782)
		(end 132.6896 -160.782)
		(width 0.17145)
		(layer "B.Cu")
		(net "SDA_DR4")
	)
	(segment
		(start 143.002 -135.128)
		(end 142.33525 -134.46125)
		(width 0.17145)
		(layer "B.Cu")
		(net "SDA_DR4")
	)
	(segment
		(start 140.97 -134.5946)
		(end 140.97 -135.088376)
		(width 0.17145)
		(layer "B.Cu")
		(net "SDA_DR4")
	)
	(segment
		(start 141.10335 -134.46125)
		(end 140.97 -134.5946)
		(width 0.17145)
		(layer "B.Cu")
		(net "SDA_DR4")
	)
	(segment
		(start 79.49565 -152.96515)
		(end 80.264 -153.7335)
		(width 0.17145)
		(layer "F.Cu")
		(net "SDA_DR3")
	)
	(segment
		(start 131.443476 -157.75559)
		(end 131.443476 -158.19755)
		(width 0.17145)
		(layer "F.Cu")
		(net "SDA_DR3")
	)
	(segment
		(start 180.219858 -157.404562)
		(end 131.794504 -157.404562)
		(width 0.17145)
		(layer "F.Cu")
		(net "SDA_DR3")
	)
	(segment
		(start 79.49565 -152.399746)
		(end 79.49565 -152.96515)
		(width 0.17145)
		(layer "F.Cu")
		(net "SDA_DR3")
	)
	(segment
		(start 77.449934 -151.363934)
		(end 77.9272 -151.8412)
		(width 0.17145)
		(layer "F.Cu")
		(net "SDA_DR3")
	)
	(segment
		(start 216.2429 -185.4454)
		(end 208.260696 -185.4454)
		(width 0.17145)
		(layer "F.Cu")
		(net "SDA_DR3")
	)
	(segment
		(start 131.794504 -157.404562)
		(end 131.443476 -157.75559)
		(width 0.17145)
		(layer "F.Cu")
		(net "SDA_DR3")
	)
	(segment
		(start 208.260696 -185.4454)
		(end 180.219858 -157.404562)
		(width 0.17145)
		(layer "F.Cu")
		(net "SDA_DR3")
	)
	(segment
		(start 216.5985 -185.801)
		(end 216.2429 -185.4454)
		(width 0.17145)
		(layer "F.Cu")
		(net "SDA_DR3")
	)
	(segment
		(start 78.937104 -151.8412)
		(end 79.49565 -152.399746)
		(width 0.17145)
		(layer "F.Cu")
		(net "SDA_DR3")
	)
	(segment
		(start 131.614926 -158.369)
		(end 132.119624 -158.369)
		(width 0.17145)
		(layer "F.Cu")
		(net "SDA_DR3")
	)
	(segment
		(start 79.713582 -156.337)
		(end 79.5274 -156.150818)
		(width 0.17145)
		(layer "F.Cu")
		(net "SDA_DR3")
	)
	(segment
		(start 79.5274 -154.4701)
		(end 80.264 -153.7335)
		(width 0.17145)
		(layer "F.Cu")
		(net "SDA_DR3")
	)
	(segment
		(start 77.449934 -150.7744)
		(end 77.449934 -151.363934)
		(width 0.17145)
		(layer "F.Cu")
		(net "SDA_DR3")
	)
	(segment
		(start 131.443476 -158.19755)
		(end 131.614926 -158.369)
		(width 0.17145)
		(layer "F.Cu")
		(net "SDA_DR3")
	)
	(segment
		(start 77.9272 -151.8412)
		(end 78.937104 -151.8412)
		(width 0.17145)
		(layer "F.Cu")
		(net "SDA_DR3")
	)
	(segment
		(start 79.5274 -156.150818)
		(end 79.5274 -154.4701)
		(width 0.17145)
		(layer "F.Cu")
		(net "SDA_DR3")
	)
	(via
		(at 79.713582 -156.337)
		(size 0.508)
		(drill 0.254)
		(layers "F.Cu" "B.Cu")
		(net "SDA_DR3")
	)
	(via
		(at 132.119624 -158.369)
		(size 0.5588)
		(drill 0.3048)
		(layers "F.Cu" "B.Cu")
		(net "SDA_DR3")
	)
	(segment
		(start 131.568698 -158.19755)
		(end 131.568698 -157.376368)
		(width 0.17145)
		(layer "B.Cu")
		(net "SDA_DR3")
	)
	(segment
		(start 80.013302 -158.499302)
		(end 79.57185 -158.05785)
		(width 0.17145)
		(layer "B.Cu")
		(net "SDA_DR3")
	)
	(segment
		(start 79.57185 -156.478732)
		(end 79.713582 -156.337)
		(width 0.17145)
		(layer "B.Cu")
		(net "SDA_DR3")
	)
	(segment
		(start 79.57185 -158.05785)
		(end 79.57185 -156.478732)
		(width 0.17145)
		(layer "B.Cu")
		(net "SDA_DR3")
	)
	(segment
		(start 132.119624 -158.369)
		(end 131.740148 -158.369)
		(width 0.17145)
		(layer "B.Cu")
		(net "SDA_DR3")
	)
	(segment
		(start 131.740148 -158.369)
		(end 131.568698 -158.19755)
		(width 0.17145)
		(layer "B.Cu")
		(net "SDA_DR3")
	)
	(segment
		(start 123.802394 -158.499302)
		(end 80.013302 -158.499302)
		(width 0.17145)
		(layer "B.Cu")
		(net "SDA_DR3")
	)
	(segment
		(start 130.30708 -156.11475)
		(end 126.186946 -156.11475)
		(width 0.17145)
		(layer "B.Cu")
		(net "SDA_DR3")
	)
	(segment
		(start 126.186946 -156.11475)
		(end 123.802394 -158.499302)
		(width 0.17145)
		(layer "B.Cu")
		(net "SDA_DR3")
	)
	(segment
		(start 131.568698 -157.376368)
		(end 130.30708 -156.11475)
		(width 0.17145)
		(layer "B.Cu")
		(net "SDA_DR3")
	)
	(segment
		(start 78.77683 -359.811066)
		(end 79.248 -359.339896)
		(width 0.17145)
		(layer "F.Cu")
		(net "SDA_DR2")
	)
	(segment
		(start 81.95945 -357.71455)
		(end 81.2165 -356.9716)
		(width 0.17145)
		(layer "F.Cu")
		(net "SDA_DR2")
	)
	(segment
		(start 79.248 -358.425496)
		(end 79.882746 -357.79075)
		(width 0.17145)
		(layer "F.Cu")
		(net "SDA_DR2")
	)
	(segment
		(start 79.882746 -357.79075)
		(end 80.4418 -357.79075)
		(width 0.17145)
		(layer "F.Cu")
		(net "SDA_DR2")
	)
	(segment
		(start 216.241376 -288.440876)
		(end 105.449624 -288.440876)
		(width 0.17145)
		(layer "F.Cu")
		(net "SDA_DR2")
	)
	(segment
		(start 83.635088 -357.71455)
		(end 81.95945 -357.71455)
		(width 0.17145)
		(layer "F.Cu")
		(net "SDA_DR2")
	)
	(segment
		(start 78.2574 -359.811066)
		(end 78.77683 -359.811066)
		(width 0.17145)
		(layer "F.Cu")
		(net "SDA_DR2")
	)
	(segment
		(start 79.248 -359.339896)
		(end 79.248 -358.425496)
		(width 0.17145)
		(layer "F.Cu")
		(net "SDA_DR2")
	)
	(segment
		(start 81.2165 -357.01605)
		(end 81.2165 -356.9716)
		(width 0.17145)
		(layer "F.Cu")
		(net "SDA_DR2")
	)
	(segment
		(start 105.449624 -288.440876)
		(end 104.775 -289.1155)
		(width 0.17145)
		(layer "F.Cu")
		(net "SDA_DR2")
	)
	(segment
		(start 83.8962 -357.453438)
		(end 83.635088 -357.71455)
		(width 0.17145)
		(layer "F.Cu")
		(net "SDA_DR2")
	)
	(segment
		(start 80.4418 -357.79075)
		(end 81.2165 -357.01605)
		(width 0.17145)
		(layer "F.Cu")
		(net "SDA_DR2")
	)
	(segment
		(start 216.5985 -288.798)
		(end 216.241376 -288.440876)
		(width 0.17145)
		(layer "F.Cu")
		(net "SDA_DR2")
	)
	(via
		(at 83.8962 -357.453438)
		(size 0.508)
		(drill 0.254)
		(layers "F.Cu" "B.Cu")
		(net "SDA_DR2")
	)
	(via
		(at 104.775 -289.1155)
		(size 0.5588)
		(drill 0.3048)
		(layers "F.Cu" "B.Cu")
		(net "SDA_DR2")
	)
	(segment
		(start 113.03 -331.978)
		(end 113.03 -294.259)
		(width 0.17145)
		(layer "B.Cu")
		(net "SDA_DR2")
	)
	(segment
		(start 104.775 -288.485326)
		(end 104.775 -289.1155)
		(width 0.17145)
		(layer "B.Cu")
		(net "SDA_DR2")
	)
	(segment
		(start 84.125562 -357.6828)
		(end 87.3252 -357.6828)
		(width 0.17145)
		(layer "B.Cu")
		(net "SDA_DR2")
	)
	(segment
		(start 113.03 -294.259)
		(end 107.1626 -288.3916)
		(width 0.17145)
		(layer "B.Cu")
		(net "SDA_DR2")
	)
	(segment
		(start 104.868726 -288.3916)
		(end 104.775 -288.485326)
		(width 0.17145)
		(layer "B.Cu")
		(net "SDA_DR2")
	)
	(segment
		(start 87.3252 -357.6828)
		(end 113.03 -331.978)
		(width 0.17145)
		(layer "B.Cu")
		(net "SDA_DR2")
	)
	(segment
		(start 83.8962 -357.453438)
		(end 84.125562 -357.6828)
		(width 0.17145)
		(layer "B.Cu")
		(net "SDA_DR2")
	)
	(segment
		(start 107.1626 -288.3916)
		(end 104.868726 -288.3916)
		(width 0.17145)
		(layer "B.Cu")
		(net "SDA_DR2")
	)
	(segment
		(start 74.5236 -144.85493)
		(end 75.449938 -145.781268)
		(width 0.17145)
		(layer "F.Cu")
		(net "SDA_DR14")
	)
	(segment
		(start 30.3022 -17.5895)
		(end 30.3022 -18.019014)
		(width 0.17145)
		(layer "F.Cu")
		(net "SDA_DR14")
	)
	(segment
		(start 60.624974 -24.003)
		(end 106.219752 -69.597778)
		(width 0.17145)
		(layer "F.Cu")
		(net "SDA_DR14")
	)
	(segment
		(start 30.3022 -18.019014)
		(end 29.943552 -18.377662)
		(width 0.17145)
		(layer "F.Cu")
		(net "SDA_DR14")
	)
	(segment
		(start 74.337418 -141.097)
		(end 74.52995 -141.289532)
		(width 0.17145)
		(layer "F.Cu")
		(net "SDA_DR14")
	)
	(segment
		(start 106.219752 -122.050048)
		(end 89.4842 -138.7856)
		(width 0.17145)
		(layer "F.Cu")
		(net "SDA_DR14")
	)
	(segment
		(start 72.136 -138.9634)
		(end 72.136 -139.406376)
		(width 0.17145)
		(layer "F.Cu")
		(net "SDA_DR14")
	)
	(segment
		(start 72.3138 -138.7856)
		(end 72.136 -138.9634)
		(width 0.17145)
		(layer "F.Cu")
		(net "SDA_DR14")
	)
	(segment
		(start 29.943552 -18.377662)
		(end 29.943552 -19.123152)
		(width 0.17145)
		(layer "F.Cu")
		(net "SDA_DR14")
	)
	(segment
		(start 106.219752 -69.597778)
		(end 106.219752 -122.050048)
		(width 0.17145)
		(layer "F.Cu")
		(net "SDA_DR14")
	)
	(segment
		(start 74.52995 -142.97787)
		(end 73.80732 -143.7005)
		(width 0.17145)
		(layer "F.Cu")
		(net "SDA_DR14")
	)
	(segment
		(start 29.943552 -19.123152)
		(end 34.8234 -24.003)
		(width 0.17145)
		(layer "F.Cu")
		(net "SDA_DR14")
	)
	(segment
		(start 74.5236 -144.41678)
		(end 74.5236 -144.85493)
		(width 0.17145)
		(layer "F.Cu")
		(net "SDA_DR14")
	)
	(segment
		(start 89.4842 -138.7856)
		(end 72.3138 -138.7856)
		(width 0.17145)
		(layer "F.Cu")
		(net "SDA_DR14")
	)
	(segment
		(start 73.80732 -143.7005)
		(end 74.5236 -144.41678)
		(width 0.17145)
		(layer "F.Cu")
		(net "SDA_DR14")
	)
	(segment
		(start 74.52995 -141.289532)
		(end 74.52995 -142.97787)
		(width 0.17145)
		(layer "F.Cu")
		(net "SDA_DR14")
	)
	(segment
		(start 75.449938 -145.781268)
		(end 75.449938 -146.7358)
		(width 0.17145)
		(layer "F.Cu")
		(net "SDA_DR14")
	)
	(segment
		(start 34.8234 -24.003)
		(end 60.624974 -24.003)
		(width 0.17145)
		(layer "F.Cu")
		(net "SDA_DR14")
	)
	(via
		(at 74.337418 -141.097)
		(size 0.508)
		(drill 0.254)
		(layers "F.Cu" "B.Cu")
		(net "SDA_DR14")
	)
	(via
		(at 72.136 -139.406376)
		(size 0.5588)
		(drill 0.3048)
		(layers "F.Cu" "B.Cu")
		(net "SDA_DR14")
	)
	(segment
		(start 72.136 -139.406376)
		(end 72.136 -138.843258)
		(width 0.17145)
		(layer "B.Cu")
		(net "SDA_DR14")
	)
	(segment
		(start 74.669396 -140.765022)
		(end 74.337418 -141.097)
		(width 0.17145)
		(layer "B.Cu")
		(net "SDA_DR14")
	)
	(segment
		(start 74.669396 -139.566396)
		(end 74.669396 -140.765022)
		(width 0.17145)
		(layer "B.Cu")
		(net "SDA_DR14")
	)
	(segment
		(start 72.136 -138.843258)
		(end 72.269858 -138.7094)
		(width 0.17145)
		(layer "B.Cu")
		(net "SDA_DR14")
	)
	(segment
		(start 72.269858 -138.7094)
		(end 73.8124 -138.7094)
		(width 0.17145)
		(layer "B.Cu")
		(net "SDA_DR14")
	)
	(segment
		(start 73.8124 -138.7094)
		(end 74.669396 -139.566396)
		(width 0.17145)
		(layer "B.Cu")
		(net "SDA_DR14")
	)
	(segment
		(start 68.772532 -147.84705)
		(end 70.44055 -147.84705)
		(width 0.17145)
		(layer "F.Cu")
		(net "SDA_DR13")
	)
	(segment
		(start 68.58 -148.039582)
		(end 68.772532 -147.84705)
		(width 0.17145)
		(layer "F.Cu")
		(net "SDA_DR13")
	)
	(segment
		(start 55.225696 -114.554)
		(end 56.59755 -113.182146)
		(width 0.17145)
		(layer "F.Cu")
		(net "SDA_DR13")
	)
	(segment
		(start 70.44055 -147.84705)
		(end 71.1835 -148.59)
		(width 0.17145)
		(layer "F.Cu")
		(net "SDA_DR13")
	)
	(segment
		(start 74.2188 -148.467064)
		(end 73.435464 -148.467064)
		(width 0.17145)
		(layer "F.Cu")
		(net "SDA_DR13")
	)
	(segment
		(start 56.4261 -111.379)
		(end 56.046624 -111.379)
		(width 0.17145)
		(layer "F.Cu")
		(net "SDA_DR13")
	)
	(segment
		(start 56.59755 -113.182146)
		(end 56.59755 -111.55045)
		(width 0.17145)
		(layer "F.Cu")
		(net "SDA_DR13")
	)
	(segment
		(start 73.435464 -148.467064)
		(end 72.81545 -147.84705)
		(width 0.17145)
		(layer "F.Cu")
		(net "SDA_DR13")
	)
	(segment
		(start 71.92645 -147.84705)
		(end 71.1835 -148.59)
		(width 0.17145)
		(layer "F.Cu")
		(net "SDA_DR13")
	)
	(segment
		(start 30.6705 -114.554)
		(end 55.225696 -114.554)
		(width 0.17145)
		(layer "F.Cu")
		(net "SDA_DR13")
	)
	(segment
		(start 30.2895 -114.173)
		(end 30.6705 -114.554)
		(width 0.17145)
		(layer "F.Cu")
		(net "SDA_DR13")
	)
	(segment
		(start 72.81545 -147.84705)
		(end 71.92645 -147.84705)
		(width 0.17145)
		(layer "F.Cu")
		(net "SDA_DR13")
	)
	(segment
		(start 56.59755 -111.55045)
		(end 56.4261 -111.379)
		(width 0.17145)
		(layer "F.Cu")
		(net "SDA_DR13")
	)
	(via
		(at 68.58 -148.039582)
		(size 0.508)
		(drill 0.254)
		(layers "F.Cu" "B.Cu")
		(net "SDA_DR13")
	)
	(via
		(at 56.046624 -111.379)
		(size 0.5588)
		(drill 0.3048)
		(layers "F.Cu" "B.Cu")
		(net "SDA_DR13")
	)
	(segment
		(start 56.54675 -111.379)
		(end 56.64835 -111.4806)
		(width 0.17145)
		(layer "B.Cu")
		(net "SDA_DR13")
	)
	(segment
		(start 56.046624 -111.379)
		(end 56.54675 -111.379)
		(width 0.17145)
		(layer "B.Cu")
		(net "SDA_DR13")
	)
	(segment
		(start 63.860426 -147.8534)
		(end 68.393818 -147.8534)
		(width 0.17145)
		(layer "B.Cu")
		(net "SDA_DR13")
	)
	(segment
		(start 68.393818 -147.8534)
		(end 68.58 -148.039582)
		(width 0.17145)
		(layer "B.Cu")
		(net "SDA_DR13")
	)
	(segment
		(start 56.64835 -140.641324)
		(end 63.860426 -147.8534)
		(width 0.17145)
		(layer "B.Cu")
		(net "SDA_DR13")
	)
	(segment
		(start 56.64835 -111.4806)
		(end 56.64835 -140.641324)
		(width 0.17145)
		(layer "B.Cu")
		(net "SDA_DR13")
	)
	(segment
		(start 73.4822 -152.5778)
		(end 73.81875 -152.24125)
		(width 0.17145)
		(layer "F.Cu")
		(net "SDA_DR12")
	)
	(segment
		(start 32.060134 -217.464894)
		(end 31.948628 -217.5764)
		(width 0.17145)
		(layer "F.Cu")
		(net "SDA_DR12")
	)
	(segment
		(start 74.904854 -152.24125)
		(end 75.449938 -151.696166)
		(width 0.17145)
		(layer "F.Cu")
		(net "SDA_DR12")
	)
	(segment
		(start 73.81875 -152.24125)
		(end 74.904854 -152.24125)
		(width 0.17145)
		(layer "F.Cu")
		(net "SDA_DR12")
	)
	(segment
		(start 31.948628 -217.5764)
		(end 30.6959 -217.5764)
		(width 0.17145)
		(layer "F.Cu")
		(net "SDA_DR12")
	)
	(segment
		(start 73.4822 -153.0477)
		(end 73.4822 -152.5778)
		(width 0.17145)
		(layer "F.Cu")
		(net "SDA_DR12")
	)
	(segment
		(start 32.060134 -216.8525)
		(end 32.060134 -217.464894)
		(width 0.17145)
		(layer "F.Cu")
		(net "SDA_DR12")
	)
	(segment
		(start 75.449938 -151.696166)
		(end 75.449938 -150.6982)
		(width 0.17145)
		(layer "F.Cu")
		(net "SDA_DR12")
	)
	(segment
		(start 74.168 -153.7335)
		(end 73.4822 -153.0477)
		(width 0.17145)
		(layer "F.Cu")
		(net "SDA_DR12")
	)
	(segment
		(start 73.642982 -156.3878)
		(end 73.4314 -156.176218)
		(width 0.17145)
		(layer "F.Cu")
		(net "SDA_DR12")
	)
	(segment
		(start 30.6959 -217.5764)
		(end 30.2895 -217.17)
		(width 0.17145)
		(layer "F.Cu")
		(net "SDA_DR12")
	)
	(segment
		(start 73.4314 -156.176218)
		(end 73.4314 -154.4701)
		(width 0.17145)
		(layer "F.Cu")
		(net "SDA_DR12")
	)
	(segment
		(start 73.4314 -154.4701)
		(end 74.168 -153.7335)
		(width 0.17145)
		(layer "F.Cu")
		(net "SDA_DR12")
	)
	(via
		(at 32.060134 -216.8525)
		(size 0.5588)
		(drill 0.3048)
		(layers "F.Cu" "B.Cu")
		(net "SDA_DR12")
	)
	(via
		(at 73.642982 -156.3878)
		(size 0.508)
		(drill 0.254)
		(layers "F.Cu" "B.Cu")
		(net "SDA_DR12")
	)
	(segment
		(start 32.060134 -216.8525)
		(end 32.060134 -217.482674)
		(width 0.17145)
		(layer "B.Cu")
		(net "SDA_DR12")
	)
	(segment
		(start 73.45045 -158.851854)
		(end 73.45045 -156.580332)
		(width 0.17145)
		(layer "B.Cu")
		(net "SDA_DR12")
	)
	(segment
		(start 62.96025 -194.08775)
		(end 62.96025 -169.342054)
		(width 0.17145)
		(layer "B.Cu")
		(net "SDA_DR12")
	)
	(segment
		(start 32.060134 -217.482674)
		(end 31.888684 -217.654124)
		(width 0.17145)
		(layer "B.Cu")
		(net "SDA_DR12")
	)
	(segment
		(start 31.162752 -217.425778)
		(end 31.162752 -215.750648)
		(width 0.17145)
		(layer "B.Cu")
		(net "SDA_DR12")
	)
	(segment
		(start 31.888684 -217.654124)
		(end 31.391098 -217.654124)
		(width 0.17145)
		(layer "B.Cu")
		(net "SDA_DR12")
	)
	(segment
		(start 62.96025 -169.342054)
		(end 73.45045 -158.851854)
		(width 0.17145)
		(layer "B.Cu")
		(net "SDA_DR12")
	)
	(segment
		(start 31.6484 -215.265)
		(end 41.783 -215.265)
		(width 0.17145)
		(layer "B.Cu")
		(net "SDA_DR12")
	)
	(segment
		(start 31.162752 -215.750648)
		(end 31.6484 -215.265)
		(width 0.17145)
		(layer "B.Cu")
		(net "SDA_DR12")
	)
	(segment
		(start 73.45045 -156.580332)
		(end 73.642982 -156.3878)
		(width 0.17145)
		(layer "B.Cu")
		(net "SDA_DR12")
	)
	(segment
		(start 31.391098 -217.654124)
		(end 31.162752 -217.425778)
		(width 0.17145)
		(layer "B.Cu")
		(net "SDA_DR12")
	)
	(segment
		(start 41.783 -215.265)
		(end 62.96025 -194.08775)
		(width 0.17145)
		(layer "B.Cu")
		(net "SDA_DR12")
	)
	(segment
		(start 71.924926 -362.859574)
		(end 71.1835 -363.601)
		(width 0.17145)
		(layer "F.Cu")
		(net "SDA_DR11")
	)
	(segment
		(start 30.2895 -320.167)
		(end 30.67685 -320.55435)
		(width 0.17145)
		(layer "F.Cu")
		(net "SDA_DR11")
	)
	(segment
		(start 68.84035 -362.85805)
		(end 70.44055 -362.85805)
		(width 0.17145)
		(layer "F.Cu")
		(net "SDA_DR11")
	)
	(segment
		(start 74.2188 -361.811062)
		(end 73.564242 -361.811062)
		(width 0.17145)
		(layer "F.Cu")
		(net "SDA_DR11")
	)
	(segment
		(start 70.44055 -362.85805)
		(end 71.1835 -363.601)
		(width 0.17145)
		(layer "F.Cu")
		(net "SDA_DR11")
	)
	(segment
		(start 68.6054 -363.093)
		(end 68.84035 -362.85805)
		(width 0.17145)
		(layer "F.Cu")
		(net "SDA_DR11")
	)
	(segment
		(start 60.917074 -320.55435)
		(end 61.6458 -319.825624)
		(width 0.17145)
		(layer "F.Cu")
		(net "SDA_DR11")
	)
	(segment
		(start 73.564242 -361.811062)
		(end 72.51573 -362.859574)
		(width 0.17145)
		(layer "F.Cu")
		(net "SDA_DR11")
	)
	(segment
		(start 72.51573 -362.859574)
		(end 71.924926 -362.859574)
		(width 0.17145)
		(layer "F.Cu")
		(net "SDA_DR11")
	)
	(segment
		(start 30.67685 -320.55435)
		(end 60.917074 -320.55435)
		(width 0.17145)
		(layer "F.Cu")
		(net "SDA_DR11")
	)
	(via
		(at 61.6458 -319.825624)
		(size 0.5588)
		(drill 0.3048)
		(layers "F.Cu" "B.Cu")
		(net "SDA_DR11")
	)
	(via
		(at 68.6054 -363.093)
		(size 0.508)
		(drill 0.254)
		(layers "F.Cu" "B.Cu")
		(net "SDA_DR11")
	)
	(segment
		(start 61.6458 -320.2051)
		(end 61.6458 -319.825624)
		(width 0.17145)
		(layer "B.Cu")
		(net "SDA_DR11")
	)
	(segment
		(start 68.31965 -362.80725)
		(end 66.242946 -362.80725)
		(width 0.17145)
		(layer "B.Cu")
		(net "SDA_DR11")
	)
	(segment
		(start 68.6054 -363.093)
		(end 68.31965 -362.80725)
		(width 0.17145)
		(layer "B.Cu")
		(net "SDA_DR11")
	)
	(segment
		(start 66.242946 -362.80725)
		(end 58.85815 -355.422454)
		(width 0.17145)
		(layer "B.Cu")
		(net "SDA_DR11")
	)
	(segment
		(start 60.019946 -320.37655)
		(end 61.47435 -320.37655)
		(width 0.17145)
		(layer "B.Cu")
		(net "SDA_DR11")
	)
	(segment
		(start 58.85815 -321.538346)
		(end 60.019946 -320.37655)
		(width 0.17145)
		(layer "B.Cu")
		(net "SDA_DR11")
	)
	(segment
		(start 61.47435 -320.37655)
		(end 61.6458 -320.2051)
		(width 0.17145)
		(layer "B.Cu")
		(net "SDA_DR11")
	)
	(segment
		(start 58.85815 -355.422454)
		(end 58.85815 -321.538346)
		(width 0.17145)
		(layer "B.Cu")
		(net "SDA_DR11")
	)
	(segment
		(start 75.360276 -365.339376)
		(end 75.360276 -364.618524)
		(width 0.17145)
		(layer "F.Cu")
		(net "SDA_DR10")
	)
	(segment
		(start 75.3618 -368.444018)
		(end 75.3618 -366.8141)
		(width 0.17145)
		(layer "F.Cu")
		(net "SDA_DR10")
	)
	(segment
		(start 32.305752 -424.054778)
		(end 32.305752 -424.61815)
		(width 0.17145)
		(layer "F.Cu")
		(net "SDA_DR10")
	)
	(segment
		(start 75.950064 -364.028736)
		(end 75.950064 -363.0422)
		(width 0.17145)
		(layer "F.Cu")
		(net "SDA_DR10")
	)
	(segment
		(start 30.6197 -423.4942)
		(end 31.745174 -423.4942)
		(width 0.17145)
		(layer "F.Cu")
		(net "SDA_DR10")
	)
	(segment
		(start 76.0984 -366.0775)
		(end 75.360276 -365.339376)
		(width 0.17145)
		(layer "F.Cu")
		(net "SDA_DR10")
	)
	(segment
		(start 31.745174 -423.4942)
		(end 32.305752 -424.054778)
		(width 0.17145)
		(layer "F.Cu")
		(net "SDA_DR10")
	)
	(segment
		(start 32.477202 -424.7896)
		(end 33.107376 -424.7896)
		(width 0.17145)
		(layer "F.Cu")
		(net "SDA_DR10")
	)
	(segment
		(start 32.305752 -424.61815)
		(end 32.477202 -424.7896)
		(width 0.17145)
		(layer "F.Cu")
		(net "SDA_DR10")
	)
	(segment
		(start 75.598782 -368.681)
		(end 75.3618 -368.444018)
		(width 0.17145)
		(layer "F.Cu")
		(net "SDA_DR10")
	)
	(segment
		(start 75.3618 -366.8141)
		(end 76.0984 -366.0775)
		(width 0.17145)
		(layer "F.Cu")
		(net "SDA_DR10")
	)
	(segment
		(start 30.2895 -423.164)
		(end 30.6197 -423.4942)
		(width 0.17145)
		(layer "F.Cu")
		(net "SDA_DR10")
	)
	(segment
		(start 75.360276 -364.618524)
		(end 75.950064 -364.028736)
		(width 0.17145)
		(layer "F.Cu")
		(net "SDA_DR10")
	)
	(via
		(at 33.107376 -424.7896)
		(size 0.5588)
		(drill 0.3048)
		(layers "F.Cu" "B.Cu")
		(net "SDA_DR10")
	)
	(via
		(at 75.598782 -368.681)
		(size 0.508)
		(drill 0.254)
		(layers "F.Cu" "B.Cu")
		(net "SDA_DR10")
	)
	(segment
		(start 32.3596 -423.462704)
		(end 76.831698 -378.990606)
		(width 0.17145)
		(layer "B.Cu")
		(net "SDA_DR10")
	)
	(segment
		(start 32.3596 -424.671998)
		(end 32.3596 -423.462704)
		(width 0.17145)
		(layer "B.Cu")
		(net "SDA_DR10")
	)
	(segment
		(start 32.477202 -424.7896)
		(end 32.3596 -424.671998)
		(width 0.17145)
		(layer "B.Cu")
		(net "SDA_DR10")
	)
	(segment
		(start 33.107376 -424.7896)
		(end 32.477202 -424.7896)
		(width 0.17145)
		(layer "B.Cu")
		(net "SDA_DR10")
	)
	(segment
		(start 76.831698 -378.990606)
		(end 76.831698 -372.260368)
		(width 0.17145)
		(layer "B.Cu")
		(net "SDA_DR10")
	)
	(segment
		(start 75.3872 -370.81587)
		(end 75.3872 -368.892582)
		(width 0.17145)
		(layer "B.Cu")
		(net "SDA_DR10")
	)
	(segment
		(start 76.831698 -372.260368)
		(end 75.3872 -370.81587)
		(width 0.17145)
		(layer "B.Cu")
		(net "SDA_DR10")
	)
	(segment
		(start 75.3872 -368.892582)
		(end 75.598782 -368.681)
		(width 0.17145)
		(layer "B.Cu")
		(net "SDA_DR10")
	)
	(segment
		(start 216.5985 -391.795)
		(end 216.2429 -391.4394)
		(width 0.17145)
		(layer "F.Cu")
		(net "SDA_DR1")
	)
	(segment
		(start 216.2429 -391.4394)
		(end 115.830096 -391.4394)
		(width 0.17145)
		(layer "F.Cu")
		(net "SDA_DR1")
	)
	(segment
		(start 78.1812 -360.811064)
		(end 80.450436 -360.811064)
		(width 0.17145)
		(layer "F.Cu")
		(net "SDA_DR1")
	)
	(segment
		(start 82.0039 -360.8324)
		(end 81.2165 -360.045)
		(width 0.17145)
		(layer "F.Cu")
		(net "SDA_DR1")
	)
	(segment
		(start 83.82 -360.595418)
		(end 83.583018 -360.8324)
		(width 0.17145)
		(layer "F.Cu")
		(net "SDA_DR1")
	)
	(segment
		(start 115.830096 -391.4394)
		(end 89.59215 -365.201454)
		(width 0.17145)
		(layer "F.Cu")
		(net "SDA_DR1")
	)
	(segment
		(start 89.59215 -358.56545)
		(end 89.4207 -358.394)
		(width 0.17145)
		(layer "F.Cu")
		(net "SDA_DR1")
	)
	(segment
		(start 89.59215 -365.201454)
		(end 89.59215 -358.56545)
		(width 0.17145)
		(layer "F.Cu")
		(net "SDA_DR1")
	)
	(segment
		(start 80.450436 -360.811064)
		(end 81.2165 -360.045)
		(width 0.17145)
		(layer "F.Cu")
		(net "SDA_DR1")
	)
	(segment
		(start 89.4207 -358.394)
		(end 89.066624 -358.394)
		(width 0.17145)
		(layer "F.Cu")
		(net "SDA_DR1")
	)
	(segment
		(start 83.583018 -360.8324)
		(end 82.0039 -360.8324)
		(width 0.17145)
		(layer "F.Cu")
		(net "SDA_DR1")
	)
	(via
		(at 83.82 -360.595418)
		(size 0.508)
		(drill 0.254)
		(layers "F.Cu" "B.Cu")
		(net "SDA_DR1")
	)
	(via
		(at 89.066624 -358.394)
		(size 0.5588)
		(drill 0.3048)
		(layers "F.Cu" "B.Cu")
		(net "SDA_DR1")
	)
	(segment
		(start 84.031582 -360.807)
		(end 83.82 -360.595418)
		(width 0.17145)
		(layer "B.Cu")
		(net "SDA_DR1")
	)
	(segment
		(start 89.71915 -359.306876)
		(end 88.219026 -360.807)
		(width 0.17145)
		(layer "B.Cu")
		(net "SDA_DR1")
	)
	(segment
		(start 89.5604 -358.394)
		(end 89.71915 -358.55275)
		(width 0.17145)
		(layer "B.Cu")
		(net "SDA_DR1")
	)
	(segment
		(start 89.066624 -358.394)
		(end 89.5604 -358.394)
		(width 0.17145)
		(layer "B.Cu")
		(net "SDA_DR1")
	)
	(segment
		(start 89.71915 -358.55275)
		(end 89.71915 -359.306876)
		(width 0.17145)
		(layer "B.Cu")
		(net "SDA_DR1")
	)
	(segment
		(start 88.219026 -360.807)
		(end 84.031582 -360.807)
		(width 0.17145)
		(layer "B.Cu")
		(net "SDA_DR1")
	)
	(segment
		(start 180.934106 -445.576452)
		(end 209.615024 -474.25737)
		(width 0.17145)
		(layer "F.Cu")
		(net "SDA_DR0")
	)
	(segment
		(start 83.506818 -363.8804)
		(end 81.9531 -363.8804)
		(width 0.17145)
		(layer "F.Cu")
		(net "SDA_DR0")
	)
	(segment
		(start 214.3252 -492.6076)
		(end 215.9889 -492.6076)
		(width 0.17145)
		(layer "F.Cu")
		(net "SDA_DR0")
	)
	(segment
		(start 215.9889 -492.6076)
		(end 216.3445 -492.9632)
		(width 0.17145)
		(layer "F.Cu")
		(net "SDA_DR0")
	)
	(segment
		(start 209.615024 -487.897424)
		(end 214.3252 -492.6076)
		(width 0.17145)
		(layer "F.Cu")
		(net "SDA_DR0")
	)
	(segment
		(start 114.466624 -442.722)
		(end 114.841274 -442.722)
		(width 0.17145)
		(layer "F.Cu")
		(net "SDA_DR0")
	)
	(segment
		(start 115.01755 -444.206884)
		(end 116.387118 -445.576452)
		(width 0.17145)
		(layer "F.Cu")
		(net "SDA_DR0")
	)
	(segment
		(start 80.183228 -363.881924)
		(end 80.478376 -363.881924)
		(width 0.17145)
		(layer "F.Cu")
		(net "SDA_DR0")
	)
	(segment
		(start 80.478376 -363.881924)
		(end 81.2165 -363.1438)
		(width 0.17145)
		(layer "F.Cu")
		(net "SDA_DR0")
	)
	(segment
		(start 83.82 -363.567218)
		(end 83.506818 -363.8804)
		(width 0.17145)
		(layer "F.Cu")
		(net "SDA_DR0")
	)
	(segment
		(start 79.7306 -362.5342)
		(end 79.7306 -363.429296)
		(width 0.17145)
		(layer "F.Cu")
		(net "SDA_DR0")
	)
	(segment
		(start 114.841274 -442.722)
		(end 115.01755 -442.898276)
		(width 0.17145)
		(layer "F.Cu")
		(net "SDA_DR0")
	)
	(segment
		(start 79.7306 -363.429296)
		(end 80.183228 -363.881924)
		(width 0.17145)
		(layer "F.Cu")
		(net "SDA_DR0")
	)
	(segment
		(start 78.1812 -361.811062)
		(end 79.007462 -361.811062)
		(width 0.17145)
		(layer "F.Cu")
		(net "SDA_DR0")
	)
	(segment
		(start 116.387118 -445.576452)
		(end 180.934106 -445.576452)
		(width 0.17145)
		(layer "F.Cu")
		(net "SDA_DR0")
	)
	(segment
		(start 115.01755 -442.898276)
		(end 115.01755 -444.206884)
		(width 0.17145)
		(layer "F.Cu")
		(net "SDA_DR0")
	)
	(segment
		(start 81.9531 -363.8804)
		(end 81.2165 -363.1438)
		(width 0.17145)
		(layer "F.Cu")
		(net "SDA_DR0")
	)
	(segment
		(start 209.615024 -474.25737)
		(end 209.615024 -487.897424)
		(width 0.17145)
		(layer "F.Cu")
		(net "SDA_DR0")
	)
	(segment
		(start 79.007462 -361.811062)
		(end 79.7306 -362.5342)
		(width 0.17145)
		(layer "F.Cu")
		(net "SDA_DR0")
	)
	(via
		(at 114.466624 -442.722)
		(size 0.5588)
		(drill 0.3048)
		(layers "F.Cu" "B.Cu")
		(net "SDA_DR0")
	)
	(via
		(at 83.82 -363.567218)
		(size 0.508)
		(drill 0.254)
		(layers "F.Cu" "B.Cu")
		(net "SDA_DR0")
	)
	(segment
		(start 113.458752 -390.826752)
		(end 113.458752 -443.231778)
		(width 0.17145)
		(layer "B.Cu")
		(net "SDA_DR0")
	)
	(segment
		(start 114.091974 -443.865)
		(end 115.143026 -443.865)
		(width 0.17145)
		(layer "B.Cu")
		(net "SDA_DR0")
	)
	(segment
		(start 113.458752 -443.231778)
		(end 114.091974 -443.865)
		(width 0.17145)
		(layer "B.Cu")
		(net "SDA_DR0")
	)
	(segment
		(start 84.056982 -363.8042)
		(end 86.4362 -363.8042)
		(width 0.17145)
		(layer "B.Cu")
		(net "SDA_DR0")
	)
	(segment
		(start 83.82 -363.567218)
		(end 84.056982 -363.8042)
		(width 0.17145)
		(layer "B.Cu")
		(net "SDA_DR0")
	)
	(segment
		(start 115.268248 -443.739778)
		(end 115.268248 -442.89345)
		(width 0.17145)
		(layer "B.Cu")
		(net "SDA_DR0")
	)
	(segment
		(start 115.268248 -442.89345)
		(end 115.096798 -442.722)
		(width 0.17145)
		(layer "B.Cu")
		(net "SDA_DR0")
	)
	(segment
		(start 115.096798 -442.722)
		(end 114.466624 -442.722)
		(width 0.17145)
		(layer "B.Cu")
		(net "SDA_DR0")
	)
	(segment
		(start 115.143026 -443.865)
		(end 115.268248 -443.739778)
		(width 0.17145)
		(layer "B.Cu")
		(net "SDA_DR0")
	)
	(segment
		(start 86.4362 -363.8042)
		(end 113.458752 -390.826752)
		(width 0.17145)
		(layer "B.Cu")
		(net "SDA_DR0")
	)
	(segment
		(start 250.723908 -419.379908)
		(end 256.474976 -419.379908)
		(width 0.17145)
		(layer "F.Cu")
		(net "SD_LATCH_RELEASE")
	)
	(segment
		(start 10.52068 -300.188122)
		(end 11.773662 -298.93514)
		(width 0.17145)
		(layer "F.Cu")
		(net "SD_LATCH_RELEASE")
	)
	(segment
		(start 10.414 -273.304)
		(end 10.414 -271.78)
		(width 0.17145)
		(layer "F.Cu")
		(net "SD_LATCH_RELEASE")
	)
	(segment
		(start 10.52068 -325.437246)
		(end 10.52068 -300.188122)
		(width 0.17145)
		(layer "F.Cu")
		(net "SD_LATCH_RELEASE")
	)
	(segment
		(start 11.773662 -274.663662)
		(end 10.414 -273.304)
		(width 0.17145)
		(layer "F.Cu")
		(net "SD_LATCH_RELEASE")
	)
	(segment
		(start 9.360662 -332.168754)
		(end 9.360662 -326.597264)
		(width 0.17145)
		(layer "F.Cu")
		(net "SD_LATCH_RELEASE")
	)
	(segment
		(start 10.414 -271.78)
		(end 10.414 -270.3195)
		(width 0.17145)
		(layer "F.Cu")
		(net "SD_LATCH_RELEASE")
	)
	(segment
		(start 9.18718 -332.342236)
		(end 9.360662 -332.168754)
		(width 0.17145)
		(layer "F.Cu")
		(net "SD_LATCH_RELEASE")
	)
	(segment
		(start 239.649 -418.335206)
		(end 249.679206 -418.335206)
		(width 0.17145)
		(layer "F.Cu")
		(net "SD_LATCH_RELEASE")
	)
	(segment
		(start 9.360662 -326.597264)
		(end 10.52068 -325.437246)
		(width 0.17145)
		(layer "F.Cu")
		(net "SD_LATCH_RELEASE")
	)
	(segment
		(start 249.679206 -418.335206)
		(end 250.723908 -419.379908)
		(width 0.17145)
		(layer "F.Cu")
		(net "SD_LATCH_RELEASE")
	)
	(segment
		(start 11.773662 -298.93514)
		(end 11.773662 -274.663662)
		(width 0.17145)
		(layer "F.Cu")
		(net "SD_LATCH_RELEASE")
	)
	(via
		(at 239.649 -418.335206)
		(size 0.508)
		(drill 0.254)
		(layers "F.Cu" "B.Cu")
		(net "SD_LATCH_RELEASE")
	)
	(via
		(at 10.414 -271.78)
		(size 0.7112)
		(drill 0.3556)
		(layers "F.Cu" "B.Cu")
		(net "SD_LATCH_RELEASE")
	)
	(via
		(at 9.18718 -332.342236)
		(size 0.508)
		(drill 0.254)
		(layers "F.Cu" "B.Cu")
		(net "SD_LATCH_RELEASE")
	)
	(segment
		(start 18.8976 -322.74002)
		(end 18.8976 -324.73519)
		(width 0.1524)
		(layer "In5.Cu")
		(net "SD_LATCH_RELEASE")
	)
	(segment
		(start 236.7026 -415.388806)
		(end 236.7026 -341.35822)
		(width 0.1524)
		(layer "In5.Cu")
		(net "SD_LATCH_RELEASE")
	)
	(segment
		(start 11.290554 -332.342236)
		(end 9.18718 -332.342236)
		(width 0.1524)
		(layer "In5.Cu")
		(net "SD_LATCH_RELEASE")
	)
	(segment
		(start 64.54902 -301.9806)
		(end 57.81802 -301.9806)
		(width 0.1524)
		(layer "In5.Cu")
		(net "SD_LATCH_RELEASE")
	)
	(segment
		(start 43.84802 -315.9506)
		(end 25.68702 -315.9506)
		(width 0.1524)
		(layer "In5.Cu")
		(net "SD_LATCH_RELEASE")
	)
	(segment
		(start 18.8976 -324.73519)
		(end 11.290554 -332.342236)
		(width 0.1524)
		(layer "In5.Cu")
		(net "SD_LATCH_RELEASE")
	)
	(segment
		(start 221.0054 -325.66102)
		(end 221.0054 -302.92802)
		(width 0.1524)
		(layer "In5.Cu")
		(net "SD_LATCH_RELEASE")
	)
	(segment
		(start 210.78698 -292.7096)
		(end 73.82002 -292.7096)
		(width 0.1524)
		(layer "In5.Cu")
		(net "SD_LATCH_RELEASE")
	)
	(segment
		(start 57.81802 -301.9806)
		(end 43.84802 -315.9506)
		(width 0.1524)
		(layer "In5.Cu")
		(net "SD_LATCH_RELEASE")
	)
	(segment
		(start 25.68702 -315.9506)
		(end 18.8976 -322.74002)
		(width 0.1524)
		(layer "In5.Cu")
		(net "SD_LATCH_RELEASE")
	)
	(segment
		(start 221.0054 -302.92802)
		(end 210.78698 -292.7096)
		(width 0.1524)
		(layer "In5.Cu")
		(net "SD_LATCH_RELEASE")
	)
	(segment
		(start 73.82002 -292.7096)
		(end 64.54902 -301.9806)
		(width 0.1524)
		(layer "In5.Cu")
		(net "SD_LATCH_RELEASE")
	)
	(segment
		(start 236.7026 -341.35822)
		(end 221.0054 -325.66102)
		(width 0.1524)
		(layer "In5.Cu")
		(net "SD_LATCH_RELEASE")
	)
	(segment
		(start 239.649 -418.335206)
		(end 236.7026 -415.388806)
		(width 0.1524)
		(layer "In5.Cu")
		(net "SD_LATCH_RELEASE")
	)
	(segment
		(start 46.843696 -98.171)
		(end 19.11731 -98.171)
		(width 0.17145)
		(layer "F.Cu")
		(net "SCL_DR9")
	)
	(segment
		(start 60.9854 -98.879152)
		(end 59.998102 -99.86645)
		(width 0.17145)
		(layer "F.Cu")
		(net "SCL_DR9")
	)
	(segment
		(start 19.11731 -98.171)
		(end 17.585182 -96.638872)
		(width 0.17145)
		(layer "F.Cu")
		(net "SCL_DR9")
	)
	(segment
		(start 70.4469 -144.2466)
		(end 71.1835 -143.51)
		(width 0.17145)
		(layer "F.Cu")
		(net "SCL_DR9")
	)
	(segment
		(start 24.255476 -81.87055)
		(end 31.34995 -81.87055)
		(width 0.17145)
		(layer "F.Cu")
		(net "SCL_DR9")
	)
	(segment
		(start 74.950066 -146.6596)
		(end 74.720704 -146.6596)
		(width 0.17145)
		(layer "F.Cu")
		(net "SCL_DR9")
	)
	(segment
		(start 60.9854 -97.189544)
		(end 60.9854 -98.879152)
		(width 0.17145)
		(layer "F.Cu")
		(net "SCL_DR9")
	)
	(segment
		(start 61.761624 -97.04324)
		(end 61.13145 -97.04324)
		(width 0.17145)
		(layer "F.Cu")
		(net "SCL_DR9")
	)
	(segment
		(start 17.585182 -96.638872)
		(end 17.585182 -88.540844)
		(width 0.17145)
		(layer "F.Cu")
		(net "SCL_DR9")
	)
	(segment
		(start 61.13145 -97.04324)
		(end 61.025024 -97.14992)
		(width 0.17145)
		(layer "F.Cu")
		(net "SCL_DR9")
	)
	(segment
		(start 71.92645 -144.25295)
		(end 71.1835 -143.51)
		(width 0.17145)
		(layer "F.Cu")
		(net "SCL_DR9")
	)
	(segment
		(start 68.58 -144.05102)
		(end 68.77558 -144.2466)
		(width 0.17145)
		(layer "F.Cu")
		(net "SCL_DR9")
	)
	(segment
		(start 68.77558 -144.2466)
		(end 70.4469 -144.2466)
		(width 0.17145)
		(layer "F.Cu")
		(net "SCL_DR9")
	)
	(segment
		(start 48.539146 -99.86645)
		(end 46.843696 -98.171)
		(width 0.17145)
		(layer "F.Cu")
		(net "SCL_DR9")
	)
	(segment
		(start 74.720704 -146.6596)
		(end 72.314054 -144.25295)
		(width 0.17145)
		(layer "F.Cu")
		(net "SCL_DR9")
	)
	(segment
		(start 61.025024 -97.14992)
		(end 60.9854 -97.189544)
		(width 0.17145)
		(layer "F.Cu")
		(net "SCL_DR9")
	)
	(segment
		(start 31.34995 -81.87055)
		(end 31.6865 -81.534)
		(width 0.17145)
		(layer "F.Cu")
		(net "SCL_DR9")
	)
	(segment
		(start 59.998102 -99.86645)
		(end 48.539146 -99.86645)
		(width 0.17145)
		(layer "F.Cu")
		(net "SCL_DR9")
	)
	(segment
		(start 72.314054 -144.25295)
		(end 71.92645 -144.25295)
		(width 0.17145)
		(layer "F.Cu")
		(net "SCL_DR9")
	)
	(segment
		(start 17.585182 -88.540844)
		(end 24.255476 -81.87055)
		(width 0.17145)
		(layer "F.Cu")
		(net "SCL_DR9")
	)
	(via
		(at 68.58 -144.05102)
		(size 0.508)
		(drill 0.254)
		(layers "F.Cu" "B.Cu")
		(net "SCL_DR9")
	)
	(via
		(at 61.761624 -97.04324)
		(size 0.5588)
		(drill 0.3048)
		(layers "F.Cu" "B.Cu")
		(net "SCL_DR9")
	)
	(segment
		(start 68.58 -144.05102)
		(end 68.35267 -144.27835)
		(width 0.17145)
		(layer "B.Cu")
		(net "SCL_DR9")
	)
	(segment
		(start 68.35267 -144.27835)
		(end 65.00368 -144.27835)
		(width 0.17145)
		(layer "B.Cu")
		(net "SCL_DR9")
	)
	(segment
		(start 61.382148 -97.04324)
		(end 61.761624 -97.04324)
		(width 0.17145)
		(layer "B.Cu")
		(net "SCL_DR9")
	)
	(segment
		(start 65.00368 -144.27835)
		(end 61.210698 -140.485368)
		(width 0.17145)
		(layer "B.Cu")
		(net "SCL_DR9")
	)
	(segment
		(start 61.210698 -140.485368)
		(end 61.210698 -97.21469)
		(width 0.17145)
		(layer "B.Cu")
		(net "SCL_DR9")
	)
	(segment
		(start 61.210698 -97.21469)
		(end 61.382148 -97.04324)
		(width 0.17145)
		(layer "B.Cu")
		(net "SCL_DR9")
	)
	(segment
		(start 31.32455 -184.89295)
		(end 24.764746 -184.89295)
		(width 0.17145)
		(layer "F.Cu")
		(net "SCL_DR8")
	)
	(segment
		(start 44.01185 -200.45045)
		(end 47.371 -203.8096)
		(width 0.17145)
		(layer "F.Cu")
		(net "SCL_DR8")
	)
	(segment
		(start 47.371 -205.11135)
		(end 47.19955 -205.2828)
		(width 0.17145)
		(layer "F.Cu")
		(net "SCL_DR8")
	)
	(segment
		(start 47.371 -203.8096)
		(end 47.371 -205.11135)
		(width 0.17145)
		(layer "F.Cu")
		(net "SCL_DR8")
	)
	(segment
		(start 20.599146 -200.45045)
		(end 44.01185 -200.45045)
		(width 0.17145)
		(layer "F.Cu")
		(net "SCL_DR8")
	)
	(segment
		(start 70.4469 -150.3426)
		(end 71.1835 -149.606)
		(width 0.17145)
		(layer "F.Cu")
		(net "SCL_DR8")
	)
	(segment
		(start 47.19955 -205.2828)
		(end 46.569376 -205.2828)
		(width 0.17145)
		(layer "F.Cu")
		(net "SCL_DR8")
	)
	(segment
		(start 19.20875 -199.060054)
		(end 20.599146 -200.45045)
		(width 0.17145)
		(layer "F.Cu")
		(net "SCL_DR8")
	)
	(segment
		(start 19.20875 -190.448946)
		(end 19.20875 -199.060054)
		(width 0.17145)
		(layer "F.Cu")
		(net "SCL_DR8")
	)
	(segment
		(start 24.764746 -184.89295)
		(end 19.20875 -190.448946)
		(width 0.17145)
		(layer "F.Cu")
		(net "SCL_DR8")
	)
	(segment
		(start 72.623426 -150.3426)
		(end 73.498964 -149.467062)
		(width 0.17145)
		(layer "F.Cu")
		(net "SCL_DR8")
	)
	(segment
		(start 73.498964 -149.467062)
		(end 74.2188 -149.467062)
		(width 0.17145)
		(layer "F.Cu")
		(net "SCL_DR8")
	)
	(segment
		(start 68.77558 -150.3426)
		(end 70.4469 -150.3426)
		(width 0.17145)
		(layer "F.Cu")
		(net "SCL_DR8")
	)
	(segment
		(start 31.6865 -184.531)
		(end 31.32455 -184.89295)
		(width 0.17145)
		(layer "F.Cu")
		(net "SCL_DR8")
	)
	(segment
		(start 71.1835 -149.606)
		(end 71.9201 -150.3426)
		(width 0.17145)
		(layer "F.Cu")
		(net "SCL_DR8")
	)
	(segment
		(start 71.9201 -150.3426)
		(end 72.623426 -150.3426)
		(width 0.17145)
		(layer "F.Cu")
		(net "SCL_DR8")
	)
	(segment
		(start 68.5292 -150.09622)
		(end 68.77558 -150.3426)
		(width 0.17145)
		(layer "F.Cu")
		(net "SCL_DR8")
	)
	(via
		(at 46.569376 -205.2828)
		(size 0.5588)
		(drill 0.3048)
		(layers "F.Cu" "B.Cu")
		(net "SCL_DR8")
	)
	(via
		(at 68.5292 -150.09622)
		(size 0.508)
		(drill 0.254)
		(layers "F.Cu" "B.Cu")
		(net "SCL_DR8")
	)
	(segment
		(start 47.0408 -205.2828)
		(end 47.22495 -205.09865)
		(width 0.17145)
		(layer "B.Cu")
		(net "SCL_DR8")
	)
	(segment
		(start 60.836302 -189.558168)
		(end 60.836302 -155.806394)
		(width 0.17145)
		(layer "B.Cu")
		(net "SCL_DR8")
	)
	(segment
		(start 60.836302 -155.806394)
		(end 66.319146 -150.32355)
		(width 0.17145)
		(layer "B.Cu")
		(net "SCL_DR8")
	)
	(segment
		(start 47.22495 -205.09865)
		(end 47.22495 -203.16952)
		(width 0.17145)
		(layer "B.Cu")
		(net "SCL_DR8")
	)
	(segment
		(start 68.30187 -150.32355)
		(end 68.5292 -150.09622)
		(width 0.17145)
		(layer "B.Cu")
		(net "SCL_DR8")
	)
	(segment
		(start 46.569376 -205.2828)
		(end 47.0408 -205.2828)
		(width 0.17145)
		(layer "B.Cu")
		(net "SCL_DR8")
	)
	(segment
		(start 47.22495 -203.16952)
		(end 60.836302 -189.558168)
		(width 0.17145)
		(layer "B.Cu")
		(net "SCL_DR8")
	)
	(segment
		(start 66.319146 -150.32355)
		(end 68.30187 -150.32355)
		(width 0.17145)
		(layer "B.Cu")
		(net "SCL_DR8")
	)
	(segment
		(start 71.1835 -358.521)
		(end 71.17715 -358.521)
		(width 0.17145)
		(layer "F.Cu")
		(net "SCL_DR7")
	)
	(segment
		(start 72.105774 -359.3338)
		(end 71.882 -359.3338)
		(width 0.17145)
		(layer "F.Cu")
		(net "SCL_DR7")
	)
	(segment
		(start 70.44055 -359.2576)
		(end 68.80098 -359.2576)
		(width 0.17145)
		(layer "F.Cu")
		(net "SCL_DR7")
	)
	(segment
		(start 19.763994 -302.257968)
		(end 21.544026 -304.038)
		(width 0.17145)
		(layer "F.Cu")
		(net "SCL_DR7")
	)
	(segment
		(start 67.355974 -304.038)
		(end 69.56425 -301.829724)
		(width 0.17145)
		(layer "F.Cu")
		(net "SCL_DR7")
	)
	(segment
		(start 71.882 -359.3338)
		(end 71.1835 -358.6353)
		(width 0.17145)
		(layer "F.Cu")
		(net "SCL_DR7")
	)
	(segment
		(start 69.56425 -300.645322)
		(end 69.712332 -300.49724)
		(width 0.17145)
		(layer "F.Cu")
		(net "SCL_DR7")
	)
	(segment
		(start 31.34995 -287.86455)
		(end 24.890476 -287.86455)
		(width 0.17145)
		(layer "F.Cu")
		(net "SCL_DR7")
	)
	(segment
		(start 71.17715 -358.521)
		(end 70.44055 -359.2576)
		(width 0.17145)
		(layer "F.Cu")
		(net "SCL_DR7")
	)
	(segment
		(start 19.764248 -301.800514)
		(end 19.763994 -301.800768)
		(width 0.17145)
		(layer "F.Cu")
		(net "SCL_DR7")
	)
	(segment
		(start 31.6865 -287.528)
		(end 31.34995 -287.86455)
		(width 0.17145)
		(layer "F.Cu")
		(net "SCL_DR7")
	)
	(segment
		(start 19.763994 -301.800768)
		(end 19.763994 -302.257968)
		(width 0.17145)
		(layer "F.Cu")
		(net "SCL_DR7")
	)
	(segment
		(start 68.80098 -359.2576)
		(end 68.58 -359.03662)
		(width 0.17145)
		(layer "F.Cu")
		(net "SCL_DR7")
	)
	(segment
		(start 73.082912 -360.310938)
		(end 72.105774 -359.3338)
		(width 0.17145)
		(layer "F.Cu")
		(net "SCL_DR7")
	)
	(segment
		(start 69.56425 -301.829724)
		(end 69.56425 -300.645322)
		(width 0.17145)
		(layer "F.Cu")
		(net "SCL_DR7")
	)
	(segment
		(start 71.1835 -358.6353)
		(end 71.1835 -358.521)
		(width 0.17145)
		(layer "F.Cu")
		(net "SCL_DR7")
	)
	(segment
		(start 69.712332 -300.49724)
		(end 70.191376 -300.49724)
		(width 0.17145)
		(layer "F.Cu")
		(net "SCL_DR7")
	)
	(segment
		(start 74.2188 -360.310938)
		(end 73.082912 -360.310938)
		(width 0.17145)
		(layer "F.Cu")
		(net "SCL_DR7")
	)
	(segment
		(start 19.764248 -292.990778)
		(end 19.764248 -301.800514)
		(width 0.17145)
		(layer "F.Cu")
		(net "SCL_DR7")
	)
	(segment
		(start 21.544026 -304.038)
		(end 67.355974 -304.038)
		(width 0.17145)
		(layer "F.Cu")
		(net "SCL_DR7")
	)
	(segment
		(start 24.890476 -287.86455)
		(end 19.764248 -292.990778)
		(width 0.17145)
		(layer "F.Cu")
		(net "SCL_DR7")
	)
	(via
		(at 70.191376 -300.49724)
		(size 0.5588)
		(drill 0.3048)
		(layers "F.Cu" "B.Cu")
		(net "SCL_DR7")
	)
	(via
		(at 68.58 -359.03662)
		(size 0.508)
		(drill 0.254)
		(layers "F.Cu" "B.Cu")
		(net "SCL_DR7")
	)
	(segment
		(start 69.64045 -300.66869)
		(end 69.8119 -300.49724)
		(width 0.17145)
		(layer "B.Cu")
		(net "SCL_DR7")
	)
	(segment
		(start 65.14465 -351.206054)
		(end 69.64045 -346.710254)
		(width 0.17145)
		(layer "B.Cu")
		(net "SCL_DR7")
	)
	(segment
		(start 67.49288 -359.23855)
		(end 65.14465 -356.89032)
		(width 0.17145)
		(layer "B.Cu")
		(net "SCL_DR7")
	)
	(segment
		(start 68.37807 -359.23855)
		(end 67.49288 -359.23855)
		(width 0.17145)
		(layer "B.Cu")
		(net "SCL_DR7")
	)
	(segment
		(start 68.58 -359.03662)
		(end 68.37807 -359.23855)
		(width 0.17145)
		(layer "B.Cu")
		(net "SCL_DR7")
	)
	(segment
		(start 65.14465 -356.89032)
		(end 65.14465 -351.206054)
		(width 0.17145)
		(layer "B.Cu")
		(net "SCL_DR7")
	)
	(segment
		(start 69.8119 -300.49724)
		(end 70.191376 -300.49724)
		(width 0.17145)
		(layer "B.Cu")
		(net "SCL_DR7")
	)
	(segment
		(start 69.64045 -346.710254)
		(end 69.64045 -300.66869)
		(width 0.17145)
		(layer "B.Cu")
		(net "SCL_DR7")
	)
	(segment
		(start 71.76135 -368.52987)
		(end 71.76135 -366.80775)
		(width 0.17145)
		(layer "F.Cu")
		(net "SCL_DR6")
	)
	(segment
		(start 30.0736 -390.8552)
		(end 29.816298 -390.597898)
		(width 0.17145)
		(layer "F.Cu")
		(net "SCL_DR6")
	)
	(segment
		(start 74.1426 -362.310934)
		(end 74.1426 -362.641896)
		(width 0.17145)
		(layer "F.Cu")
		(net "SCL_DR6")
	)
	(segment
		(start 31.6865 -390.525)
		(end 31.3563 -390.8552)
		(width 0.17145)
		(layer "F.Cu")
		(net "SCL_DR6")
	)
	(segment
		(start 31.3563 -390.8552)
		(end 30.0736 -390.8552)
		(width 0.17145)
		(layer "F.Cu")
		(net "SCL_DR6")
	)
	(segment
		(start 71.861426 -364.92307)
		(end 71.861426 -365.247174)
		(width 0.17145)
		(layer "F.Cu")
		(net "SCL_DR6")
	)
	(segment
		(start 74.1426 -362.641896)
		(end 71.861426 -364.92307)
		(width 0.17145)
		(layer "F.Cu")
		(net "SCL_DR6")
	)
	(segment
		(start 71.63562 -368.6556)
		(end 71.76135 -368.52987)
		(width 0.17145)
		(layer "F.Cu")
		(net "SCL_DR6")
	)
	(segment
		(start 71.861426 -365.247174)
		(end 71.0311 -366.0775)
		(width 0.17145)
		(layer "F.Cu")
		(net "SCL_DR6")
	)
	(segment
		(start 71.76135 -366.80775)
		(end 71.0311 -366.0775)
		(width 0.17145)
		(layer "F.Cu")
		(net "SCL_DR6")
	)
	(segment
		(start 29.816298 -390.597898)
		(end 29.816298 -390.2075)
		(width 0.17145)
		(layer "F.Cu")
		(net "SCL_DR6")
	)
	(via
		(at 71.63562 -368.6556)
		(size 0.508)
		(drill 0.254)
		(layers "F.Cu" "B.Cu")
		(net "SCL_DR6")
	)
	(via
		(at 29.816298 -390.2075)
		(size 0.5588)
		(drill 0.3048)
		(layers "F.Cu" "B.Cu")
		(net "SCL_DR6")
	)
	(segment
		(start 51.643026 -393.065)
		(end 35.6362 -393.065)
		(width 0.17145)
		(layer "B.Cu")
		(net "SCL_DR6")
	)
	(segment
		(start 71.8566 -368.87658)
		(end 71.8566 -369.957096)
		(width 0.17145)
		(layer "B.Cu")
		(net "SCL_DR6")
	)
	(segment
		(start 71.049896 -370.7638)
		(end 66.604896 -370.7638)
		(width 0.17145)
		(layer "B.Cu")
		(net "SCL_DR6")
	)
	(segment
		(start 35.6362 -393.065)
		(end 33.50895 -390.93775)
		(width 0.17145)
		(layer "B.Cu")
		(net "SCL_DR6")
	)
	(segment
		(start 71.63562 -368.6556)
		(end 71.8566 -368.87658)
		(width 0.17145)
		(layer "B.Cu")
		(net "SCL_DR6")
	)
	(segment
		(start 66.604896 -370.7638)
		(end 62.3824 -374.986296)
		(width 0.17145)
		(layer "B.Cu")
		(net "SCL_DR6")
	)
	(segment
		(start 30.07995 -390.93775)
		(end 29.816298 -390.674098)
		(width 0.17145)
		(layer "B.Cu")
		(net "SCL_DR6")
	)
	(segment
		(start 62.3824 -374.986296)
		(end 62.3824 -382.325626)
		(width 0.17145)
		(layer "B.Cu")
		(net "SCL_DR6")
	)
	(segment
		(start 62.3824 -382.325626)
		(end 51.643026 -393.065)
		(width 0.17145)
		(layer "B.Cu")
		(net "SCL_DR6")
	)
	(segment
		(start 33.50895 -390.93775)
		(end 30.07995 -390.93775)
		(width 0.17145)
		(layer "B.Cu")
		(net "SCL_DR6")
	)
	(segment
		(start 71.8566 -369.957096)
		(end 71.049896 -370.7638)
		(width 0.17145)
		(layer "B.Cu")
		(net "SCL_DR6")
	)
	(segment
		(start 29.816298 -390.674098)
		(end 29.816298 -390.2075)
		(width 0.17145)
		(layer "B.Cu")
		(net "SCL_DR6")
	)
	(segment
		(start 30.353 -491.3376)
		(end 30.635448 -491.620048)
		(width 0.17145)
		(layer "F.Cu")
		(net "SCL_DR5")
	)
	(segment
		(start 31.928308 -474.394784)
		(end 30.353 -475.970092)
		(width 0.17145)
		(layer "F.Cu")
		(net "SCL_DR5")
	)
	(segment
		(start 58.674 -439.42)
		(end 51.223926 -439.42)
		(width 0.17145)
		(layer "F.Cu")
		(net "SCL_DR5")
	)
	(segment
		(start 77.85735 -366.82045)
		(end 77.1144 -366.0775)
		(width 0.17145)
		(layer "F.Cu")
		(net "SCL_DR5")
	)
	(segment
		(start 51.223926 -439.42)
		(end 38.7096 -451.934326)
		(width 0.17145)
		(layer "F.Cu")
		(net "SCL_DR5")
	)
	(segment
		(start 59.7154 -441.89015)
		(end 59.7154 -440.4614)
		(width 0.17145)
		(layer "F.Cu")
		(net "SCL_DR5")
	)
	(segment
		(start 59.64555 -441.96)
		(end 59.7154 -441.89015)
		(width 0.17145)
		(layer "F.Cu")
		(net "SCL_DR5")
	)
	(segment
		(start 77.724 -365.4679)
		(end 77.1144 -366.0775)
		(width 0.17145)
		(layer "F.Cu")
		(net "SCL_DR5")
	)
	(segment
		(start 59.015376 -441.96)
		(end 59.64555 -441.96)
		(width 0.17145)
		(layer "F.Cu")
		(net "SCL_DR5")
	)
	(segment
		(start 77.85735 -368.45367)
		(end 77.85735 -366.82045)
		(width 0.17145)
		(layer "F.Cu")
		(net "SCL_DR5")
	)
	(segment
		(start 31.928308 -461.898492)
		(end 31.928308 -474.394784)
		(width 0.17145)
		(layer "F.Cu")
		(net "SCL_DR5")
	)
	(segment
		(start 77.724 -364.890304)
		(end 77.724 -365.4679)
		(width 0.17145)
		(layer "F.Cu")
		(net "SCL_DR5")
	)
	(segment
		(start 38.7096 -455.1172)
		(end 31.928308 -461.898492)
		(width 0.17145)
		(layer "F.Cu")
		(net "SCL_DR5")
	)
	(segment
		(start 76.950062 -364.116366)
		(end 77.724 -364.890304)
		(width 0.17145)
		(layer "F.Cu")
		(net "SCL_DR5")
	)
	(segment
		(start 30.896052 -491.620048)
		(end 31.2547 -491.2614)
		(width 0.17145)
		(layer "F.Cu")
		(net "SCL_DR5")
	)
	(segment
		(start 30.353 -475.970092)
		(end 30.353 -491.3376)
		(width 0.17145)
		(layer "F.Cu")
		(net "SCL_DR5")
	)
	(segment
		(start 77.68082 -368.6302)
		(end 77.85735 -368.45367)
		(width 0.17145)
		(layer "F.Cu")
		(net "SCL_DR5")
	)
	(segment
		(start 76.950062 -363.0422)
		(end 76.950062 -364.116366)
		(width 0.17145)
		(layer "F.Cu")
		(net "SCL_DR5")
	)
	(segment
		(start 59.7154 -440.4614)
		(end 58.674 -439.42)
		(width 0.17145)
		(layer "F.Cu")
		(net "SCL_DR5")
	)
	(segment
		(start 30.635448 -491.620048)
		(end 30.896052 -491.620048)
		(width 0.17145)
		(layer "F.Cu")
		(net "SCL_DR5")
	)
	(segment
		(start 38.7096 -451.934326)
		(end 38.7096 -455.1172)
		(width 0.17145)
		(layer "F.Cu")
		(net "SCL_DR5")
	)
	(via
		(at 59.015376 -441.96)
		(size 0.5588)
		(drill 0.3048)
		(layers "F.Cu" "B.Cu")
		(net "SCL_DR5")
	)
	(via
		(at 77.68082 -368.6302)
		(size 0.508)
		(drill 0.254)
		(layers "F.Cu" "B.Cu")
		(net "SCL_DR5")
	)
	(segment
		(start 77.85735 -380.81585)
		(end 77.85735 -368.80673)
		(width 0.17145)
		(layer "B.Cu")
		(net "SCL_DR5")
	)
	(segment
		(start 59.4868 -441.96)
		(end 59.7154 -441.7314)
		(width 0.17145)
		(layer "B.Cu")
		(net "SCL_DR5")
	)
	(segment
		(start 77.85735 -368.80673)
		(end 77.68082 -368.6302)
		(width 0.17145)
		(layer "B.Cu")
		(net "SCL_DR5")
	)
	(segment
		(start 59.015376 -441.96)
		(end 59.4868 -441.96)
		(width 0.17145)
		(layer "B.Cu")
		(net "SCL_DR5")
	)
	(segment
		(start 59.7154 -441.7314)
		(end 59.7154 -398.9578)
		(width 0.17145)
		(layer "B.Cu")
		(net "SCL_DR5")
	)
	(segment
		(start 59.7154 -398.9578)
		(end 77.85735 -380.81585)
		(width 0.17145)
		(layer "B.Cu")
		(net "SCL_DR5")
	)
	(segment
		(start 195.096638 -81.892648)
		(end 216.239852 -81.892648)
		(width 0.17145)
		(layer "F.Cu")
		(net "SCL_DR4")
	)
	(segment
		(start 75.950064 -150.6982)
		(end 75.950064 -151.584914)
		(width 0.17145)
		(layer "F.Cu")
		(net "SCL_DR4")
	)
	(segment
		(start 75.92695 -154.47645)
		(end 75.184 -153.7335)
		(width 0.17145)
		(layer "F.Cu")
		(net "SCL_DR4")
	)
	(segment
		(start 75.92695 -157.50667)
		(end 75.92695 -154.47645)
		(width 0.17145)
		(layer "F.Cu")
		(net "SCL_DR4")
	)
	(segment
		(start 75.95235 -151.5872)
		(end 75.95235 -152.96515)
		(width 0.17145)
		(layer "F.Cu")
		(net "SCL_DR4")
	)
	(segment
		(start 140.97 -133.183376)
		(end 140.97 -133.688074)
		(width 0.17145)
		(layer "F.Cu")
		(net "SCL_DR4")
	)
	(segment
		(start 75.69962 -157.734)
		(end 75.92695 -157.50667)
		(width 0.17145)
		(layer "F.Cu")
		(net "SCL_DR4")
	)
	(segment
		(start 140.97 -133.688074)
		(end 141.14145 -133.859524)
		(width 0.17145)
		(layer "F.Cu")
		(net "SCL_DR4")
	)
	(segment
		(start 143.129762 -133.859524)
		(end 195.096638 -81.892648)
		(width 0.17145)
		(layer "F.Cu")
		(net "SCL_DR4")
	)
	(segment
		(start 216.239852 -81.892648)
		(end 216.5985 -81.534)
		(width 0.17145)
		(layer "F.Cu")
		(net "SCL_DR4")
	)
	(segment
		(start 75.95235 -152.96515)
		(end 75.184 -153.7335)
		(width 0.17145)
		(layer "F.Cu")
		(net "SCL_DR4")
	)
	(segment
		(start 75.950064 -151.584914)
		(end 75.95235 -151.5872)
		(width 0.17145)
		(layer "F.Cu")
		(net "SCL_DR4")
	)
	(segment
		(start 141.14145 -133.859524)
		(end 143.129762 -133.859524)
		(width 0.17145)
		(layer "F.Cu")
		(net "SCL_DR4")
	)
	(via
		(at 140.97 -133.183376)
		(size 0.5588)
		(drill 0.3048)
		(layers "F.Cu" "B.Cu")
		(net "SCL_DR4")
	)
	(via
		(at 75.69962 -157.734)
		(size 0.508)
		(drill 0.254)
		(layers "F.Cu" "B.Cu")
		(net "SCL_DR4")
	)
	(segment
		(start 143.55445 -150.698454)
		(end 143.55445 -134.899146)
		(width 0.17145)
		(layer "B.Cu")
		(net "SCL_DR4")
	)
	(segment
		(start 132.918454 -161.33445)
		(end 143.55445 -150.698454)
		(width 0.17145)
		(layer "B.Cu")
		(net "SCL_DR4")
	)
	(segment
		(start 75.802998 -157.837378)
		(end 75.802998 -157.926532)
		(width 0.17145)
		(layer "B.Cu")
		(net "SCL_DR4")
	)
	(segment
		(start 77.749146 -161.33445)
		(end 132.918454 -161.33445)
		(width 0.17145)
		(layer "B.Cu")
		(net "SCL_DR4")
	)
	(segment
		(start 141.06525 -133.9088)
		(end 140.97 -133.81355)
		(width 0.17145)
		(layer "B.Cu")
		(net "SCL_DR4")
	)
	(segment
		(start 140.97 -133.81355)
		(end 140.97 -133.183376)
		(width 0.17145)
		(layer "B.Cu")
		(net "SCL_DR4")
	)
	(segment
		(start 75.69962 -157.734)
		(end 75.802998 -157.837378)
		(width 0.17145)
		(layer "B.Cu")
		(net "SCL_DR4")
	)
	(segment
		(start 75.9206 -158.044134)
		(end 75.9206 -159.505904)
		(width 0.17145)
		(layer "B.Cu")
		(net "SCL_DR4")
	)
	(segment
		(start 75.9206 -159.505904)
		(end 77.749146 -161.33445)
		(width 0.17145)
		(layer "B.Cu")
		(net "SCL_DR4")
	)
	(segment
		(start 75.802998 -157.926532)
		(end 75.9206 -158.044134)
		(width 0.17145)
		(layer "B.Cu")
		(net "SCL_DR4")
	)
	(segment
		(start 142.564104 -133.9088)
		(end 141.06525 -133.9088)
		(width 0.17145)
		(layer "B.Cu")
		(net "SCL_DR4")
	)
	(segment
		(start 143.55445 -134.899146)
		(end 142.564104 -133.9088)
		(width 0.17145)
		(layer "B.Cu")
		(net "SCL_DR4")
	)
	(segment
		(start 216.5985 -184.531)
		(end 216.23655 -184.89295)
		(width 0.17145)
		(layer "F.Cu")
		(net "SCL_DR3")
	)
	(segment
		(start 78.74762 -156.337)
		(end 78.97495 -156.10967)
		(width 0.17145)
		(layer "F.Cu")
		(net "SCL_DR3")
	)
	(segment
		(start 78.97495 -154.47645)
		(end 78.232 -153.7335)
		(width 0.17145)
		(layer "F.Cu")
		(net "SCL_DR3")
	)
	(segment
		(start 130.891026 -157.526736)
		(end 130.891026 -158.19755)
		(width 0.17145)
		(layer "F.Cu")
		(net "SCL_DR3")
	)
	(segment
		(start 78.97495 -156.10967)
		(end 78.97495 -154.47645)
		(width 0.17145)
		(layer "F.Cu")
		(net "SCL_DR3")
	)
	(segment
		(start 78.70825 -152.39365)
		(end 78.9432 -152.6286)
		(width 0.17145)
		(layer "F.Cu")
		(net "SCL_DR3")
	)
	(segment
		(start 130.891026 -158.19755)
		(end 130.719576 -158.369)
		(width 0.17145)
		(layer "F.Cu")
		(net "SCL_DR3")
	)
	(segment
		(start 78.9432 -152.6286)
		(end 78.9432 -153.0223)
		(width 0.17145)
		(layer "F.Cu")
		(net "SCL_DR3")
	)
	(segment
		(start 77.698346 -152.39365)
		(end 78.70825 -152.39365)
		(width 0.17145)
		(layer "F.Cu")
		(net "SCL_DR3")
	)
	(segment
		(start 76.950062 -151.645366)
		(end 77.698346 -152.39365)
		(width 0.17145)
		(layer "F.Cu")
		(net "SCL_DR3")
	)
	(segment
		(start 130.719576 -158.369)
		(end 130.214624 -158.369)
		(width 0.17145)
		(layer "F.Cu")
		(net "SCL_DR3")
	)
	(segment
		(start 208.48955 -184.89295)
		(end 180.448712 -156.852112)
		(width 0.17145)
		(layer "F.Cu")
		(net "SCL_DR3")
	)
	(segment
		(start 76.950062 -150.6982)
		(end 76.950062 -151.645366)
		(width 0.17145)
		(layer "F.Cu")
		(net "SCL_DR3")
	)
	(segment
		(start 131.56565 -156.852112)
		(end 130.891026 -157.526736)
		(width 0.17145)
		(layer "F.Cu")
		(net "SCL_DR3")
	)
	(segment
		(start 78.9432 -153.0223)
		(end 78.232 -153.7335)
		(width 0.17145)
		(layer "F.Cu")
		(net "SCL_DR3")
	)
	(segment
		(start 180.448712 -156.852112)
		(end 131.56565 -156.852112)
		(width 0.17145)
		(layer "F.Cu")
		(net "SCL_DR3")
	)
	(segment
		(start 216.23655 -184.89295)
		(end 208.48955 -184.89295)
		(width 0.17145)
		(layer "F.Cu")
		(net "SCL_DR3")
	)
	(via
		(at 78.74762 -156.337)
		(size 0.508)
		(drill 0.254)
		(layers "F.Cu" "B.Cu")
		(net "SCL_DR3")
	)
	(via
		(at 130.214624 -158.369)
		(size 0.5588)
		(drill 0.3048)
		(layers "F.Cu" "B.Cu")
		(net "SCL_DR3")
	)
	(segment
		(start 131.016248 -157.605222)
		(end 130.078226 -156.6672)
		(width 0.17145)
		(layer "B.Cu")
		(net "SCL_DR3")
	)
	(segment
		(start 130.078226 -156.6672)
		(end 126.4158 -156.6672)
		(width 0.17145)
		(layer "B.Cu")
		(net "SCL_DR3")
	)
	(segment
		(start 130.214624 -158.369)
		(end 130.844798 -158.369)
		(width 0.17145)
		(layer "B.Cu")
		(net "SCL_DR3")
	)
	(segment
		(start 124.031248 -159.051752)
		(end 79.784448 -159.051752)
		(width 0.17145)
		(layer "B.Cu")
		(net "SCL_DR3")
	)
	(segment
		(start 126.4158 -156.6672)
		(end 124.031248 -159.051752)
		(width 0.17145)
		(layer "B.Cu")
		(net "SCL_DR3")
	)
	(segment
		(start 130.844798 -158.369)
		(end 131.016248 -158.19755)
		(width 0.17145)
		(layer "B.Cu")
		(net "SCL_DR3")
	)
	(segment
		(start 79.784448 -159.051752)
		(end 79.0194 -158.286704)
		(width 0.17145)
		(layer "B.Cu")
		(net "SCL_DR3")
	)
	(segment
		(start 131.016248 -158.19755)
		(end 131.016248 -157.605222)
		(width 0.17145)
		(layer "B.Cu")
		(net "SCL_DR3")
	)
	(segment
		(start 79.0194 -158.286704)
		(end 79.0194 -156.60878)
		(width 0.17145)
		(layer "B.Cu")
		(net "SCL_DR3")
	)
	(segment
		(start 79.0194 -156.60878)
		(end 78.74762 -156.337)
		(width 0.17145)
		(layer "B.Cu")
		(net "SCL_DR3")
	)
	(segment
		(start 105.452926 -287.888426)
		(end 216.238074 -287.888426)
		(width 0.17145)
		(layer "F.Cu")
		(net "SCL_DR2")
	)
	(segment
		(start 216.238074 -287.888426)
		(end 216.5985 -287.528)
		(width 0.17145)
		(layer "F.Cu")
		(net "SCL_DR2")
	)
	(segment
		(start 79.80045 -359.56875)
		(end 79.80045 -358.65435)
		(width 0.17145)
		(layer "F.Cu")
		(net "SCL_DR2")
	)
	(segment
		(start 81.9785 -358.267)
		(end 83.7438 -358.267)
		(width 0.17145)
		(layer "F.Cu")
		(net "SCL_DR2")
	)
	(segment
		(start 80.1116 -358.3432)
		(end 80.5307 -358.3432)
		(width 0.17145)
		(layer "F.Cu")
		(net "SCL_DR2")
	)
	(segment
		(start 80.5307 -358.3432)
		(end 81.2165 -359.029)
		(width 0.17145)
		(layer "F.Cu")
		(net "SCL_DR2")
	)
	(segment
		(start 83.7438 -358.267)
		(end 83.8962 -358.4194)
		(width 0.17145)
		(layer "F.Cu")
		(net "SCL_DR2")
	)
	(segment
		(start 79.058262 -360.310938)
		(end 79.80045 -359.56875)
		(width 0.17145)
		(layer "F.Cu")
		(net "SCL_DR2")
	)
	(segment
		(start 78.1812 -360.310938)
		(end 79.058262 -360.310938)
		(width 0.17145)
		(layer "F.Cu")
		(net "SCL_DR2")
	)
	(segment
		(start 79.80045 -358.65435)
		(end 80.1116 -358.3432)
		(width 0.17145)
		(layer "F.Cu")
		(net "SCL_DR2")
	)
	(segment
		(start 104.775 -287.2105)
		(end 105.452926 -287.888426)
		(width 0.17145)
		(layer "F.Cu")
		(net "SCL_DR2")
	)
	(segment
		(start 81.2165 -359.029)
		(end 81.9785 -358.267)
		(width 0.17145)
		(layer "F.Cu")
		(net "SCL_DR2")
	)
	(via
		(at 104.775 -287.2105)
		(size 0.5588)
		(drill 0.3048)
		(layers "F.Cu" "B.Cu")
		(net "SCL_DR2")
	)
	(via
		(at 83.8962 -358.4194)
		(size 0.508)
		(drill 0.254)
		(layers "F.Cu" "B.Cu")
		(net "SCL_DR2")
	)
	(segment
		(start 83.896708 -358.4067)
		(end 84.068158 -358.23525)
		(width 0.17145)
		(layer "B.Cu")
		(net "SCL_DR2")
	)
	(segment
		(start 113.58245 -332.206854)
		(end 113.58245 -294.030146)
		(width 0.17145)
		(layer "B.Cu")
		(net "SCL_DR2")
	)
	(segment
		(start 104.775 -287.7312)
		(end 104.775 -287.2105)
		(width 0.17145)
		(layer "B.Cu")
		(net "SCL_DR2")
	)
	(segment
		(start 113.58245 -294.030146)
		(end 107.391454 -287.83915)
		(width 0.17145)
		(layer "B.Cu")
		(net "SCL_DR2")
	)
	(segment
		(start 107.391454 -287.83915)
		(end 104.88295 -287.83915)
		(width 0.17145)
		(layer "B.Cu")
		(net "SCL_DR2")
	)
	(segment
		(start 84.068158 -358.23525)
		(end 87.554054 -358.23525)
		(width 0.17145)
		(layer "B.Cu")
		(net "SCL_DR2")
	)
	(segment
		(start 104.88295 -287.83915)
		(end 104.775 -287.7312)
		(width 0.17145)
		(layer "B.Cu")
		(net "SCL_DR2")
	)
	(segment
		(start 83.896708 -358.418892)
		(end 83.896708 -358.4067)
		(width 0.17145)
		(layer "B.Cu")
		(net "SCL_DR2")
	)
	(segment
		(start 83.8962 -358.4194)
		(end 83.896708 -358.418892)
		(width 0.17145)
		(layer "B.Cu")
		(net "SCL_DR2")
	)
	(segment
		(start 87.554054 -358.23525)
		(end 113.58245 -332.206854)
		(width 0.17145)
		(layer "B.Cu")
		(net "SCL_DR2")
	)
	(segment
		(start 76.002388 -145.8976)
		(end 76.002388 -145.552414)
		(width 0.17145)
		(layer "F.Cu")
		(net "SCL_DR14")
	)
	(segment
		(start 29.0322 -17.5895)
		(end 29.0322 -18.01876)
		(width 0.17145)
		(layer "F.Cu")
		(net "SCL_DR14")
	)
	(segment
		(start 105.667302 -69.826632)
		(end 105.667302 -121.821194)
		(width 0.17145)
		(layer "F.Cu")
		(net "SCL_DR14")
	)
	(segment
		(start 34.594546 -24.55545)
		(end 60.39612 -24.55545)
		(width 0.17145)
		(layer "F.Cu")
		(net "SCL_DR14")
	)
	(segment
		(start 75.0824 -141.31798)
		(end 75.0824 -142.9766)
		(width 0.17145)
		(layer "F.Cu")
		(net "SCL_DR14")
	)
	(segment
		(start 75.950064 -146.7358)
		(end 75.950064 -145.949924)
		(width 0.17145)
		(layer "F.Cu")
		(net "SCL_DR14")
	)
	(segment
		(start 29.391102 -18.377662)
		(end 29.391102 -19.352006)
		(width 0.17145)
		(layer "F.Cu")
		(net "SCL_DR14")
	)
	(segment
		(start 105.667302 -121.821194)
		(end 89.255346 -138.23315)
		(width 0.17145)
		(layer "F.Cu")
		(net "SCL_DR14")
	)
	(segment
		(start 72.136 -138.13155)
		(end 72.136 -137.501376)
		(width 0.17145)
		(layer "F.Cu")
		(net "SCL_DR14")
	)
	(segment
		(start 75.0824 -142.9766)
		(end 75.8063 -143.7005)
		(width 0.17145)
		(layer "F.Cu")
		(net "SCL_DR14")
	)
	(segment
		(start 72.2376 -138.23315)
		(end 72.136 -138.13155)
		(width 0.17145)
		(layer "F.Cu")
		(net "SCL_DR14")
	)
	(segment
		(start 75.950064 -145.949924)
		(end 76.002388 -145.8976)
		(width 0.17145)
		(layer "F.Cu")
		(net "SCL_DR14")
	)
	(segment
		(start 89.255346 -138.23315)
		(end 72.2376 -138.23315)
		(width 0.17145)
		(layer "F.Cu")
		(net "SCL_DR14")
	)
	(segment
		(start 29.0322 -18.01876)
		(end 29.391102 -18.377662)
		(width 0.17145)
		(layer "F.Cu")
		(net "SCL_DR14")
	)
	(segment
		(start 29.391102 -19.352006)
		(end 34.594546 -24.55545)
		(width 0.17145)
		(layer "F.Cu")
		(net "SCL_DR14")
	)
	(segment
		(start 60.39612 -24.55545)
		(end 105.667302 -69.826632)
		(width 0.17145)
		(layer "F.Cu")
		(net "SCL_DR14")
	)
	(segment
		(start 75.07605 -144.626076)
		(end 75.07605 -144.43075)
		(width 0.17145)
		(layer "F.Cu")
		(net "SCL_DR14")
	)
	(segment
		(start 75.07605 -144.43075)
		(end 75.8063 -143.7005)
		(width 0.17145)
		(layer "F.Cu")
		(net "SCL_DR14")
	)
	(segment
		(start 75.30338 -141.097)
		(end 75.0824 -141.31798)
		(width 0.17145)
		(layer "F.Cu")
		(net "SCL_DR14")
	)
	(segment
		(start 76.002388 -145.552414)
		(end 75.07605 -144.626076)
		(width 0.17145)
		(layer "F.Cu")
		(net "SCL_DR14")
	)
	(via
		(at 75.30338 -141.097)
		(size 0.508)
		(drill 0.254)
		(layers "F.Cu" "B.Cu")
		(net "SCL_DR14")
	)
	(via
		(at 72.136 -137.501376)
		(size 0.5588)
		(drill 0.3048)
		(layers "F.Cu" "B.Cu")
		(net "SCL_DR14")
	)
	(segment
		(start 72.272652 -138.15695)
		(end 72.136 -138.020298)
		(width 0.17145)
		(layer "B.Cu")
		(net "SCL_DR14")
	)
	(segment
		(start 75.30338 -141.097)
		(end 75.221846 -141.015466)
		(width 0.17145)
		(layer "B.Cu")
		(net "SCL_DR14")
	)
	(segment
		(start 75.221846 -141.015466)
		(end 75.221846 -139.337542)
		(width 0.17145)
		(layer "B.Cu")
		(net "SCL_DR14")
	)
	(segment
		(start 74.041254 -138.15695)
		(end 72.272652 -138.15695)
		(width 0.17145)
		(layer "B.Cu")
		(net "SCL_DR14")
	)
	(segment
		(start 72.136 -138.020298)
		(end 72.136 -137.501376)
		(width 0.17145)
		(layer "B.Cu")
		(net "SCL_DR14")
	)
	(segment
		(start 75.221846 -139.337542)
		(end 74.041254 -138.15695)
		(width 0.17145)
		(layer "B.Cu")
		(net "SCL_DR14")
	)
	(segment
		(start 68.58 -147.07362)
		(end 68.80098 -147.2946)
		(width 0.17145)
		(layer "F.Cu")
		(net "SCL_DR13")
	)
	(segment
		(start 74.2188 -147.966938)
		(end 73.716642 -147.966938)
		(width 0.17145)
		(layer "F.Cu")
		(net "SCL_DR13")
	)
	(segment
		(start 73.044304 -147.2946)
		(end 71.9201 -147.2946)
		(width 0.17145)
		(layer "F.Cu")
		(net "SCL_DR13")
	)
	(segment
		(start 57.15 -113.411)
		(end 57.15 -111.55045)
		(width 0.17145)
		(layer "F.Cu")
		(net "SCL_DR13")
	)
	(segment
		(start 68.80098 -147.2946)
		(end 70.4469 -147.2946)
		(width 0.17145)
		(layer "F.Cu")
		(net "SCL_DR13")
	)
	(segment
		(start 57.32145 -111.379)
		(end 57.951624 -111.379)
		(width 0.17145)
		(layer "F.Cu")
		(net "SCL_DR13")
	)
	(segment
		(start 30.62605 -115.10645)
		(end 55.45455 -115.10645)
		(width 0.17145)
		(layer "F.Cu")
		(net "SCL_DR13")
	)
	(segment
		(start 73.716642 -147.966938)
		(end 73.044304 -147.2946)
		(width 0.17145)
		(layer "F.Cu")
		(net "SCL_DR13")
	)
	(segment
		(start 70.4469 -147.2946)
		(end 71.1835 -146.558)
		(width 0.17145)
		(layer "F.Cu")
		(net "SCL_DR13")
	)
	(segment
		(start 30.2895 -115.443)
		(end 30.62605 -115.10645)
		(width 0.17145)
		(layer "F.Cu")
		(net "SCL_DR13")
	)
	(segment
		(start 55.45455 -115.10645)
		(end 57.15 -113.411)
		(width 0.17145)
		(layer "F.Cu")
		(net "SCL_DR13")
	)
	(segment
		(start 57.15 -111.55045)
		(end 57.32145 -111.379)
		(width 0.17145)
		(layer "F.Cu")
		(net "SCL_DR13")
	)
	(segment
		(start 71.9201 -147.2946)
		(end 71.1835 -146.558)
		(width 0.17145)
		(layer "F.Cu")
		(net "SCL_DR13")
	)
	(via
		(at 57.951624 -111.379)
		(size 0.5588)
		(drill 0.3048)
		(layers "F.Cu" "B.Cu")
		(net "SCL_DR13")
	)
	(via
		(at 68.58 -147.07362)
		(size 0.508)
		(drill 0.254)
		(layers "F.Cu" "B.Cu")
		(net "SCL_DR13")
	)
	(segment
		(start 68.35267 -147.30095)
		(end 68.58 -147.07362)
		(width 0.17145)
		(layer "B.Cu")
		(net "SCL_DR13")
	)
	(segment
		(start 57.951624 -111.379)
		(end 57.32145 -111.379)
		(width 0.17145)
		(layer "B.Cu")
		(net "SCL_DR13")
	)
	(segment
		(start 57.32145 -111.379)
		(end 57.2008 -111.49965)
		(width 0.17145)
		(layer "B.Cu")
		(net "SCL_DR13")
	)
	(segment
		(start 64.08928 -147.30095)
		(end 68.35267 -147.30095)
		(width 0.17145)
		(layer "B.Cu")
		(net "SCL_DR13")
	)
	(segment
		(start 57.2008 -140.41247)
		(end 64.08928 -147.30095)
		(width 0.17145)
		(layer "B.Cu")
		(net "SCL_DR13")
	)
	(segment
		(start 57.2008 -111.49965)
		(end 57.2008 -140.41247)
		(width 0.17145)
		(layer "B.Cu")
		(net "SCL_DR13")
	)
	(segment
		(start 72.136 -153.7335)
		(end 72.92975 -152.93975)
		(width 0.17145)
		(layer "F.Cu")
		(net "SCL_DR12")
	)
	(segment
		(start 72.92975 -152.93975)
		(end 72.92975 -152.348946)
		(width 0.17145)
		(layer "F.Cu")
		(net "SCL_DR12")
	)
	(segment
		(start 72.67702 -156.3878)
		(end 72.87895 -156.18587)
		(width 0.17145)
		(layer "F.Cu")
		(net "SCL_DR12")
	)
	(segment
		(start 32.060134 -218.7575)
		(end 32.060134 -218.260168)
		(width 0.17145)
		(layer "F.Cu")
		(net "SCL_DR12")
	)
	(segment
		(start 74.950066 -151.414734)
		(end 74.950066 -150.7744)
		(width 0.17145)
		(layer "F.Cu")
		(net "SCL_DR12")
	)
	(segment
		(start 32.060134 -218.260168)
		(end 31.928816 -218.12885)
		(width 0.17145)
		(layer "F.Cu")
		(net "SCL_DR12")
	)
	(segment
		(start 72.87895 -154.47645)
		(end 72.136 -153.7335)
		(width 0.17145)
		(layer "F.Cu")
		(net "SCL_DR12")
	)
	(segment
		(start 73.589896 -151.6888)
		(end 74.676 -151.6888)
		(width 0.17145)
		(layer "F.Cu")
		(net "SCL_DR12")
	)
	(segment
		(start 72.87895 -156.18587)
		(end 72.87895 -154.47645)
		(width 0.17145)
		(layer "F.Cu")
		(net "SCL_DR12")
	)
	(segment
		(start 72.92975 -152.348946)
		(end 73.589896 -151.6888)
		(width 0.17145)
		(layer "F.Cu")
		(net "SCL_DR12")
	)
	(segment
		(start 74.676 -151.6888)
		(end 74.950066 -151.414734)
		(width 0.17145)
		(layer "F.Cu")
		(net "SCL_DR12")
	)
	(segment
		(start 30.60065 -218.12885)
		(end 30.2895 -218.44)
		(width 0.17145)
		(layer "F.Cu")
		(net "SCL_DR12")
	)
	(segment
		(start 31.928816 -218.12885)
		(end 30.60065 -218.12885)
		(width 0.17145)
		(layer "F.Cu")
		(net "SCL_DR12")
	)
	(via
		(at 32.060134 -218.7575)
		(size 0.5588)
		(drill 0.3048)
		(layers "F.Cu" "B.Cu")
		(net "SCL_DR12")
	)
	(via
		(at 72.67702 -156.3878)
		(size 0.508)
		(drill 0.254)
		(layers "F.Cu" "B.Cu")
		(net "SCL_DR12")
	)
	(segment
		(start 62.4078 -169.1132)
		(end 72.898 -158.623)
		(width 0.17145)
		(layer "B.Cu")
		(net "SCL_DR12")
	)
	(segment
		(start 72.898 -158.623)
		(end 72.898 -156.60878)
		(width 0.17145)
		(layer "B.Cu")
		(net "SCL_DR12")
	)
	(segment
		(start 32.060134 -218.7575)
		(end 32.060134 -218.378024)
		(width 0.17145)
		(layer "B.Cu")
		(net "SCL_DR12")
	)
	(segment
		(start 31.419546 -214.71255)
		(end 41.554146 -214.71255)
		(width 0.17145)
		(layer "B.Cu")
		(net "SCL_DR12")
	)
	(segment
		(start 30.610302 -215.521794)
		(end 31.419546 -214.71255)
		(width 0.17145)
		(layer "B.Cu")
		(net "SCL_DR12")
	)
	(segment
		(start 31.162244 -218.206574)
		(end 30.610302 -217.654632)
		(width 0.17145)
		(layer "B.Cu")
		(net "SCL_DR12")
	)
	(segment
		(start 32.060134 -218.378024)
		(end 31.888684 -218.206574)
		(width 0.17145)
		(layer "B.Cu")
		(net "SCL_DR12")
	)
	(segment
		(start 41.554146 -214.71255)
		(end 62.4078 -193.858896)
		(width 0.17145)
		(layer "B.Cu")
		(net "SCL_DR12")
	)
	(segment
		(start 72.898 -156.60878)
		(end 72.67702 -156.3878)
		(width 0.17145)
		(layer "B.Cu")
		(net "SCL_DR12")
	)
	(segment
		(start 62.4078 -193.858896)
		(end 62.4078 -169.1132)
		(width 0.17145)
		(layer "B.Cu")
		(net "SCL_DR12")
	)
	(segment
		(start 31.888684 -218.206574)
		(end 31.162244 -218.206574)
		(width 0.17145)
		(layer "B.Cu")
		(net "SCL_DR12")
	)
	(segment
		(start 30.610302 -217.654632)
		(end 30.610302 -215.521794)
		(width 0.17145)
		(layer "B.Cu")
		(net "SCL_DR12")
	)
	(segment
		(start 68.783962 -362.3056)
		(end 70.4469 -362.3056)
		(width 0.17145)
		(layer "F.Cu")
		(net "SCL_DR11")
	)
	(segment
		(start 72.286876 -362.307124)
		(end 71.921624 -362.307124)
		(width 0.17145)
		(layer "F.Cu")
		(net "SCL_DR11")
	)
	(segment
		(start 30.6197 -321.1068)
		(end 61.021976 -321.1068)
		(width 0.17145)
		(layer "F.Cu")
		(net "SCL_DR11")
	)
	(segment
		(start 71.921624 -362.307124)
		(end 71.1835 -361.569)
		(width 0.17145)
		(layer "F.Cu")
		(net "SCL_DR11")
	)
	(segment
		(start 73.283064 -361.310936)
		(end 72.286876 -362.307124)
		(width 0.17145)
		(layer "F.Cu")
		(net "SCL_DR11")
	)
	(segment
		(start 68.6054 -362.127038)
		(end 68.783962 -362.3056)
		(width 0.17145)
		(layer "F.Cu")
		(net "SCL_DR11")
	)
	(segment
		(start 61.021976 -321.1068)
		(end 61.6458 -321.730624)
		(width 0.17145)
		(layer "F.Cu")
		(net "SCL_DR11")
	)
	(segment
		(start 74.2188 -361.310936)
		(end 73.283064 -361.310936)
		(width 0.17145)
		(layer "F.Cu")
		(net "SCL_DR11")
	)
	(segment
		(start 70.4469 -362.3056)
		(end 71.1835 -361.569)
		(width 0.17145)
		(layer "F.Cu")
		(net "SCL_DR11")
	)
	(segment
		(start 30.2895 -321.437)
		(end 30.6197 -321.1068)
		(width 0.17145)
		(layer "F.Cu")
		(net "SCL_DR11")
	)
	(via
		(at 61.6458 -321.730624)
		(size 0.5588)
		(drill 0.3048)
		(layers "F.Cu" "B.Cu")
		(net "SCL_DR11")
	)
	(via
		(at 68.6054 -362.127038)
		(size 0.508)
		(drill 0.254)
		(layers "F.Cu" "B.Cu")
		(net "SCL_DR11")
	)
	(segment
		(start 60.2488 -320.929)
		(end 61.47435 -320.929)
		(width 0.17145)
		(layer "B.Cu")
		(net "SCL_DR11")
	)
	(segment
		(start 61.47435 -320.929)
		(end 61.6458 -321.10045)
		(width 0.17145)
		(layer "B.Cu")
		(net "SCL_DR11")
	)
	(segment
		(start 61.6458 -321.10045)
		(end 61.6458 -321.730624)
		(width 0.17145)
		(layer "B.Cu")
		(net "SCL_DR11")
	)
	(segment
		(start 68.6054 -362.127038)
		(end 68.477638 -362.2548)
		(width 0.17145)
		(layer "B.Cu")
		(net "SCL_DR11")
	)
	(segment
		(start 66.4718 -362.2548)
		(end 59.4106 -355.1936)
		(width 0.17145)
		(layer "B.Cu")
		(net "SCL_DR11")
	)
	(segment
		(start 59.4106 -321.7672)
		(end 60.2488 -320.929)
		(width 0.17145)
		(layer "B.Cu")
		(net "SCL_DR11")
	)
	(segment
		(start 59.4106 -355.1936)
		(end 59.4106 -321.7672)
		(width 0.17145)
		(layer "B.Cu")
		(net "SCL_DR11")
	)
	(segment
		(start 68.477638 -362.2548)
		(end 66.4718 -362.2548)
		(width 0.17145)
		(layer "B.Cu")
		(net "SCL_DR11")
	)
	(segment
		(start 31.753302 -424.283632)
		(end 31.51632 -424.04665)
		(width 0.17145)
		(layer "F.Cu")
		(net "SCL_DR10")
	)
	(segment
		(start 31.581852 -424.7896)
		(end 31.753302 -424.61815)
		(width 0.17145)
		(layer "F.Cu")
		(net "SCL_DR10")
	)
	(segment
		(start 74.80935 -368.50447)
		(end 74.80935 -366.82045)
		(width 0.17145)
		(layer "F.Cu")
		(net "SCL_DR10")
	)
	(segment
		(start 74.0664 -366.0775)
		(end 74.807826 -365.336074)
		(width 0.17145)
		(layer "F.Cu")
		(net "SCL_DR10")
	)
	(segment
		(start 31.202376 -424.7896)
		(end 31.581852 -424.7896)
		(width 0.17145)
		(layer "F.Cu")
		(net "SCL_DR10")
	)
	(segment
		(start 31.51632 -424.04665)
		(end 30.67685 -424.04665)
		(width 0.17145)
		(layer "F.Cu")
		(net "SCL_DR10")
	)
	(segment
		(start 74.807826 -365.336074)
		(end 74.807826 -364.38967)
		(width 0.17145)
		(layer "F.Cu")
		(net "SCL_DR10")
	)
	(segment
		(start 74.807826 -364.38967)
		(end 75.449938 -363.747558)
		(width 0.17145)
		(layer "F.Cu")
		(net "SCL_DR10")
	)
	(segment
		(start 74.63282 -368.681)
		(end 74.80935 -368.50447)
		(width 0.17145)
		(layer "F.Cu")
		(net "SCL_DR10")
	)
	(segment
		(start 75.449938 -363.747558)
		(end 75.449938 -363.0422)
		(width 0.17145)
		(layer "F.Cu")
		(net "SCL_DR10")
	)
	(segment
		(start 74.80935 -366.82045)
		(end 74.0664 -366.0775)
		(width 0.17145)
		(layer "F.Cu")
		(net "SCL_DR10")
	)
	(segment
		(start 31.753302 -424.61815)
		(end 31.753302 -424.283632)
		(width 0.17145)
		(layer "F.Cu")
		(net "SCL_DR10")
	)
	(segment
		(start 30.67685 -424.04665)
		(end 30.2895 -424.434)
		(width 0.17145)
		(layer "F.Cu")
		(net "SCL_DR10")
	)
	(via
		(at 74.63282 -368.681)
		(size 0.508)
		(drill 0.254)
		(layers "F.Cu" "B.Cu")
		(net "SCL_DR10")
	)
	(via
		(at 31.202376 -424.7896)
		(size 0.5588)
		(drill 0.3048)
		(layers "F.Cu" "B.Cu")
		(net "SCL_DR10")
	)
	(segment
		(start 76.279248 -378.761752)
		(end 76.279248 -372.489222)
		(width 0.17145)
		(layer "B.Cu")
		(net "SCL_DR10")
	)
	(segment
		(start 74.83475 -368.88293)
		(end 74.63282 -368.681)
		(width 0.17145)
		(layer "B.Cu")
		(net "SCL_DR10")
	)
	(segment
		(start 31.80715 -424.65625)
		(end 31.80715 -423.23385)
		(width 0.17145)
		(layer "B.Cu")
		(net "SCL_DR10")
	)
	(segment
		(start 76.279248 -372.489222)
		(end 74.83475 -371.044724)
		(width 0.17145)
		(layer "B.Cu")
		(net "SCL_DR10")
	)
	(segment
		(start 31.6738 -424.7896)
		(end 31.80715 -424.65625)
		(width 0.17145)
		(layer "B.Cu")
		(net "SCL_DR10")
	)
	(segment
		(start 74.83475 -371.044724)
		(end 74.83475 -368.88293)
		(width 0.17145)
		(layer "B.Cu")
		(net "SCL_DR10")
	)
	(segment
		(start 31.80715 -423.23385)
		(end 76.279248 -378.761752)
		(width 0.17145)
		(layer "B.Cu")
		(net "SCL_DR10")
	)
	(segment
		(start 31.202376 -424.7896)
		(end 31.6738 -424.7896)
		(width 0.17145)
		(layer "B.Cu")
		(net "SCL_DR10")
	)
	(segment
		(start 83.64347 -361.38485)
		(end 81.95945 -361.38485)
		(width 0.17145)
		(layer "F.Cu")
		(net "SCL_DR1")
	)
	(segment
		(start 79.0448 -361.363514)
		(end 80.452214 -361.363514)
		(width 0.17145)
		(layer "F.Cu")
		(net "SCL_DR1")
	)
	(segment
		(start 78.1812 -361.310936)
		(end 78.992222 -361.310936)
		(width 0.17145)
		(layer "F.Cu")
		(net "SCL_DR1")
	)
	(segment
		(start 90.1446 -358.670098)
		(end 90.1446 -364.9726)
		(width 0.17145)
		(layer "F.Cu")
		(net "SCL_DR1")
	)
	(segment
		(start 90.971624 -358.394)
		(end 90.420698 -358.394)
		(width 0.17145)
		(layer "F.Cu")
		(net "SCL_DR1")
	)
	(segment
		(start 78.992222 -361.310936)
		(end 79.0448 -361.363514)
		(width 0.17145)
		(layer "F.Cu")
		(net "SCL_DR1")
	)
	(segment
		(start 81.95945 -361.38485)
		(end 81.2165 -362.1278)
		(width 0.17145)
		(layer "F.Cu")
		(net "SCL_DR1")
	)
	(segment
		(start 80.452214 -361.363514)
		(end 81.2165 -362.1278)
		(width 0.17145)
		(layer "F.Cu")
		(net "SCL_DR1")
	)
	(segment
		(start 90.420698 -358.394)
		(end 90.1446 -358.670098)
		(width 0.17145)
		(layer "F.Cu")
		(net "SCL_DR1")
	)
	(segment
		(start 116.05895 -390.88695)
		(end 216.23655 -390.88695)
		(width 0.17145)
		(layer "F.Cu")
		(net "SCL_DR1")
	)
	(segment
		(start 90.1446 -364.9726)
		(end 116.05895 -390.88695)
		(width 0.17145)
		(layer "F.Cu")
		(net "SCL_DR1")
	)
	(segment
		(start 83.82 -361.56138)
		(end 83.64347 -361.38485)
		(width 0.17145)
		(layer "F.Cu")
		(net "SCL_DR1")
	)
	(segment
		(start 216.23655 -390.88695)
		(end 216.5985 -390.525)
		(width 0.17145)
		(layer "F.Cu")
		(net "SCL_DR1")
	)
	(via
		(at 83.82 -361.56138)
		(size 0.508)
		(drill 0.254)
		(layers "F.Cu" "B.Cu")
		(net "SCL_DR1")
	)
	(via
		(at 90.971624 -358.394)
		(size 0.5588)
		(drill 0.3048)
		(layers "F.Cu" "B.Cu")
		(net "SCL_DR1")
	)
	(segment
		(start 84.02193 -361.35945)
		(end 83.82 -361.56138)
		(width 0.17145)
		(layer "B.Cu")
		(net "SCL_DR1")
	)
	(segment
		(start 88.44788 -361.35945)
		(end 84.02193 -361.35945)
		(width 0.17145)
		(layer "B.Cu")
		(net "SCL_DR1")
	)
	(segment
		(start 90.2716 -359.53573)
		(end 88.44788 -361.35945)
		(width 0.17145)
		(layer "B.Cu")
		(net "SCL_DR1")
	)
	(segment
		(start 90.971624 -358.394)
		(end 90.5002 -358.394)
		(width 0.17145)
		(layer "B.Cu")
		(net "SCL_DR1")
	)
	(segment
		(start 90.2716 -358.6226)
		(end 90.2716 -359.53573)
		(width 0.17145)
		(layer "B.Cu")
		(net "SCL_DR1")
	)
	(segment
		(start 90.5002 -358.394)
		(end 90.2716 -358.6226)
		(width 0.17145)
		(layer "B.Cu")
		(net "SCL_DR1")
	)
	(segment
		(start 79.17815 -362.763054)
		(end 79.17815 -363.65815)
		(width 0.17145)
		(layer "F.Cu")
		(net "SCL_DR0")
	)
	(segment
		(start 210.167474 -474.028516)
		(end 210.167474 -487.66857)
		(width 0.17145)
		(layer "F.Cu")
		(net "SCL_DR0")
	)
	(segment
		(start 83.71967 -364.43285)
		(end 81.95945 -364.43285)
		(width 0.17145)
		(layer "F.Cu")
		(net "SCL_DR0")
	)
	(segment
		(start 116.615972 -445.024002)
		(end 181.16296 -445.024002)
		(width 0.17145)
		(layer "F.Cu")
		(net "SCL_DR0")
	)
	(segment
		(start 81.95945 -364.43285)
		(end 81.2165 -365.1758)
		(width 0.17145)
		(layer "F.Cu")
		(net "SCL_DR0")
	)
	(segment
		(start 181.16296 -445.024002)
		(end 210.167474 -474.028516)
		(width 0.17145)
		(layer "F.Cu")
		(net "SCL_DR0")
	)
	(segment
		(start 79.954374 -364.434374)
		(end 80.475074 -364.434374)
		(width 0.17145)
		(layer "F.Cu")
		(net "SCL_DR0")
	)
	(segment
		(start 214.554054 -492.05515)
		(end 215.98255 -492.05515)
		(width 0.17145)
		(layer "F.Cu")
		(net "SCL_DR0")
	)
	(segment
		(start 210.167474 -487.66857)
		(end 214.554054 -492.05515)
		(width 0.17145)
		(layer "F.Cu")
		(net "SCL_DR0")
	)
	(segment
		(start 115.74145 -442.722)
		(end 115.57 -442.89345)
		(width 0.17145)
		(layer "F.Cu")
		(net "SCL_DR0")
	)
	(segment
		(start 79.17815 -363.65815)
		(end 79.954374 -364.434374)
		(width 0.17145)
		(layer "F.Cu")
		(net "SCL_DR0")
	)
	(segment
		(start 115.57 -442.89345)
		(end 115.57 -443.97803)
		(width 0.17145)
		(layer "F.Cu")
		(net "SCL_DR0")
	)
	(segment
		(start 83.82 -364.53318)
		(end 83.71967 -364.43285)
		(width 0.17145)
		(layer "F.Cu")
		(net "SCL_DR0")
	)
	(segment
		(start 115.57 -443.97803)
		(end 116.615972 -445.024002)
		(width 0.17145)
		(layer "F.Cu")
		(net "SCL_DR0")
	)
	(segment
		(start 78.72603 -362.310934)
		(end 79.17815 -362.763054)
		(width 0.17145)
		(layer "F.Cu")
		(net "SCL_DR0")
	)
	(segment
		(start 215.98255 -492.05515)
		(end 216.3445 -491.6932)
		(width 0.17145)
		(layer "F.Cu")
		(net "SCL_DR0")
	)
	(segment
		(start 78.2574 -362.310934)
		(end 78.72603 -362.310934)
		(width 0.17145)
		(layer "F.Cu")
		(net "SCL_DR0")
	)
	(segment
		(start 80.475074 -364.434374)
		(end 81.2165 -365.1758)
		(width 0.17145)
		(layer "F.Cu")
		(net "SCL_DR0")
	)
	(segment
		(start 116.371624 -442.722)
		(end 115.74145 -442.722)
		(width 0.17145)
		(layer "F.Cu")
		(net "SCL_DR0")
	)
	(via
		(at 116.371624 -442.722)
		(size 0.5588)
		(drill 0.3048)
		(layers "F.Cu" "B.Cu")
		(net "SCL_DR0")
	)
	(via
		(at 83.82 -364.53318)
		(size 0.508)
		(drill 0.254)
		(layers "F.Cu" "B.Cu")
		(net "SCL_DR0")
	)
	(segment
		(start 115.820698 -442.89345)
		(end 115.992148 -442.722)
		(width 0.17145)
		(layer "B.Cu")
		(net "SCL_DR0")
	)
	(segment
		(start 112.906302 -443.460632)
		(end 113.86312 -444.41745)
		(width 0.17145)
		(layer "B.Cu")
		(net "SCL_DR0")
	)
	(segment
		(start 115.37188 -444.41745)
		(end 115.820698 -443.968632)
		(width 0.17145)
		(layer "B.Cu")
		(net "SCL_DR0")
	)
	(segment
		(start 115.992148 -442.722)
		(end 116.371624 -442.722)
		(width 0.17145)
		(layer "B.Cu")
		(net "SCL_DR0")
	)
	(segment
		(start 86.207346 -364.35665)
		(end 112.906302 -391.055606)
		(width 0.17145)
		(layer "B.Cu")
		(net "SCL_DR0")
	)
	(segment
		(start 113.86312 -444.41745)
		(end 115.37188 -444.41745)
		(width 0.17145)
		(layer "B.Cu")
		(net "SCL_DR0")
	)
	(segment
		(start 112.906302 -391.055606)
		(end 112.906302 -443.460632)
		(width 0.17145)
		(layer "B.Cu")
		(net "SCL_DR0")
	)
	(segment
		(start 83.99653 -364.35665)
		(end 86.207346 -364.35665)
		(width 0.17145)
		(layer "B.Cu")
		(net "SCL_DR0")
	)
	(segment
		(start 83.82 -364.53318)
		(end 83.99653 -364.35665)
		(width 0.17145)
		(layer "B.Cu")
		(net "SCL_DR0")
	)
	(segment
		(start 115.820698 -443.968632)
		(end 115.820698 -442.89345)
		(width 0.17145)
		(layer "B.Cu")
		(net "SCL_DR0")
	)
	(segment
		(start 109.513624 -423.926)
		(end 110.018576 -423.926)
		(width 0.17145)
		(layer "F.Cu")
		(net "SAS_I2C_C_BUF_SDA_R")
	)
	(segment
		(start 3.826256 -456.620118)
		(end 3.70459 -456.741784)
		(width 0.17145)
		(layer "F.Cu")
		(net "SAS_I2C_C_BUF_SDA_R")
	)
	(segment
		(start 241.18824 -422.529)
		(end 241.6175 -422.529)
		(width 0.17145)
		(layer "F.Cu")
		(net "SAS_I2C_C_BUF_SDA_R")
	)
	(segment
		(start 64.136524 -441.390786)
		(end 64.136524 -440.066684)
		(width 0.17145)
		(layer "F.Cu")
		(net "SAS_I2C_C_BUF_SDA_R")
	)
	(segment
		(start 15.99692 -478.574608)
		(end 13.86078 -476.438468)
		(width 0.17145)
		(layer "F.Cu")
		(net "SAS_I2C_C_BUF_SDA_R")
	)
	(segment
		(start 37.086032 -451.81012)
		(end 37.086032 -454.68286)
		(width 0.17145)
		(layer "F.Cu")
		(net "SAS_I2C_C_BUF_SDA_R")
	)
	(segment
		(start 30.823408 -461.403192)
		(end 30.823408 -472.820238)
		(width 0.17145)
		(layer "F.Cu")
		(net "SAS_I2C_C_BUF_SDA_R")
	)
	(segment
		(start 240.829338 -422.887902)
		(end 241.18824 -422.529)
		(width 0.17145)
		(layer "F.Cu")
		(net "SAS_I2C_C_BUF_SDA_R")
	)
	(segment
		(start 63.929768 -441.597542)
		(end 64.136524 -441.390786)
		(width 0.17145)
		(layer "F.Cu")
		(net "SAS_I2C_C_BUF_SDA_R")
	)
	(segment
		(start 25.069038 -478.574608)
		(end 15.99692 -478.574608)
		(width 0.17145)
		(layer "F.Cu")
		(net "SAS_I2C_C_BUF_SDA_R")
	)
	(segment
		(start 30.823408 -472.820238)
		(end 25.069038 -478.574608)
		(width 0.17145)
		(layer "F.Cu")
		(net "SAS_I2C_C_BUF_SDA_R")
	)
	(segment
		(start 110.190026 -423.75455)
		(end 110.190026 -421.585644)
		(width 0.17145)
		(layer "F.Cu")
		(net "SAS_I2C_C_BUF_SDA_R")
	)
	(segment
		(start 62.09284 -438.023)
		(end 50.873152 -438.023)
		(width 0.17145)
		(layer "F.Cu")
		(net "SAS_I2C_C_BUF_SDA_R")
	)
	(segment
		(start 5.897118 -456.620118)
		(end 3.826256 -456.620118)
		(width 0.17145)
		(layer "F.Cu")
		(net "SAS_I2C_C_BUF_SDA_R")
	)
	(segment
		(start 3.70459 -456.741784)
		(end 2.249932 -456.741784)
		(width 0.17145)
		(layer "F.Cu")
		(net "SAS_I2C_C_BUF_SDA_R")
	)
	(segment
		(start 12.2428 -458.95514)
		(end 10.76706 -457.4794)
		(width 0.17145)
		(layer "F.Cu")
		(net "SAS_I2C_C_BUF_SDA_R")
	)
	(segment
		(start 229.586282 -417.706302)
		(end 234.767882 -422.887902)
		(width 0.17145)
		(layer "F.Cu")
		(net "SAS_I2C_C_BUF_SDA_R")
	)
	(segment
		(start 13.860526 -476.438468)
		(end 12.2428 -474.820742)
		(width 0.17145)
		(layer "F.Cu")
		(net "SAS_I2C_C_BUF_SDA_R")
	)
	(segment
		(start 37.086286 -454.683114)
		(end 37.086286 -455.140314)
		(width 0.17145)
		(layer "F.Cu")
		(net "SAS_I2C_C_BUF_SDA_R")
	)
	(segment
		(start 234.767882 -422.887902)
		(end 240.829338 -422.887902)
		(width 0.17145)
		(layer "F.Cu")
		(net "SAS_I2C_C_BUF_SDA_R")
	)
	(segment
		(start 114.069368 -417.706302)
		(end 229.586282 -417.706302)
		(width 0.17145)
		(layer "F.Cu")
		(net "SAS_I2C_C_BUF_SDA_R")
	)
	(segment
		(start 10.76706 -457.4794)
		(end 6.7564 -457.4794)
		(width 0.17145)
		(layer "F.Cu")
		(net "SAS_I2C_C_BUF_SDA_R")
	)
	(segment
		(start 37.086286 -455.140314)
		(end 30.823408 -461.403192)
		(width 0.17145)
		(layer "F.Cu")
		(net "SAS_I2C_C_BUF_SDA_R")
	)
	(segment
		(start 50.873152 -438.023)
		(end 37.086032 -451.81012)
		(width 0.17145)
		(layer "F.Cu")
		(net "SAS_I2C_C_BUF_SDA_R")
	)
	(segment
		(start 6.7564 -457.4794)
		(end 5.897118 -456.620118)
		(width 0.17145)
		(layer "F.Cu")
		(net "SAS_I2C_C_BUF_SDA_R")
	)
	(segment
		(start 37.086032 -454.68286)
		(end 37.086286 -454.683114)
		(width 0.17145)
		(layer "F.Cu")
		(net "SAS_I2C_C_BUF_SDA_R")
	)
	(segment
		(start 13.86078 -476.438468)
		(end 13.860526 -476.438468)
		(width 0.17145)
		(layer "F.Cu")
		(net "SAS_I2C_C_BUF_SDA_R")
	)
	(segment
		(start 12.2428 -474.820742)
		(end 12.2428 -458.95514)
		(width 0.17145)
		(layer "F.Cu")
		(net "SAS_I2C_C_BUF_SDA_R")
	)
	(segment
		(start 64.136524 -440.066684)
		(end 62.09284 -438.023)
		(width 0.17145)
		(layer "F.Cu")
		(net "SAS_I2C_C_BUF_SDA_R")
	)
	(segment
		(start 110.018576 -423.926)
		(end 110.190026 -423.75455)
		(width 0.17145)
		(layer "F.Cu")
		(net "SAS_I2C_C_BUF_SDA_R")
	)
	(segment
		(start 110.190026 -421.585644)
		(end 114.069368 -417.706302)
		(width 0.17145)
		(layer "F.Cu")
		(net "SAS_I2C_C_BUF_SDA_R")
	)
	(via
		(at 63.929768 -441.597542)
		(size 0.508)
		(drill 0.254)
		(layers "F.Cu" "B.Cu")
		(net "SAS_I2C_C_BUF_SDA_R")
	)
	(via
		(at 109.513624 -423.926)
		(size 0.5588)
		(drill 0.3048)
		(layers "F.Cu" "B.Cu")
		(net "SAS_I2C_C_BUF_SDA_R")
	)
	(segment
		(start 110.143798 -423.926)
		(end 110.315248 -424.09745)
		(width 0.17145)
		(layer "B.Cu")
		(net "SAS_I2C_C_BUF_SDA_R")
	)
	(segment
		(start 90.337894 -439.784744)
		(end 77.917294 -439.784744)
		(width 0.17145)
		(layer "B.Cu")
		(net "SAS_I2C_C_BUF_SDA_R")
	)
	(segment
		(start 99.348798 -441.512452)
		(end 92.065602 -441.512452)
		(width 0.17145)
		(layer "B.Cu")
		(net "SAS_I2C_C_BUF_SDA_R")
	)
	(segment
		(start 67.094608 -435.1401)
		(end 67.094862 -435.1401)
		(width 0.17145)
		(layer "B.Cu")
		(net "SAS_I2C_C_BUF_SDA_R")
	)
	(segment
		(start 108.6866 -439.4454)
		(end 101.41585 -439.4454)
		(width 0.17145)
		(layer "B.Cu")
		(net "SAS_I2C_C_BUF_SDA_R")
	)
	(segment
		(start 92.065602 -441.512452)
		(end 90.337894 -439.784744)
		(width 0.17145)
		(layer "B.Cu")
		(net "SAS_I2C_C_BUF_SDA_R")
	)
	(segment
		(start 110.315248 -437.816752)
		(end 108.6866 -439.4454)
		(width 0.17145)
		(layer "B.Cu")
		(net "SAS_I2C_C_BUF_SDA_R")
	)
	(segment
		(start 64.136524 -441.390786)
		(end 63.929768 -441.597542)
		(width 0.17145)
		(layer "B.Cu")
		(net "SAS_I2C_C_BUF_SDA_R")
	)
	(segment
		(start 109.513624 -423.926)
		(end 110.143798 -423.926)
		(width 0.17145)
		(layer "B.Cu")
		(net "SAS_I2C_C_BUF_SDA_R")
	)
	(segment
		(start 101.41585 -439.4454)
		(end 99.348798 -441.512452)
		(width 0.17145)
		(layer "B.Cu")
		(net "SAS_I2C_C_BUF_SDA_R")
	)
	(segment
		(start 77.917294 -439.784744)
		(end 73.110852 -434.978302)
		(width 0.17145)
		(layer "B.Cu")
		(net "SAS_I2C_C_BUF_SDA_R")
	)
	(segment
		(start 67.094862 -435.1401)
		(end 64.136524 -438.098438)
		(width 0.17145)
		(layer "B.Cu")
		(net "SAS_I2C_C_BUF_SDA_R")
	)
	(segment
		(start 73.110852 -434.978302)
		(end 67.256406 -434.978302)
		(width 0.17145)
		(layer "B.Cu")
		(net "SAS_I2C_C_BUF_SDA_R")
	)
	(segment
		(start 67.256406 -434.978302)
		(end 67.094608 -435.1401)
		(width 0.17145)
		(layer "B.Cu")
		(net "SAS_I2C_C_BUF_SDA_R")
	)
	(segment
		(start 110.315248 -424.09745)
		(end 110.315248 -437.816752)
		(width 0.17145)
		(layer "B.Cu")
		(net "SAS_I2C_C_BUF_SDA_R")
	)
	(segment
		(start 64.136524 -438.098438)
		(end 64.136524 -441.390786)
		(width 0.17145)
		(layer "B.Cu")
		(net "SAS_I2C_C_BUF_SDA_R")
	)
	(segment
		(start 241.187986 -423.799)
		(end 241.6175 -423.799)
		(width 0.17145)
		(layer "F.Cu")
		(net "SAS_I2C_C_BUF_SCL_R")
	)
	(segment
		(start 12.79525 -458.726286)
		(end 10.995914 -456.92695)
		(width 0.17145)
		(layer "F.Cu")
		(net "SAS_I2C_C_BUF_SCL_R")
	)
	(segment
		(start 12.79525 -474.591888)
		(end 12.79525 -458.726286)
		(width 0.17145)
		(layer "F.Cu")
		(net "SAS_I2C_C_BUF_SCL_R")
	)
	(segment
		(start 16.225774 -478.022158)
		(end 14.089634 -475.886018)
		(width 0.17145)
		(layer "F.Cu")
		(net "SAS_I2C_C_BUF_SCL_R")
	)
	(segment
		(start 229.357428 -418.258752)
		(end 234.539028 -423.440352)
		(width 0.17145)
		(layer "F.Cu")
		(net "SAS_I2C_C_BUF_SCL_R")
	)
	(segment
		(start 36.533582 -451.581266)
		(end 36.533582 -454.911714)
		(width 0.17145)
		(layer "F.Cu")
		(net "SAS_I2C_C_BUF_SCL_R")
	)
	(segment
		(start 36.533582 -454.911714)
		(end 30.270958 -461.174338)
		(width 0.17145)
		(layer "F.Cu")
		(net "SAS_I2C_C_BUF_SCL_R")
	)
	(segment
		(start 10.995914 -456.92695)
		(end 6.985254 -456.92695)
		(width 0.17145)
		(layer "F.Cu")
		(net "SAS_I2C_C_BUF_SCL_R")
	)
	(segment
		(start 6.985254 -456.92695)
		(end 6.125972 -456.067668)
		(width 0.17145)
		(layer "F.Cu")
		(net "SAS_I2C_C_BUF_SCL_R")
	)
	(segment
		(start 110.742476 -423.75455)
		(end 110.742476 -421.814498)
		(width 0.17145)
		(layer "F.Cu")
		(net "SAS_I2C_C_BUF_SCL_R")
	)
	(segment
		(start 30.270958 -461.174338)
		(end 30.270958 -472.591384)
		(width 0.17145)
		(layer "F.Cu")
		(net "SAS_I2C_C_BUF_SCL_R")
	)
	(segment
		(start 14.08938 -475.886018)
		(end 12.79525 -474.591888)
		(width 0.17145)
		(layer "F.Cu")
		(net "SAS_I2C_C_BUF_SCL_R")
	)
	(segment
		(start 6.125972 -456.067668)
		(end 3.816096 -456.067668)
		(width 0.17145)
		(layer "F.Cu")
		(net "SAS_I2C_C_BUF_SCL_R")
	)
	(segment
		(start 64.688974 -439.83783)
		(end 62.321694 -437.47055)
		(width 0.17145)
		(layer "F.Cu")
		(net "SAS_I2C_C_BUF_SCL_R")
	)
	(segment
		(start 234.539028 -423.440352)
		(end 240.829338 -423.440352)
		(width 0.17145)
		(layer "F.Cu")
		(net "SAS_I2C_C_BUF_SCL_R")
	)
	(segment
		(start 110.742476 -421.814498)
		(end 114.298222 -418.258752)
		(width 0.17145)
		(layer "F.Cu")
		(net "SAS_I2C_C_BUF_SCL_R")
	)
	(segment
		(start 3.690366 -455.941938)
		(end 2.249932 -455.941938)
		(width 0.17145)
		(layer "F.Cu")
		(net "SAS_I2C_C_BUF_SCL_R")
	)
	(segment
		(start 14.089634 -475.886018)
		(end 14.08938 -475.886018)
		(width 0.17145)
		(layer "F.Cu")
		(net "SAS_I2C_C_BUF_SCL_R")
	)
	(segment
		(start 62.321694 -437.47055)
		(end 50.644298 -437.47055)
		(width 0.17145)
		(layer "F.Cu")
		(net "SAS_I2C_C_BUF_SCL_R")
	)
	(segment
		(start 24.840184 -478.022158)
		(end 16.225774 -478.022158)
		(width 0.17145)
		(layer "F.Cu")
		(net "SAS_I2C_C_BUF_SCL_R")
	)
	(segment
		(start 240.829338 -423.440352)
		(end 241.187986 -423.799)
		(width 0.17145)
		(layer "F.Cu")
		(net "SAS_I2C_C_BUF_SCL_R")
	)
	(segment
		(start 3.816096 -456.067668)
		(end 3.690366 -455.941938)
		(width 0.17145)
		(layer "F.Cu")
		(net "SAS_I2C_C_BUF_SCL_R")
	)
	(segment
		(start 30.270958 -472.591384)
		(end 24.840184 -478.022158)
		(width 0.17145)
		(layer "F.Cu")
		(net "SAS_I2C_C_BUF_SCL_R")
	)
	(segment
		(start 50.644298 -437.47055)
		(end 36.533582 -451.581266)
		(width 0.17145)
		(layer "F.Cu")
		(net "SAS_I2C_C_BUF_SCL_R")
	)
	(segment
		(start 64.688974 -441.390786)
		(end 64.688974 -439.83783)
		(width 0.17145)
		(layer "F.Cu")
		(net "SAS_I2C_C_BUF_SCL_R")
	)
	(segment
		(start 114.298222 -418.258752)
		(end 229.357428 -418.258752)
		(width 0.17145)
		(layer "F.Cu")
		(net "SAS_I2C_C_BUF_SCL_R")
	)
	(segment
		(start 110.913926 -423.926)
		(end 110.742476 -423.75455)
		(width 0.17145)
		(layer "F.Cu")
		(net "SAS_I2C_C_BUF_SCL_R")
	)
	(segment
		(start 64.89573 -441.597542)
		(end 64.688974 -441.390786)
		(width 0.17145)
		(layer "F.Cu")
		(net "SAS_I2C_C_BUF_SCL_R")
	)
	(segment
		(start 111.418624 -423.926)
		(end 110.913926 -423.926)
		(width 0.17145)
		(layer "F.Cu")
		(net "SAS_I2C_C_BUF_SCL_R")
	)
	(via
		(at 111.418624 -423.926)
		(size 0.5588)
		(drill 0.3048)
		(layers "F.Cu" "B.Cu")
		(net "SAS_I2C_C_BUF_SCL_R")
	)
	(via
		(at 64.89573 -441.597542)
		(size 0.508)
		(drill 0.254)
		(layers "F.Cu" "B.Cu")
		(net "SAS_I2C_C_BUF_SCL_R")
	)
	(segment
		(start 101.644704 -439.99785)
		(end 108.915454 -439.99785)
		(width 0.17145)
		(layer "B.Cu")
		(net "SAS_I2C_C_BUF_SCL_R")
	)
	(segment
		(start 110.867698 -438.045606)
		(end 110.867698 -424.256454)
		(width 0.17145)
		(layer "B.Cu")
		(net "SAS_I2C_C_BUF_SCL_R")
	)
	(segment
		(start 64.89573 -441.597542)
		(end 64.688974 -441.390786)
		(width 0.17145)
		(layer "B.Cu")
		(net "SAS_I2C_C_BUF_SCL_R")
	)
	(segment
		(start 99.577652 -442.064902)
		(end 101.644704 -439.99785)
		(width 0.17145)
		(layer "B.Cu")
		(net "SAS_I2C_C_BUF_SCL_R")
	)
	(segment
		(start 64.688974 -438.327292)
		(end 67.485514 -435.530752)
		(width 0.17145)
		(layer "B.Cu")
		(net "SAS_I2C_C_BUF_SCL_R")
	)
	(segment
		(start 67.485514 -435.530752)
		(end 72.881998 -435.530752)
		(width 0.17145)
		(layer "B.Cu")
		(net "SAS_I2C_C_BUF_SCL_R")
	)
	(segment
		(start 110.867698 -424.256454)
		(end 111.198152 -423.926)
		(width 0.17145)
		(layer "B.Cu")
		(net "SAS_I2C_C_BUF_SCL_R")
	)
	(segment
		(start 111.198152 -423.926)
		(end 111.418624 -423.926)
		(width 0.17145)
		(layer "B.Cu")
		(net "SAS_I2C_C_BUF_SCL_R")
	)
	(segment
		(start 108.915454 -439.99785)
		(end 110.867698 -438.045606)
		(width 0.17145)
		(layer "B.Cu")
		(net "SAS_I2C_C_BUF_SCL_R")
	)
	(segment
		(start 77.68844 -440.337194)
		(end 90.10904 -440.337194)
		(width 0.17145)
		(layer "B.Cu")
		(net "SAS_I2C_C_BUF_SCL_R")
	)
	(segment
		(start 64.688974 -441.390786)
		(end 64.688974 -438.327292)
		(width 0.17145)
		(layer "B.Cu")
		(net "SAS_I2C_C_BUF_SCL_R")
	)
	(segment
		(start 91.836748 -442.064902)
		(end 99.577652 -442.064902)
		(width 0.17145)
		(layer "B.Cu")
		(net "SAS_I2C_C_BUF_SCL_R")
	)
	(segment
		(start 72.881998 -435.530752)
		(end 77.68844 -440.337194)
		(width 0.17145)
		(layer "B.Cu")
		(net "SAS_I2C_C_BUF_SCL_R")
	)
	(segment
		(start 90.10904 -440.337194)
		(end 91.836748 -442.064902)
		(width 0.17145)
		(layer "B.Cu")
		(net "SAS_I2C_C_BUF_SCL_R")
	)
	(segment
		(start 14.4526 -473.905072)
		(end 14.4526 -457.740004)
		(width 0.17145)
		(layer "F.Cu")
		(net "SAS_I2C_B_BUF_SDA_R")
	)
	(segment
		(start 28.57246 -471.94597)
		(end 24.153622 -476.364808)
		(width 0.17145)
		(layer "F.Cu")
		(net "SAS_I2C_B_BUF_SDA_R")
	)
	(segment
		(start 69.215 -435.4195)
		(end 69.215 -435.106064)
		(width 0.17145)
		(layer "F.Cu")
		(net "SAS_I2C_B_BUF_SDA_R")
	)
	(segment
		(start 16.912336 -476.364808)
		(end 14.4526 -473.905072)
		(width 0.17145)
		(layer "F.Cu")
		(net "SAS_I2C_B_BUF_SDA_R")
	)
	(segment
		(start 69.215 -435.106064)
		(end 68.326 -434.217064)
		(width 0.17145)
		(layer "F.Cu")
		(net "SAS_I2C_B_BUF_SDA_R")
	)
	(segment
		(start 67.991736 -433.8828)
		(end 51.430174 -433.8828)
		(width 0.17145)
		(layer "F.Cu")
		(net "SAS_I2C_B_BUF_SDA_R")
	)
	(segment
		(start 3.657092 -451.941946)
		(end 2.249932 -451.941946)
		(width 0.17145)
		(layer "F.Cu")
		(net "SAS_I2C_B_BUF_SDA_R")
	)
	(segment
		(start 14.4526 -457.740004)
		(end 11.90879 -455.196194)
		(width 0.17145)
		(layer "F.Cu")
		(net "SAS_I2C_B_BUF_SDA_R")
	)
	(segment
		(start 4.464558 -451.804532)
		(end 3.794506 -451.804532)
		(width 0.17145)
		(layer "F.Cu")
		(net "SAS_I2C_B_BUF_SDA_R")
	)
	(segment
		(start 51.430174 -433.8828)
		(end 34.21126 -451.101714)
		(width 0.17145)
		(layer "F.Cu")
		(net "SAS_I2C_B_BUF_SDA_R")
	)
	(segment
		(start 7.85622 -455.196194)
		(end 4.464558 -451.804532)
		(width 0.17145)
		(layer "F.Cu")
		(net "SAS_I2C_B_BUF_SDA_R")
	)
	(segment
		(start 24.153622 -476.364808)
		(end 16.912336 -476.364808)
		(width 0.17145)
		(layer "F.Cu")
		(net "SAS_I2C_B_BUF_SDA_R")
	)
	(segment
		(start 3.794506 -451.804532)
		(end 3.657092 -451.941946)
		(width 0.17145)
		(layer "F.Cu")
		(net "SAS_I2C_B_BUF_SDA_R")
	)
	(segment
		(start 34.21126 -454.795636)
		(end 28.57246 -460.434436)
		(width 0.17145)
		(layer "F.Cu")
		(net "SAS_I2C_B_BUF_SDA_R")
	)
	(segment
		(start 28.57246 -460.434436)
		(end 28.57246 -471.94597)
		(width 0.17145)
		(layer "F.Cu")
		(net "SAS_I2C_B_BUF_SDA_R")
	)
	(segment
		(start 34.21126 -451.101714)
		(end 34.21126 -454.795636)
		(width 0.17145)
		(layer "F.Cu")
		(net "SAS_I2C_B_BUF_SDA_R")
	)
	(segment
		(start 68.326 -434.217064)
		(end 67.991736 -433.8828)
		(width 0.17145)
		(layer "F.Cu")
		(net "SAS_I2C_B_BUF_SDA_R")
	)
	(segment
		(start 11.90879 -455.196194)
		(end 7.85622 -455.196194)
		(width 0.17145)
		(layer "F.Cu")
		(net "SAS_I2C_B_BUF_SDA_R")
	)
	(via
		(at 68.326 -434.217064)
		(size 0.7112)
		(drill 0.3556)
		(layers "F.Cu" "B.Cu")
		(net "SAS_I2C_B_BUF_SDA_R")
	)
	(segment
		(start 28.02001 -471.717116)
		(end 23.924768 -475.812358)
		(width 0.17145)
		(layer "F.Cu")
		(net "SAS_I2C_B_BUF_SCL_R")
	)
	(segment
		(start 69.6214 -433.578)
		(end 68.46824 -433.578)
		(width 0.17145)
		(layer "F.Cu")
		(net "SAS_I2C_B_BUF_SCL_R")
	)
	(segment
		(start 4.693412 -451.252082)
		(end 3.71475 -451.252082)
		(width 0.17145)
		(layer "F.Cu")
		(net "SAS_I2C_B_BUF_SCL_R")
	)
	(segment
		(start 51.20132 -433.33035)
		(end 33.982406 -450.549264)
		(width 0.17145)
		(layer "F.Cu")
		(net "SAS_I2C_B_BUF_SCL_R")
	)
	(segment
		(start 3.71475 -451.252082)
		(end 3.604514 -451.141846)
		(width 0.17145)
		(layer "F.Cu")
		(net "SAS_I2C_B_BUF_SCL_R")
	)
	(segment
		(start 70.231 -434.1876)
		(end 69.6214 -433.578)
		(width 0.17145)
		(layer "F.Cu")
		(net "SAS_I2C_B_BUF_SCL_R")
	)
	(segment
		(start 68.22059 -433.33035)
		(end 51.20132 -433.33035)
		(width 0.17145)
		(layer "F.Cu")
		(net "SAS_I2C_B_BUF_SCL_R")
	)
	(segment
		(start 15.00505 -473.676218)
		(end 15.00505 -457.51115)
		(width 0.17145)
		(layer "F.Cu")
		(net "SAS_I2C_B_BUF_SCL_R")
	)
	(segment
		(start 17.14119 -475.812358)
		(end 15.00505 -473.676218)
		(width 0.17145)
		(layer "F.Cu")
		(net "SAS_I2C_B_BUF_SCL_R")
	)
	(segment
		(start 68.46824 -433.578)
		(end 68.22059 -433.33035)
		(width 0.17145)
		(layer "F.Cu")
		(net "SAS_I2C_B_BUF_SCL_R")
	)
	(segment
		(start 23.924768 -475.812358)
		(end 17.14119 -475.812358)
		(width 0.17145)
		(layer "F.Cu")
		(net "SAS_I2C_B_BUF_SCL_R")
	)
	(segment
		(start 15.00505 -457.51115)
		(end 12.137644 -454.643744)
		(width 0.17145)
		(layer "F.Cu")
		(net "SAS_I2C_B_BUF_SCL_R")
	)
	(segment
		(start 33.982152 -450.549264)
		(end 33.65881 -450.872606)
		(width 0.17145)
		(layer "F.Cu")
		(net "SAS_I2C_B_BUF_SCL_R")
	)
	(segment
		(start 28.02001 -460.205582)
		(end 28.02001 -471.717116)
		(width 0.17145)
		(layer "F.Cu")
		(net "SAS_I2C_B_BUF_SCL_R")
	)
	(segment
		(start 8.085074 -454.643744)
		(end 4.693412 -451.252082)
		(width 0.17145)
		(layer "F.Cu")
		(net "SAS_I2C_B_BUF_SCL_R")
	)
	(segment
		(start 33.65881 -454.566782)
		(end 28.02001 -460.205582)
		(width 0.17145)
		(layer "F.Cu")
		(net "SAS_I2C_B_BUF_SCL_R")
	)
	(segment
		(start 70.231 -434.1876)
		(end 70.231 -435.4195)
		(width 0.17145)
		(layer "F.Cu")
		(net "SAS_I2C_B_BUF_SCL_R")
	)
	(segment
		(start 33.982406 -450.549264)
		(end 33.982152 -450.549264)
		(width 0.17145)
		(layer "F.Cu")
		(net "SAS_I2C_B_BUF_SCL_R")
	)
	(segment
		(start 33.65881 -450.872606)
		(end 33.65881 -454.566782)
		(width 0.17145)
		(layer "F.Cu")
		(net "SAS_I2C_B_BUF_SCL_R")
	)
	(segment
		(start 12.137644 -454.643744)
		(end 8.085074 -454.643744)
		(width 0.17145)
		(layer "F.Cu")
		(net "SAS_I2C_B_BUF_SCL_R")
	)
	(segment
		(start 3.604514 -451.141846)
		(end 2.249932 -451.141846)
		(width 0.17145)
		(layer "F.Cu")
		(net "SAS_I2C_B_BUF_SCL_R")
	)
	(via
		(at 70.231 -434.1876)
		(size 0.7112)
		(drill 0.3556)
		(layers "F.Cu" "B.Cu")
		(net "SAS_I2C_B_BUF_SCL_R")
	)
	(segment
		(start 6.53415 -422.155874)
		(end 3.852926 -422.155874)
		(width 0.17145)
		(layer "F.Cu")
		(net "PWM_EXP_A")
	)
	(segment
		(start 8.766048 -406.578562)
		(end 8.766048 -419.923976)
		(width 0.17145)
		(layer "F.Cu")
		(net "PWM_EXP_A")
	)
	(segment
		(start 3.666998 -422.341802)
		(end 2.249932 -422.341802)
		(width 0.17145)
		(layer "F.Cu")
		(net "PWM_EXP_A")
	)
	(segment
		(start 12.583922 -402.760688)
		(end 12.002516 -403.342094)
		(width 0.17145)
		(layer "F.Cu")
		(net "PWM_EXP_A")
	)
	(segment
		(start 8.766048 -419.923976)
		(end 6.53415 -422.155874)
		(width 0.17145)
		(layer "F.Cu")
		(net "PWM_EXP_A")
	)
	(segment
		(start 12.002516 -403.342094)
		(end 8.766048 -406.578562)
		(width 0.17145)
		(layer "F.Cu")
		(net "PWM_EXP_A")
	)
	(segment
		(start 12.583922 -386.747766)
		(end 12.583922 -402.760688)
		(width 0.17145)
		(layer "F.Cu")
		(net "PWM_EXP_A")
	)
	(segment
		(start 11.910822 -386.074666)
		(end 12.583922 -386.747766)
		(width 0.17145)
		(layer "F.Cu")
		(net "PWM_EXP_A")
	)
	(segment
		(start 3.852926 -422.155874)
		(end 3.666998 -422.341802)
		(width 0.17145)
		(layer "F.Cu")
		(net "PWM_EXP_A")
	)
	(via
		(at 239.014 -419.862)
		(size 0.508)
		(drill 0.254)
		(layers "F.Cu" "B.Cu")
		(net "PWM_EXP_A")
	)
	(via
		(at 12.002516 -403.342094)
		(size 0.7112)
		(drill 0.3556)
		(layers "F.Cu" "B.Cu")
		(net "PWM_EXP_A")
	)
	(via
		(at 11.910822 -386.074666)
		(size 0.508)
		(drill 0.254)
		(layers "F.Cu" "B.Cu")
		(net "PWM_EXP_A")
	)
	(segment
		(start 239.496092 -419.379908)
		(end 256.093976 -419.379908)
		(width 0.17145)
		(layer "B.Cu")
		(net "PWM_EXP_A")
	)
	(segment
		(start 239.014 -419.862)
		(end 239.496092 -419.379908)
		(width 0.17145)
		(layer "B.Cu")
		(net "PWM_EXP_A")
	)
	(segment
		(start 125.0188 -343.1032)
		(end 222.8596 -343.1032)
		(width 0.1524)
		(layer "In5.Cu")
		(net "PWM_EXP_A")
	)
	(segment
		(start 222.8596 -343.1032)
		(end 222.859854 -343.102946)
		(width 0.1524)
		(layer "In5.Cu")
		(net "PWM_EXP_A")
	)
	(segment
		(start 234.7468 -355.473)
		(end 234.7468 -380.492)
		(width 0.1524)
		(layer "In5.Cu")
		(net "PWM_EXP_A")
	)
	(segment
		(start 20.804886 -386.074666)
		(end 22.61362 -387.8834)
		(width 0.1524)
		(layer "In5.Cu")
		(net "PWM_EXP_A")
	)
	(segment
		(start 31.90494 -387.8834)
		(end 35.20694 -391.1854)
		(width 0.1524)
		(layer "In5.Cu")
		(net "PWM_EXP_A")
	)
	(segment
		(start 234.7468 -380.492)
		(end 227.838 -387.4008)
		(width 0.1524)
		(layer "In5.Cu")
		(net "PWM_EXP_A")
	)
	(segment
		(start 227.011738 -347.737938)
		(end 234.7468 -355.473)
		(width 0.1524)
		(layer "In5.Cu")
		(net "PWM_EXP_A")
	)
	(segment
		(start 222.859854 -343.102946)
		(end 223.301306 -343.102946)
		(width 0.1524)
		(layer "In5.Cu")
		(net "PWM_EXP_A")
	)
	(segment
		(start 11.910822 -386.074666)
		(end 20.804886 -386.074666)
		(width 0.1524)
		(layer "In5.Cu")
		(net "PWM_EXP_A")
	)
	(segment
		(start 227.011738 -346.813378)
		(end 227.011738 -347.737938)
		(width 0.1524)
		(layer "In5.Cu")
		(net "PWM_EXP_A")
	)
	(segment
		(start 235.2294 -398.9324)
		(end 235.2294 -416.0774)
		(width 0.1524)
		(layer "In5.Cu")
		(net "PWM_EXP_A")
	)
	(segment
		(start 76.9366 -391.1854)
		(end 125.0188 -343.1032)
		(width 0.1524)
		(layer "In5.Cu")
		(net "PWM_EXP_A")
	)
	(segment
		(start 227.838 -387.4008)
		(end 227.838 -391.541)
		(width 0.1524)
		(layer "In5.Cu")
		(net "PWM_EXP_A")
	)
	(segment
		(start 235.2294 -416.0774)
		(end 239.014 -419.862)
		(width 0.1524)
		(layer "In5.Cu")
		(net "PWM_EXP_A")
	)
	(segment
		(start 227.838 -391.541)
		(end 235.2294 -398.9324)
		(width 0.1524)
		(layer "In5.Cu")
		(net "PWM_EXP_A")
	)
	(segment
		(start 223.301306 -343.102946)
		(end 227.011738 -346.813378)
		(width 0.1524)
		(layer "In5.Cu")
		(net "PWM_EXP_A")
	)
	(segment
		(start 22.61362 -387.8834)
		(end 31.90494 -387.8834)
		(width 0.1524)
		(layer "In5.Cu")
		(net "PWM_EXP_A")
	)
	(segment
		(start 35.20694 -391.1854)
		(end 76.9366 -391.1854)
		(width 0.1524)
		(layer "In5.Cu")
		(net "PWM_EXP_A")
	)
	(via
		(at 16.149066 -481.299774)
		(size 0.7112)
		(drill 0.3556)
		(layers "F.Cu" "B.Cu")
		(net "PEER_TRAY_PRESENT")
	)
	(segment
		(start 5.836666 -456.741784)
		(end 6.650482 -457.5556)
		(width 0.17145)
		(layer "B.Cu")
		(net "PEER_TRAY_PRESENT")
	)
	(segment
		(start 229.292912 -445.49695)
		(end 220.80855 -453.981312)
		(width 0.17145)
		(layer "B.Cu")
		(net "PEER_TRAY_PRESENT")
	)
	(segment
		(start 20.064476 -481.299774)
		(end 16.149066 -481.299774)
		(width 0.17145)
		(layer "B.Cu")
		(net "PEER_TRAY_PRESENT")
	)
	(segment
		(start 1.868932 -456.741784)
		(end 5.836666 -456.741784)
		(width 0.17145)
		(layer "B.Cu")
		(net "PEER_TRAY_PRESENT")
	)
	(segment
		(start 12.061698 -458.711808)
		(end 12.061698 -475.100396)
		(width 0.17145)
		(layer "B.Cu")
		(net "PEER_TRAY_PRESENT")
	)
	(segment
		(start 6.650482 -457.5556)
		(end 10.90549 -457.5556)
		(width 0.17145)
		(layer "B.Cu")
		(net "PEER_TRAY_PRESENT")
	)
	(segment
		(start 12.57173 -478.046288)
		(end 12.57173 -480.159314)
		(width 0.17145)
		(layer "B.Cu")
		(net "PEER_TRAY_PRESENT")
	)
	(segment
		(start 236.531912 -445.49695)
		(end 229.292912 -445.49695)
		(width 0.17145)
		(layer "B.Cu")
		(net "PEER_TRAY_PRESENT")
	)
	(segment
		(start 253.365 -416.179)
		(end 240.284 -416.179)
		(width 0.17145)
		(layer "B.Cu")
		(net "PEER_TRAY_PRESENT")
	)
	(segment
		(start 256.093976 -415.569908)
		(end 253.974092 -415.569908)
		(width 0.17145)
		(layer "B.Cu")
		(net "PEER_TRAY_PRESENT")
	)
	(segment
		(start 240.284 -416.179)
		(end 237.744 -418.719)
		(width 0.17145)
		(layer "B.Cu")
		(net "PEER_TRAY_PRESENT")
	)
	(segment
		(start 10.90549 -457.5556)
		(end 12.061698 -458.711808)
		(width 0.17145)
		(layer "B.Cu")
		(net "PEER_TRAY_PRESENT")
	)
	(segment
		(start 11.63955 -477.114108)
		(end 12.57173 -478.046288)
		(width 0.17145)
		(layer "B.Cu")
		(net "PEER_TRAY_PRESENT")
	)
	(segment
		(start 237.744 -418.719)
		(end 237.744 -425.704)
		(width 0.17145)
		(layer "B.Cu")
		(net "PEER_TRAY_PRESENT")
	)
	(segment
		(start 12.061698 -475.100396)
		(end 11.63955 -475.522544)
		(width 0.17145)
		(layer "B.Cu")
		(net "PEER_TRAY_PRESENT")
	)
	(segment
		(start 13.71219 -481.299774)
		(end 16.149066 -481.299774)
		(width 0.17145)
		(layer "B.Cu")
		(net "PEER_TRAY_PRESENT")
	)
	(segment
		(start 11.63955 -475.522544)
		(end 11.63955 -477.114108)
		(width 0.17145)
		(layer "B.Cu")
		(net "PEER_TRAY_PRESENT")
	)
	(segment
		(start 32.69361 -492.948722)
		(end 31.713424 -492.948722)
		(width 0.17145)
		(layer "B.Cu")
		(net "PEER_TRAY_PRESENT")
	)
	(segment
		(start 12.57173 -480.159314)
		(end 13.71219 -481.299774)
		(width 0.17145)
		(layer "B.Cu")
		(net "PEER_TRAY_PRESENT")
	)
	(segment
		(start 253.974092 -415.569908)
		(end 253.365 -416.179)
		(width 0.17145)
		(layer "B.Cu")
		(net "PEER_TRAY_PRESENT")
	)
	(segment
		(start 220.80855 -459.315312)
		(end 184.646062 -495.4778)
		(width 0.17145)
		(layer "B.Cu")
		(net "PEER_TRAY_PRESENT")
	)
	(segment
		(start 239.98555 -442.043312)
		(end 236.531912 -445.49695)
		(width 0.17145)
		(layer "B.Cu")
		(net "PEER_TRAY_PRESENT")
	)
	(segment
		(start 220.80855 -453.981312)
		(end 220.80855 -459.315312)
		(width 0.17145)
		(layer "B.Cu")
		(net "PEER_TRAY_PRESENT")
	)
	(segment
		(start 31.713424 -492.948722)
		(end 20.064476 -481.299774)
		(width 0.17145)
		(layer "B.Cu")
		(net "PEER_TRAY_PRESENT")
	)
	(segment
		(start 184.646062 -495.4778)
		(end 35.222688 -495.4778)
		(width 0.17145)
		(layer "B.Cu")
		(net "PEER_TRAY_PRESENT")
	)
	(segment
		(start 239.98555 -427.94555)
		(end 239.98555 -442.043312)
		(width 0.17145)
		(layer "B.Cu")
		(net "PEER_TRAY_PRESENT")
	)
	(segment
		(start 35.222688 -495.4778)
		(end 32.69361 -492.948722)
		(width 0.17145)
		(layer "B.Cu")
		(net "PEER_TRAY_PRESENT")
	)
	(segment
		(start 237.744 -425.704)
		(end 239.98555 -427.94555)
		(width 0.17145)
		(layer "B.Cu")
		(net "PEER_TRAY_PRESENT")
	)
	(segment
		(start 235.331 -421.64)
		(end 239.395 -417.576)
		(width 0.17145)
		(layer "F.Cu")
		(net "PEER_1A&2A_HB")
	)
	(segment
		(start 252.704092 -416.839908)
		(end 256.474976 -416.839908)
		(width 0.17145)
		(layer "F.Cu")
		(net "PEER_1A&2A_HB")
	)
	(segment
		(start 239.395 -417.576)
		(end 251.968 -417.576)
		(width 0.17145)
		(layer "F.Cu")
		(net "PEER_1A&2A_HB")
	)
	(segment
		(start 251.968 -417.576)
		(end 252.704092 -416.839908)
		(width 0.17145)
		(layer "F.Cu")
		(net "PEER_1A&2A_HB")
	)
	(via
		(at 236.22 -427.99)
		(size 0.7112)
		(drill 0.3556)
		(layers "F.Cu" "B.Cu")
		(net "PEER_1A&2A_HB")
	)
	(via
		(at 235.331 -421.64)
		(size 0.508)
		(drill 0.254)
		(layers "F.Cu" "B.Cu")
		(net "PEER_1A&2A_HB")
	)
	(segment
		(start 15.211552 -473.002102)
		(end 15.211552 -477.22536)
		(width 0.17145)
		(layer "B.Cu")
		(net "PEER_1A&2A_HB")
	)
	(segment
		(start 15.188946 -472.979496)
		(end 15.211552 -473.002102)
		(width 0.17145)
		(layer "B.Cu")
		(net "PEER_1A&2A_HB")
	)
	(segment
		(start 237.998 -441.579)
		(end 237.998 -429.768)
		(width 0.17145)
		(layer "B.Cu")
		(net "PEER_1A&2A_HB")
	)
	(segment
		(start 15.155926 -479.544126)
		(end 20.65274 -479.544126)
		(width 0.17145)
		(layer "B.Cu")
		(net "PEER_1A&2A_HB")
	)
	(segment
		(start 1.868932 -452.741792)
		(end 3.569208 -452.741792)
		(width 0.17145)
		(layer "B.Cu")
		(net "PEER_1A&2A_HB")
	)
	(segment
		(start 33.2232 -491.1344)
		(end 35.8648 -493.776)
		(width 0.17145)
		(layer "B.Cu")
		(net "PEER_1A&2A_HB")
	)
	(segment
		(start 15.211552 -477.22536)
		(end 14.86535 -477.571562)
		(width 0.17145)
		(layer "B.Cu")
		(net "PEER_1A&2A_HB")
	)
	(segment
		(start 183.896 -493.776)
		(end 219.075 -458.597)
		(width 0.17145)
		(layer "B.Cu")
		(net "PEER_1A&2A_HB")
	)
	(segment
		(start 6.9596 -454.79335)
		(end 12.04976 -454.79335)
		(width 0.17145)
		(layer "B.Cu")
		(net "PEER_1A&2A_HB")
	)
	(segment
		(start 14.86535 -472.656154)
		(end 15.188692 -472.979496)
		(width 0.17145)
		(layer "B.Cu")
		(net "PEER_1A&2A_HB")
	)
	(segment
		(start 14.86535 -477.571562)
		(end 14.86535 -479.25355)
		(width 0.17145)
		(layer "B.Cu")
		(net "PEER_1A&2A_HB")
	)
	(segment
		(start 3.569208 -452.741792)
		(end 3.7338 -452.5772)
		(width 0.17145)
		(layer "B.Cu")
		(net "PEER_1A&2A_HB")
	)
	(segment
		(start 35.8648 -493.776)
		(end 183.896 -493.776)
		(width 0.17145)
		(layer "B.Cu")
		(net "PEER_1A&2A_HB")
	)
	(segment
		(start 14.86535 -479.25355)
		(end 15.155926 -479.544126)
		(width 0.17145)
		(layer "B.Cu")
		(net "PEER_1A&2A_HB")
	)
	(segment
		(start 235.8136 -443.7634)
		(end 237.998 -441.579)
		(width 0.17145)
		(layer "B.Cu")
		(net "PEER_1A&2A_HB")
	)
	(segment
		(start 236.22 -427.99)
		(end 235.331 -427.101)
		(width 0.17145)
		(layer "B.Cu")
		(net "PEER_1A&2A_HB")
	)
	(segment
		(start 3.7338 -452.5772)
		(end 4.74345 -452.5772)
		(width 0.17145)
		(layer "B.Cu")
		(net "PEER_1A&2A_HB")
	)
	(segment
		(start 4.74345 -452.5772)
		(end 6.9596 -454.79335)
		(width 0.17145)
		(layer "B.Cu")
		(net "PEER_1A&2A_HB")
	)
	(segment
		(start 14.86535 -457.60894)
		(end 14.86535 -472.656154)
		(width 0.17145)
		(layer "B.Cu")
		(net "PEER_1A&2A_HB")
	)
	(segment
		(start 237.998 -429.768)
		(end 236.22 -427.99)
		(width 0.17145)
		(layer "B.Cu")
		(net "PEER_1A&2A_HB")
	)
	(segment
		(start 32.243014 -491.1344)
		(end 33.2232 -491.1344)
		(width 0.17145)
		(layer "B.Cu")
		(net "PEER_1A&2A_HB")
	)
	(segment
		(start 15.188692 -472.979496)
		(end 15.188946 -472.979496)
		(width 0.17145)
		(layer "B.Cu")
		(net "PEER_1A&2A_HB")
	)
	(segment
		(start 219.075 -458.597)
		(end 219.075 -453.263)
		(width 0.17145)
		(layer "B.Cu")
		(net "PEER_1A&2A_HB")
	)
	(segment
		(start 235.331 -427.101)
		(end 235.331 -421.64)
		(width 0.17145)
		(layer "B.Cu")
		(net "PEER_1A&2A_HB")
	)
	(segment
		(start 228.5746 -443.7634)
		(end 235.8136 -443.7634)
		(width 0.17145)
		(layer "B.Cu")
		(net "PEER_1A&2A_HB")
	)
	(segment
		(start 12.04976 -454.79335)
		(end 14.86535 -457.60894)
		(width 0.17145)
		(layer "B.Cu")
		(net "PEER_1A&2A_HB")
	)
	(segment
		(start 20.65274 -479.544126)
		(end 32.243014 -491.1344)
		(width 0.17145)
		(layer "B.Cu")
		(net "PEER_1A&2A_HB")
	)
	(segment
		(start 219.075 -453.263)
		(end 228.5746 -443.7634)
		(width 0.17145)
		(layer "B.Cu")
		(net "PEER_1A&2A_HB")
	)
	(segment
		(start 3.905504 -196.4944)
		(end 6.738112 -196.4944)
		(width 0.174752)
		(layer "F.Cu")
		(net "PE_TX4_DR9_P")
	)
	(segment
		(start 6.738112 -196.4944)
		(end 6.992366 -196.748654)
		(width 0.174752)
		(layer "F.Cu")
		(net "PE_TX4_DR9_P")
	)
	(segment
		(start 35.583876 -77.542644)
		(end 35.33013 -77.79639)
		(width 0.174752)
		(layer "F.Cu")
		(net "PE_TX4_DR9_P")
	)
	(segment
		(start 39.200074 -77.79004)
		(end 38.093396 -77.79004)
		(width 0.174752)
		(layer "F.Cu")
		(net "PE_TX4_DR9_P")
	)
	(segment
		(start 2.249932 -196.74205)
		(end 3.657854 -196.74205)
		(width 0.174752)
		(layer "F.Cu")
		(net "PE_TX4_DR9_P")
	)
	(segment
		(start 37.846 -77.542644)
		(end 35.583876 -77.542644)
		(width 0.174752)
		(layer "F.Cu")
		(net "PE_TX4_DR9_P")
	)
	(segment
		(start 3.657854 -196.74205)
		(end 3.905504 -196.4944)
		(width 0.174752)
		(layer "F.Cu")
		(net "PE_TX4_DR9_P")
	)
	(segment
		(start 38.093396 -77.79004)
		(end 37.846 -77.542644)
		(width 0.174752)
		(layer "F.Cu")
		(net "PE_TX4_DR9_P")
	)
	(via
		(at 6.992366 -196.748654)
		(size 0.508)
		(drill 0.254)
		(layers "F.Cu" "B.Cu")
		(net "PE_TX4_DR9_P")
	)
	(via
		(at 35.33013 -77.79639)
		(size 0.508)
		(drill 0.254)
		(layers "F.Cu" "B.Cu")
		(net "PE_TX4_DR9_P")
	)
	(segment
		(start 28.084272 -79.120746)
		(end 23.004018 -86.376256)
		(width 0.1651)
		(layer "In5.Cu")
		(net "PE_TX4_DR9_P")
	)
	(segment
		(start 45.356018 -112.02924)
		(end 42.48023 -116.137436)
		(width 0.1651)
		(layer "In5.Cu")
		(net "PE_TX4_DR9_P")
	)
	(segment
		(start 42.48023 -116.137436)
		(end 37.05606 -146.892518)
		(width 0.1651)
		(layer "In5.Cu")
		(net "PE_TX4_DR9_P")
	)
	(segment
		(start 22.404832 -89.776046)
		(end 23.064216 -93.513402)
		(width 0.1651)
		(layer "In5.Cu")
		(net "PE_TX4_DR9_P")
	)
	(segment
		(start 34.04616 -77.568044)
		(end 30.18663 -78.248256)
		(width 0.1651)
		(layer "In5.Cu")
		(net "PE_TX4_DR9_P")
	)
	(segment
		(start 37.05606 -146.892518)
		(end 32.879284 -152.856692)
		(width 0.1651)
		(layer "In5.Cu")
		(net "PE_TX4_DR9_P")
	)
	(segment
		(start 30.18663 -78.248256)
		(end 28.084272 -79.120746)
		(width 0.1651)
		(layer "In5.Cu")
		(net "PE_TX4_DR9_P")
	)
	(segment
		(start 7.220966 -196.520054)
		(end 6.992366 -196.748654)
		(width 0.1651)
		(layer "In5.Cu")
		(net "PE_TX4_DR9_P")
	)
	(segment
		(start 14.88059 -192.931542)
		(end 14.879574 -192.932812)
		(width 0.1651)
		(layer "In5.Cu")
		(net "PE_TX4_DR9_P")
	)
	(segment
		(start 23.064216 -93.513402)
		(end 24.053292 -94.926404)
		(width 0.1651)
		(layer "In5.Cu")
		(net "PE_TX4_DR9_P")
	)
	(segment
		(start 35.101784 -77.568044)
		(end 34.04616 -77.568044)
		(width 0.1651)
		(layer "In5.Cu")
		(net "PE_TX4_DR9_P")
	)
	(segment
		(start 45.310298 -102.900988)
		(end 46.13783 -107.59694)
		(width 0.1651)
		(layer "In5.Cu")
		(net "PE_TX4_DR9_P")
	)
	(segment
		(start 24.053292 -94.926404)
		(end 24.77008 -95.428308)
		(width 0.1651)
		(layer "In5.Cu")
		(net "PE_TX4_DR9_P")
	)
	(segment
		(start 23.004018 -86.376256)
		(end 22.404832 -89.776046)
		(width 0.1651)
		(layer "In5.Cu")
		(net "PE_TX4_DR9_P")
	)
	(segment
		(start 29.493718 -172.056044)
		(end 14.88059 -192.931542)
		(width 0.1651)
		(layer "In5.Cu")
		(net "PE_TX4_DR9_P")
	)
	(segment
		(start 46.13783 -107.59694)
		(end 45.356018 -112.02924)
		(width 0.1651)
		(layer "In5.Cu")
		(net "PE_TX4_DR9_P")
	)
	(segment
		(start 43.92676 -100.923852)
		(end 45.310298 -102.900988)
		(width 0.1651)
		(layer "In5.Cu")
		(net "PE_TX4_DR9_P")
	)
	(segment
		(start 32.879284 -152.856692)
		(end 29.493718 -172.056044)
		(width 0.1651)
		(layer "In5.Cu")
		(net "PE_TX4_DR9_P")
	)
	(segment
		(start 14.879574 -192.932812)
		(end 10.453624 -196.031612)
		(width 0.1651)
		(layer "In5.Cu")
		(net "PE_TX4_DR9_P")
	)
	(segment
		(start 35.33013 -77.79639)
		(end 35.101784 -77.568044)
		(width 0.1651)
		(layer "In5.Cu")
		(net "PE_TX4_DR9_P")
	)
	(segment
		(start 10.453624 -196.031612)
		(end 7.682484 -196.520054)
		(width 0.1651)
		(layer "In5.Cu")
		(net "PE_TX4_DR9_P")
	)
	(segment
		(start 24.77008 -95.428308)
		(end 39.88435 -98.09353)
		(width 0.1651)
		(layer "In5.Cu")
		(net "PE_TX4_DR9_P")
	)
	(segment
		(start 39.88435 -98.09353)
		(end 43.92676 -100.923852)
		(width 0.1651)
		(layer "In5.Cu")
		(net "PE_TX4_DR9_P")
	)
	(segment
		(start 7.682484 -196.520054)
		(end 7.220966 -196.520054)
		(width 0.1651)
		(layer "In5.Cu")
		(net "PE_TX4_DR9_P")
	)
	(segment
		(start 37.846 -77.23759)
		(end 35.58413 -77.23759)
		(width 0.174752)
		(layer "F.Cu")
		(net "PE_TX4_DR9_N")
	)
	(segment
		(start 6.738874 -196.189346)
		(end 6.992366 -195.935854)
		(width 0.174752)
		(layer "F.Cu")
		(net "PE_TX4_DR9_N")
	)
	(segment
		(start 35.58413 -77.23759)
		(end 35.33013 -76.98359)
		(width 0.174752)
		(layer "F.Cu")
		(net "PE_TX4_DR9_N")
	)
	(segment
		(start 39.200074 -76.98994)
		(end 38.09365 -76.98994)
		(width 0.174752)
		(layer "F.Cu")
		(net "PE_TX4_DR9_N")
	)
	(segment
		(start 3.658362 -195.942204)
		(end 3.905504 -196.189346)
		(width 0.174752)
		(layer "F.Cu")
		(net "PE_TX4_DR9_N")
	)
	(segment
		(start 2.249932 -195.942204)
		(end 3.658362 -195.942204)
		(width 0.174752)
		(layer "F.Cu")
		(net "PE_TX4_DR9_N")
	)
	(segment
		(start 38.09365 -76.98994)
		(end 37.846 -77.23759)
		(width 0.174752)
		(layer "F.Cu")
		(net "PE_TX4_DR9_N")
	)
	(segment
		(start 3.905504 -196.189346)
		(end 6.738874 -196.189346)
		(width 0.174752)
		(layer "F.Cu")
		(net "PE_TX4_DR9_N")
	)
	(via
		(at 6.992366 -195.935854)
		(size 0.508)
		(drill 0.254)
		(layers "F.Cu" "B.Cu")
		(net "PE_TX4_DR9_N")
	)
	(via
		(at 35.33013 -76.98359)
		(size 0.508)
		(drill 0.254)
		(layers "F.Cu" "B.Cu")
		(net "PE_TX4_DR9_N")
	)
	(segment
		(start 24.630634 -95.764858)
		(end 39.744904 -98.43008)
		(width 0.1651)
		(layer "In5.Cu")
		(net "PE_TX4_DR9_N")
	)
	(segment
		(start 35.33013 -76.98359)
		(end 35.101276 -77.212444)
		(width 0.1651)
		(layer "In5.Cu")
		(net "PE_TX4_DR9_N")
	)
	(segment
		(start 29.157168 -171.916598)
		(end 14.624812 -192.67678)
		(width 0.1651)
		(layer "In5.Cu")
		(net "PE_TX4_DR9_N")
	)
	(segment
		(start 22.667468 -86.23681)
		(end 22.043644 -89.776046)
		(width 0.1651)
		(layer "In5.Cu")
		(net "PE_TX4_DR9_N")
	)
	(segment
		(start 22.727666 -93.652848)
		(end 23.797768 -95.181928)
		(width 0.1651)
		(layer "In5.Cu")
		(net "PE_TX4_DR9_N")
	)
	(segment
		(start 7.651242 -196.164454)
		(end 7.220966 -196.164454)
		(width 0.1651)
		(layer "In5.Cu")
		(net "PE_TX4_DR9_N")
	)
	(segment
		(start 43.671236 -101.179376)
		(end 44.973494 -103.04018)
		(width 0.1651)
		(layer "In5.Cu")
		(net "PE_TX4_DR9_N")
	)
	(segment
		(start 14.624812 -192.67678)
		(end 10.314178 -195.695062)
		(width 0.1651)
		(layer "In5.Cu")
		(net "PE_TX4_DR9_N")
	)
	(segment
		(start 35.101276 -77.212444)
		(end 34.014918 -77.212444)
		(width 0.1651)
		(layer "In5.Cu")
		(net "PE_TX4_DR9_N")
	)
	(segment
		(start 22.043644 -89.776046)
		(end 22.727666 -93.652848)
		(width 0.1651)
		(layer "In5.Cu")
		(net "PE_TX4_DR9_N")
	)
	(segment
		(start 45.776642 -107.59694)
		(end 45.019468 -111.889794)
		(width 0.1651)
		(layer "In5.Cu")
		(net "PE_TX4_DR9_N")
	)
	(segment
		(start 44.973494 -103.04018)
		(end 45.776642 -107.59694)
		(width 0.1651)
		(layer "In5.Cu")
		(net "PE_TX4_DR9_N")
	)
	(segment
		(start 42.14368 -115.99799)
		(end 36.71951 -146.753072)
		(width 0.1651)
		(layer "In5.Cu")
		(net "PE_TX4_DR9_N")
	)
	(segment
		(start 34.014918 -77.212444)
		(end 30.0863 -77.904848)
		(width 0.1651)
		(layer "In5.Cu")
		(net "PE_TX4_DR9_N")
	)
	(segment
		(start 45.019468 -111.889794)
		(end 42.14368 -115.99799)
		(width 0.1651)
		(layer "In5.Cu")
		(net "PE_TX4_DR9_N")
	)
	(segment
		(start 39.744904 -98.43008)
		(end 43.671236 -101.179376)
		(width 0.1651)
		(layer "In5.Cu")
		(net "PE_TX4_DR9_N")
	)
	(segment
		(start 30.0863 -77.904848)
		(end 27.85237 -78.831948)
		(width 0.1651)
		(layer "In5.Cu")
		(net "PE_TX4_DR9_N")
	)
	(segment
		(start 23.797768 -95.181928)
		(end 24.630634 -95.764858)
		(width 0.1651)
		(layer "In5.Cu")
		(net "PE_TX4_DR9_N")
	)
	(segment
		(start 7.220966 -196.164454)
		(end 6.992366 -195.935854)
		(width 0.1651)
		(layer "In5.Cu")
		(net "PE_TX4_DR9_N")
	)
	(segment
		(start 36.71951 -146.753072)
		(end 32.542734 -152.717246)
		(width 0.1651)
		(layer "In5.Cu")
		(net "PE_TX4_DR9_N")
	)
	(segment
		(start 27.85237 -78.831948)
		(end 22.667468 -86.23681)
		(width 0.1651)
		(layer "In5.Cu")
		(net "PE_TX4_DR9_N")
	)
	(segment
		(start 10.314178 -195.695062)
		(end 7.651242 -196.164454)
		(width 0.1651)
		(layer "In5.Cu")
		(net "PE_TX4_DR9_N")
	)
	(segment
		(start 32.542734 -152.717246)
		(end 29.157168 -171.916598)
		(width 0.1651)
		(layer "In5.Cu")
		(net "PE_TX4_DR9_N")
	)
	(segment
		(start 38.1 -180.790088)
		(end 37.852604 -180.542692)
		(width 0.174752)
		(layer "F.Cu")
		(net "PE_TX4_DR8_P")
	)
	(segment
		(start 37.852604 -180.542692)
		(end 35.583876 -180.542692)
		(width 0.174752)
		(layer "F.Cu")
		(net "PE_TX4_DR8_P")
	)
	(segment
		(start 39.200074 -180.790088)
		(end 38.1 -180.790088)
		(width 0.174752)
		(layer "F.Cu")
		(net "PE_TX4_DR8_P")
	)
	(segment
		(start 3.657854 -211.942172)
		(end 3.905504 -211.694522)
		(width 0.174752)
		(layer "F.Cu")
		(net "PE_TX4_DR8_P")
	)
	(segment
		(start 3.905504 -211.694522)
		(end 6.738112 -211.694522)
		(width 0.174752)
		(layer "F.Cu")
		(net "PE_TX4_DR8_P")
	)
	(segment
		(start 35.583876 -180.542692)
		(end 35.33013 -180.796438)
		(width 0.174752)
		(layer "F.Cu")
		(net "PE_TX4_DR8_P")
	)
	(segment
		(start 6.738112 -211.694522)
		(end 6.992366 -211.948776)
		(width 0.174752)
		(layer "F.Cu")
		(net "PE_TX4_DR8_P")
	)
	(segment
		(start 2.249932 -211.942172)
		(end 3.657854 -211.942172)
		(width 0.174752)
		(layer "F.Cu")
		(net "PE_TX4_DR8_P")
	)
	(via
		(at 35.33013 -180.796438)
		(size 0.508)
		(drill 0.254)
		(layers "F.Cu" "B.Cu")
		(net "PE_TX4_DR8_P")
	)
	(via
		(at 6.992366 -211.948776)
		(size 0.508)
		(drill 0.254)
		(layers "F.Cu" "B.Cu")
		(net "PE_TX4_DR8_P")
	)
	(segment
		(start 8.425942 -211.589112)
		(end 9.853422 -210.589876)
		(width 0.1651)
		(layer "In5.Cu")
		(net "PE_TX4_DR8_P")
	)
	(segment
		(start 12.182094 -204.790802)
		(end 24.121618 -187.741814)
		(width 0.1651)
		(layer "In5.Cu")
		(net "PE_TX4_DR8_P")
	)
	(segment
		(start 35.101784 -180.568092)
		(end 35.33013 -180.796438)
		(width 0.1651)
		(layer "In5.Cu")
		(net "PE_TX4_DR8_P")
	)
	(segment
		(start 9.853422 -210.589876)
		(end 11.599672 -208.096104)
		(width 0.1651)
		(layer "In5.Cu")
		(net "PE_TX4_DR8_P")
	)
	(segment
		(start 34.077402 -180.568092)
		(end 35.101784 -180.568092)
		(width 0.1651)
		(layer "In5.Cu")
		(net "PE_TX4_DR8_P")
	)
	(segment
		(start 27.369516 -183.103774)
		(end 29.95041 -181.296056)
		(width 0.1651)
		(layer "In5.Cu")
		(net "PE_TX4_DR8_P")
	)
	(segment
		(start 11.599672 -208.096104)
		(end 12.182094 -204.790802)
		(width 0.1651)
		(layer "In5.Cu")
		(net "PE_TX4_DR8_P")
	)
	(segment
		(start 7.682484 -211.720176)
		(end 8.425942 -211.589112)
		(width 0.1651)
		(layer "In5.Cu")
		(net "PE_TX4_DR8_P")
	)
	(segment
		(start 24.121618 -187.741814)
		(end 27.369516 -183.103774)
		(width 0.1651)
		(layer "In5.Cu")
		(net "PE_TX4_DR8_P")
	)
	(segment
		(start 29.95041 -181.296056)
		(end 34.077402 -180.568092)
		(width 0.1651)
		(layer "In5.Cu")
		(net "PE_TX4_DR8_P")
	)
	(segment
		(start 6.992366 -211.948776)
		(end 7.220966 -211.720176)
		(width 0.1651)
		(layer "In5.Cu")
		(net "PE_TX4_DR8_P")
	)
	(segment
		(start 7.220966 -211.720176)
		(end 7.682484 -211.720176)
		(width 0.1651)
		(layer "In5.Cu")
		(net "PE_TX4_DR8_P")
	)
	(segment
		(start 3.658108 -211.142072)
		(end 3.905504 -211.389468)
		(width 0.174752)
		(layer "F.Cu")
		(net "PE_TX4_DR8_N")
	)
	(segment
		(start 39.200074 -179.989988)
		(end 38.1 -179.989988)
		(width 0.174752)
		(layer "F.Cu")
		(net "PE_TX4_DR8_N")
	)
	(segment
		(start 35.58413 -180.237638)
		(end 35.33013 -179.983638)
		(width 0.174752)
		(layer "F.Cu")
		(net "PE_TX4_DR8_N")
	)
	(segment
		(start 3.905504 -211.389468)
		(end 6.738874 -211.389468)
		(width 0.174752)
		(layer "F.Cu")
		(net "PE_TX4_DR8_N")
	)
	(segment
		(start 6.738874 -211.389468)
		(end 6.992366 -211.135976)
		(width 0.174752)
		(layer "F.Cu")
		(net "PE_TX4_DR8_N")
	)
	(segment
		(start 37.85235 -180.237638)
		(end 35.58413 -180.237638)
		(width 0.174752)
		(layer "F.Cu")
		(net "PE_TX4_DR8_N")
	)
	(segment
		(start 38.1 -179.989988)
		(end 37.85235 -180.237638)
		(width 0.174752)
		(layer "F.Cu")
		(net "PE_TX4_DR8_N")
	)
	(segment
		(start 2.249932 -211.142072)
		(end 3.658108 -211.142072)
		(width 0.174752)
		(layer "F.Cu")
		(net "PE_TX4_DR8_N")
	)
	(via
		(at 35.33013 -179.983638)
		(size 0.508)
		(drill 0.254)
		(layers "F.Cu" "B.Cu")
		(net "PE_TX4_DR8_N")
	)
	(via
		(at 6.992366 -211.135976)
		(size 0.508)
		(drill 0.254)
		(layers "F.Cu" "B.Cu")
		(net "PE_TX4_DR8_N")
	)
	(segment
		(start 8.286496 -211.252562)
		(end 7.651242 -211.364576)
		(width 0.1651)
		(layer "In5.Cu")
		(net "PE_TX4_DR8_N")
	)
	(segment
		(start 27.113992 -182.84825)
		(end 23.830026 -187.537598)
		(width 0.1651)
		(layer "In5.Cu")
		(net "PE_TX4_DR8_N")
	)
	(segment
		(start 34.04616 -180.212492)
		(end 29.810964 -180.959506)
		(width 0.1651)
		(layer "In5.Cu")
		(net "PE_TX4_DR8_N")
	)
	(segment
		(start 11.845544 -204.651356)
		(end 11.263122 -207.956658)
		(width 0.1651)
		(layer "In5.Cu")
		(net "PE_TX4_DR8_N")
	)
	(segment
		(start 7.220966 -211.364576)
		(end 6.992366 -211.135976)
		(width 0.1651)
		(layer "In5.Cu")
		(net "PE_TX4_DR8_N")
	)
	(segment
		(start 9.597898 -210.334352)
		(end 8.286496 -211.252562)
		(width 0.1651)
		(layer "In5.Cu")
		(net "PE_TX4_DR8_N")
	)
	(segment
		(start 29.810964 -180.959506)
		(end 27.113992 -182.84825)
		(width 0.1651)
		(layer "In5.Cu")
		(net "PE_TX4_DR8_N")
	)
	(segment
		(start 11.263122 -207.956658)
		(end 9.597898 -210.334352)
		(width 0.1651)
		(layer "In5.Cu")
		(net "PE_TX4_DR8_N")
	)
	(segment
		(start 35.33013 -179.983638)
		(end 35.101276 -180.212492)
		(width 0.1651)
		(layer "In5.Cu")
		(net "PE_TX4_DR8_N")
	)
	(segment
		(start 23.830026 -187.537598)
		(end 11.845544 -204.651356)
		(width 0.1651)
		(layer "In5.Cu")
		(net "PE_TX4_DR8_N")
	)
	(segment
		(start 35.101276 -180.212492)
		(end 34.04616 -180.212492)
		(width 0.1651)
		(layer "In5.Cu")
		(net "PE_TX4_DR8_N")
	)
	(segment
		(start 7.651242 -211.364576)
		(end 7.220966 -211.364576)
		(width 0.1651)
		(layer "In5.Cu")
		(net "PE_TX4_DR8_N")
	)
	(segment
		(start 3.905504 -311.294526)
		(end 6.738112 -311.294526)
		(width 0.174752)
		(layer "F.Cu")
		(net "PE_TX4_DR7_P")
	)
	(segment
		(start 37.852604 -283.54274)
		(end 35.583876 -283.54274)
		(width 0.174752)
		(layer "F.Cu")
		(net "PE_TX4_DR7_P")
	)
	(segment
		(start 2.249932 -311.542176)
		(end 3.657854 -311.542176)
		(width 0.174752)
		(layer "F.Cu")
		(net "PE_TX4_DR7_P")
	)
	(segment
		(start 38.1 -283.790136)
		(end 37.852604 -283.54274)
		(width 0.174752)
		(layer "F.Cu")
		(net "PE_TX4_DR7_P")
	)
	(segment
		(start 39.200074 -283.790136)
		(end 38.1 -283.790136)
		(width 0.174752)
		(layer "F.Cu")
		(net "PE_TX4_DR7_P")
	)
	(segment
		(start 6.738112 -311.294526)
		(end 6.992366 -311.54878)
		(width 0.174752)
		(layer "F.Cu")
		(net "PE_TX4_DR7_P")
	)
	(segment
		(start 3.657854 -311.542176)
		(end 3.905504 -311.294526)
		(width 0.174752)
		(layer "F.Cu")
		(net "PE_TX4_DR7_P")
	)
	(segment
		(start 35.583876 -283.54274)
		(end 35.33013 -283.796486)
		(width 0.174752)
		(layer "F.Cu")
		(net "PE_TX4_DR7_P")
	)
	(via
		(at 6.992366 -311.54878)
		(size 0.508)
		(drill 0.254)
		(layers "F.Cu" "B.Cu")
		(net "PE_TX4_DR7_P")
	)
	(via
		(at 35.33013 -283.796486)
		(size 0.508)
		(drill 0.254)
		(layers "F.Cu" "B.Cu")
		(net "PE_TX4_DR7_P")
	)
	(segment
		(start 7.682484 -311.32018)
		(end 7.220966 -311.32018)
		(width 0.1651)
		(layer "In5.Cu")
		(net "PE_TX4_DR7_P")
	)
	(segment
		(start 8.951976 -311.09666)
		(end 7.682484 -311.32018)
		(width 0.1651)
		(layer "In5.Cu")
		(net "PE_TX4_DR7_P")
	)
	(segment
		(start 35.101784 -283.56814)
		(end 34.077402 -283.56814)
		(width 0.1651)
		(layer "In5.Cu")
		(net "PE_TX4_DR7_P")
	)
	(segment
		(start 34.077402 -283.56814)
		(end 31.547308 -284.014164)
		(width 0.1651)
		(layer "In5.Cu")
		(net "PE_TX4_DR7_P")
	)
	(segment
		(start 35.33013 -283.796486)
		(end 35.101784 -283.56814)
		(width 0.1651)
		(layer "In5.Cu")
		(net "PE_TX4_DR7_P")
	)
	(segment
		(start 7.220966 -311.32018)
		(end 6.992366 -311.54878)
		(width 0.1651)
		(layer "In5.Cu")
		(net "PE_TX4_DR7_P")
	)
	(segment
		(start 25.4381 -288.291778)
		(end 9.967214 -310.385968)
		(width 0.1651)
		(layer "In5.Cu")
		(net "PE_TX4_DR7_P")
	)
	(segment
		(start 9.967214 -310.385968)
		(end 8.951976 -311.09666)
		(width 0.1651)
		(layer "In5.Cu")
		(net "PE_TX4_DR7_P")
	)
	(segment
		(start 31.547308 -284.014164)
		(end 25.4381 -288.291778)
		(width 0.1651)
		(layer "In5.Cu")
		(net "PE_TX4_DR7_P")
	)
	(segment
		(start 39.200074 -282.990036)
		(end 38.1 -282.990036)
		(width 0.174752)
		(layer "F.Cu")
		(net "PE_TX4_DR7_N")
	)
	(segment
		(start 6.738874 -310.989472)
		(end 6.992366 -310.73598)
		(width 0.174752)
		(layer "F.Cu")
		(net "PE_TX4_DR7_N")
	)
	(segment
		(start 3.905504 -310.989472)
		(end 6.738874 -310.989472)
		(width 0.174752)
		(layer "F.Cu")
		(net "PE_TX4_DR7_N")
	)
	(segment
		(start 3.658108 -310.742076)
		(end 3.905504 -310.989472)
		(width 0.174752)
		(layer "F.Cu")
		(net "PE_TX4_DR7_N")
	)
	(segment
		(start 35.58413 -283.237686)
		(end 35.33013 -282.983686)
		(width 0.174752)
		(layer "F.Cu")
		(net "PE_TX4_DR7_N")
	)
	(segment
		(start 37.85235 -283.237686)
		(end 35.58413 -283.237686)
		(width 0.174752)
		(layer "F.Cu")
		(net "PE_TX4_DR7_N")
	)
	(segment
		(start 38.1 -282.990036)
		(end 37.85235 -283.237686)
		(width 0.174752)
		(layer "F.Cu")
		(net "PE_TX4_DR7_N")
	)
	(segment
		(start 2.249932 -310.742076)
		(end 3.658108 -310.742076)
		(width 0.174752)
		(layer "F.Cu")
		(net "PE_TX4_DR7_N")
	)
	(via
		(at 35.33013 -282.983686)
		(size 0.508)
		(drill 0.254)
		(layers "F.Cu" "B.Cu")
		(net "PE_TX4_DR7_N")
	)
	(via
		(at 6.992366 -310.73598)
		(size 0.508)
		(drill 0.254)
		(layers "F.Cu" "B.Cu")
		(net "PE_TX4_DR7_N")
	)
	(segment
		(start 35.33013 -282.983686)
		(end 35.101276 -283.21254)
		(width 0.1651)
		(layer "In5.Cu")
		(net "PE_TX4_DR7_N")
	)
	(segment
		(start 9.711944 -310.13019)
		(end 8.81253 -310.76011)
		(width 0.1651)
		(layer "In5.Cu")
		(net "PE_TX4_DR7_N")
	)
	(segment
		(start 25.182576 -288.036254)
		(end 9.711944 -310.13019)
		(width 0.1651)
		(layer "In5.Cu")
		(net "PE_TX4_DR7_N")
	)
	(segment
		(start 7.651242 -310.96458)
		(end 7.220966 -310.96458)
		(width 0.1651)
		(layer "In5.Cu")
		(net "PE_TX4_DR7_N")
	)
	(segment
		(start 31.407862 -283.677614)
		(end 25.182576 -288.036254)
		(width 0.1651)
		(layer "In5.Cu")
		(net "PE_TX4_DR7_N")
	)
	(segment
		(start 34.04616 -283.21254)
		(end 31.407862 -283.677614)
		(width 0.1651)
		(layer "In5.Cu")
		(net "PE_TX4_DR7_N")
	)
	(segment
		(start 35.101276 -283.21254)
		(end 34.04616 -283.21254)
		(width 0.1651)
		(layer "In5.Cu")
		(net "PE_TX4_DR7_N")
	)
	(segment
		(start 8.81253 -310.76011)
		(end 7.651242 -310.96458)
		(width 0.1651)
		(layer "In5.Cu")
		(net "PE_TX4_DR7_N")
	)
	(segment
		(start 7.220966 -310.96458)
		(end 6.992366 -310.73598)
		(width 0.1651)
		(layer "In5.Cu")
		(net "PE_TX4_DR7_N")
	)
	(segment
		(start 3.657854 -357.142034)
		(end 3.90525 -356.894638)
		(width 0.174752)
		(layer "F.Cu")
		(net "PE_TX4_DR6_P")
	)
	(segment
		(start 35.583876 -386.542788)
		(end 35.33013 -386.796534)
		(width 0.174752)
		(layer "F.Cu")
		(net "PE_TX4_DR6_P")
	)
	(segment
		(start 37.852604 -386.542788)
		(end 35.583876 -386.542788)
		(width 0.174752)
		(layer "F.Cu")
		(net "PE_TX4_DR6_P")
	)
	(segment
		(start 3.90525 -356.894638)
		(end 6.738366 -356.894638)
		(width 0.174752)
		(layer "F.Cu")
		(net "PE_TX4_DR6_P")
	)
	(segment
		(start 6.738366 -356.894638)
		(end 6.992366 -357.148638)
		(width 0.174752)
		(layer "F.Cu")
		(net "PE_TX4_DR6_P")
	)
	(segment
		(start 39.200074 -386.790184)
		(end 38.1 -386.790184)
		(width 0.174752)
		(layer "F.Cu")
		(net "PE_TX4_DR6_P")
	)
	(segment
		(start 38.1 -386.790184)
		(end 37.852604 -386.542788)
		(width 0.174752)
		(layer "F.Cu")
		(net "PE_TX4_DR6_P")
	)
	(segment
		(start 2.249932 -357.142034)
		(end 3.657854 -357.142034)
		(width 0.174752)
		(layer "F.Cu")
		(net "PE_TX4_DR6_P")
	)
	(via
		(at 35.33013 -386.796534)
		(size 0.508)
		(drill 0.254)
		(layers "F.Cu" "B.Cu")
		(net "PE_TX4_DR6_P")
	)
	(via
		(at 6.992366 -357.148638)
		(size 0.508)
		(drill 0.254)
		(layers "F.Cu" "B.Cu")
		(net "PE_TX4_DR6_P")
	)
	(segment
		(start 7.62 -356.920038)
		(end 9.047988 -357.172006)
		(width 0.1651)
		(layer "In5.Cu")
		(net "PE_TX4_DR6_P")
	)
	(segment
		(start 7.220966 -356.920038)
		(end 7.62 -356.920038)
		(width 0.1651)
		(layer "In5.Cu")
		(net "PE_TX4_DR6_P")
	)
	(segment
		(start 16.882364 -381.221742)
		(end 21.321014 -384.32994)
		(width 0.1651)
		(layer "In5.Cu")
		(net "PE_TX4_DR6_P")
	)
	(segment
		(start 14.819122 -378.276104)
		(end 16.882364 -381.221742)
		(width 0.1651)
		(layer "In5.Cu")
		(net "PE_TX4_DR6_P")
	)
	(segment
		(start 6.992366 -357.148638)
		(end 7.220966 -356.920038)
		(width 0.1651)
		(layer "In5.Cu")
		(net "PE_TX4_DR6_P")
	)
	(segment
		(start 35.101784 -386.568188)
		(end 35.33013 -386.796534)
		(width 0.1651)
		(layer "In5.Cu")
		(net "PE_TX4_DR6_P")
	)
	(segment
		(start 34.014918 -386.568188)
		(end 35.101784 -386.568188)
		(width 0.1651)
		(layer "In5.Cu")
		(net "PE_TX4_DR6_P")
	)
	(segment
		(start 10.61339 -358.267508)
		(end 11.520678 -359.563162)
		(width 0.1651)
		(layer "In5.Cu")
		(net "PE_TX4_DR6_P")
	)
	(segment
		(start 9.047988 -357.172006)
		(end 10.61339 -358.267508)
		(width 0.1651)
		(layer "In5.Cu")
		(net "PE_TX4_DR6_P")
	)
	(segment
		(start 11.520678 -359.563162)
		(end 14.819122 -378.276104)
		(width 0.1651)
		(layer "In5.Cu")
		(net "PE_TX4_DR6_P")
	)
	(segment
		(start 21.321014 -384.32994)
		(end 34.014918 -386.568188)
		(width 0.1651)
		(layer "In5.Cu")
		(net "PE_TX4_DR6_P")
	)
	(segment
		(start 3.90525 -356.589584)
		(end 6.73862 -356.589584)
		(width 0.174752)
		(layer "F.Cu")
		(net "PE_TX4_DR6_N")
	)
	(segment
		(start 38.1 -385.990084)
		(end 37.85235 -386.237734)
		(width 0.174752)
		(layer "F.Cu")
		(net "PE_TX4_DR6_N")
	)
	(segment
		(start 35.58413 -386.237734)
		(end 35.33013 -385.983734)
		(width 0.174752)
		(layer "F.Cu")
		(net "PE_TX4_DR6_N")
	)
	(segment
		(start 3.657854 -356.342188)
		(end 3.90525 -356.589584)
		(width 0.174752)
		(layer "F.Cu")
		(net "PE_TX4_DR6_N")
	)
	(segment
		(start 37.85235 -386.237734)
		(end 35.58413 -386.237734)
		(width 0.174752)
		(layer "F.Cu")
		(net "PE_TX4_DR6_N")
	)
	(segment
		(start 2.249932 -356.342188)
		(end 3.657854 -356.342188)
		(width 0.174752)
		(layer "F.Cu")
		(net "PE_TX4_DR6_N")
	)
	(segment
		(start 39.200074 -385.990084)
		(end 38.1 -385.990084)
		(width 0.174752)
		(layer "F.Cu")
		(net "PE_TX4_DR6_N")
	)
	(segment
		(start 6.73862 -356.589584)
		(end 6.992366 -356.335838)
		(width 0.174752)
		(layer "F.Cu")
		(net "PE_TX4_DR6_N")
	)
	(via
		(at 35.33013 -385.983734)
		(size 0.508)
		(drill 0.254)
		(layers "F.Cu" "B.Cu")
		(net "PE_TX4_DR6_N")
	)
	(via
		(at 6.992366 -356.335838)
		(size 0.508)
		(drill 0.254)
		(layers "F.Cu" "B.Cu")
		(net "PE_TX4_DR6_N")
	)
	(segment
		(start 7.651242 -356.564438)
		(end 9.187434 -356.835456)
		(width 0.1651)
		(layer "In5.Cu")
		(net "PE_TX4_DR6_N")
	)
	(segment
		(start 34.04616 -386.212588)
		(end 35.101276 -386.212588)
		(width 0.1651)
		(layer "In5.Cu")
		(net "PE_TX4_DR6_N")
	)
	(segment
		(start 15.155672 -378.136658)
		(end 17.137888 -380.966218)
		(width 0.1651)
		(layer "In5.Cu")
		(net "PE_TX4_DR6_N")
	)
	(segment
		(start 7.220966 -356.564438)
		(end 7.651242 -356.564438)
		(width 0.1651)
		(layer "In5.Cu")
		(net "PE_TX4_DR6_N")
	)
	(segment
		(start 10.868914 -358.011984)
		(end 11.857228 -359.423716)
		(width 0.1651)
		(layer "In5.Cu")
		(net "PE_TX4_DR6_N")
	)
	(segment
		(start 9.187434 -356.835456)
		(end 10.868914 -358.011984)
		(width 0.1651)
		(layer "In5.Cu")
		(net "PE_TX4_DR6_N")
	)
	(segment
		(start 11.857228 -359.423716)
		(end 15.155672 -378.136658)
		(width 0.1651)
		(layer "In5.Cu")
		(net "PE_TX4_DR6_N")
	)
	(segment
		(start 6.992366 -356.335838)
		(end 7.220966 -356.564438)
		(width 0.1651)
		(layer "In5.Cu")
		(net "PE_TX4_DR6_N")
	)
	(segment
		(start 35.101276 -386.212588)
		(end 35.33013 -385.983734)
		(width 0.1651)
		(layer "In5.Cu")
		(net "PE_TX4_DR6_N")
	)
	(segment
		(start 17.137888 -380.966218)
		(end 21.46046 -383.99339)
		(width 0.1651)
		(layer "In5.Cu")
		(net "PE_TX4_DR6_N")
	)
	(segment
		(start 21.46046 -383.99339)
		(end 34.04616 -386.212588)
		(width 0.1651)
		(layer "In5.Cu")
		(net "PE_TX4_DR6_N")
	)
	(segment
		(start 37.73805 -489.225082)
		(end 35.57143 -489.225082)
		(width 0.174752)
		(layer "F.Cu")
		(net "PE_TX4_DR5_P")
	)
	(segment
		(start 3.953764 -446.637918)
		(end 6.73862 -446.637918)
		(width 0.174752)
		(layer "F.Cu")
		(net "PE_TX4_DR5_P")
	)
	(segment
		(start 37.973 -488.990132)
		(end 37.73805 -489.225082)
		(width 0.174752)
		(layer "F.Cu")
		(net "PE_TX4_DR5_P")
	)
	(segment
		(start 6.73862 -446.637918)
		(end 6.992366 -446.384172)
		(width 0.174752)
		(layer "F.Cu")
		(net "PE_TX4_DR5_P")
	)
	(segment
		(start 39.200074 -488.990132)
		(end 37.973 -488.990132)
		(width 0.174752)
		(layer "F.Cu")
		(net "PE_TX4_DR5_P")
	)
	(segment
		(start 3.657854 -446.342008)
		(end 3.953764 -446.637918)
		(width 0.174752)
		(layer "F.Cu")
		(net "PE_TX4_DR5_P")
	)
	(segment
		(start 35.57143 -489.225082)
		(end 35.33013 -488.983782)
		(width 0.174752)
		(layer "F.Cu")
		(net "PE_TX4_DR5_P")
	)
	(segment
		(start 2.249932 -446.342008)
		(end 3.657854 -446.342008)
		(width 0.174752)
		(layer "F.Cu")
		(net "PE_TX4_DR5_P")
	)
	(via
		(at 35.33013 -488.983782)
		(size 0.508)
		(drill 0.254)
		(layers "F.Cu" "B.Cu")
		(net "PE_TX4_DR5_P")
	)
	(via
		(at 6.992366 -446.384172)
		(size 0.508)
		(drill 0.254)
		(layers "F.Cu" "B.Cu")
		(net "PE_TX4_DR5_P")
	)
	(segment
		(start 22.836378 -485.046528)
		(end 13.140182 -471.200734)
		(width 0.1651)
		(layer "In5.Cu")
		(net "PE_TX4_DR5_P")
	)
	(segment
		(start 7.220966 -446.612772)
		(end 6.992366 -446.384172)
		(width 0.1651)
		(layer "In5.Cu")
		(net "PE_TX4_DR5_P")
	)
	(segment
		(start 34.04616 -489.212636)
		(end 27.015948 -487.973116)
		(width 0.1651)
		(layer "In5.Cu")
		(net "PE_TX4_DR5_P")
	)
	(segment
		(start 27.015948 -487.973116)
		(end 22.836378 -485.046528)
		(width 0.1651)
		(layer "In5.Cu")
		(net "PE_TX4_DR5_P")
	)
	(segment
		(start 8.170672 -446.655698)
		(end 8.02513 -446.630044)
		(width 0.1651)
		(layer "In5.Cu")
		(net "PE_TX4_DR5_P")
	)
	(segment
		(start 8.97001 -447.562224)
		(end 8.493506 -446.88125)
		(width 0.1651)
		(layer "In5.Cu")
		(net "PE_TX4_DR5_P")
	)
	(segment
		(start 13.140182 -471.200734)
		(end 8.97001 -447.562224)
		(width 0.1651)
		(layer "In5.Cu")
		(net "PE_TX4_DR5_P")
	)
	(segment
		(start 7.927086 -446.612772)
		(end 7.220966 -446.612772)
		(width 0.1651)
		(layer "In5.Cu")
		(net "PE_TX4_DR5_P")
	)
	(segment
		(start 8.493506 -446.88125)
		(end 8.170672 -446.655698)
		(width 0.1651)
		(layer "In5.Cu")
		(net "PE_TX4_DR5_P")
	)
	(segment
		(start 8.02513 -446.630044)
		(end 7.927086 -446.612772)
		(width 0.1651)
		(layer "In5.Cu")
		(net "PE_TX4_DR5_P")
	)
	(segment
		(start 35.101276 -489.212636)
		(end 34.04616 -489.212636)
		(width 0.1651)
		(layer "In5.Cu")
		(net "PE_TX4_DR5_P")
	)
	(segment
		(start 35.33013 -488.983782)
		(end 35.101276 -489.212636)
		(width 0.1651)
		(layer "In5.Cu")
		(net "PE_TX4_DR5_P")
	)
	(segment
		(start 35.596576 -489.530136)
		(end 35.33013 -489.796582)
		(width 0.174752)
		(layer "F.Cu")
		(net "PE_TX4_DR5_N")
	)
	(segment
		(start 3.856736 -446.942972)
		(end 6.738366 -446.942972)
		(width 0.174752)
		(layer "F.Cu")
		(net "PE_TX4_DR5_N")
	)
	(segment
		(start 6.738366 -446.942972)
		(end 6.992366 -447.196972)
		(width 0.174752)
		(layer "F.Cu")
		(net "PE_TX4_DR5_N")
	)
	(segment
		(start 2.249932 -447.141854)
		(end 3.657854 -447.141854)
		(width 0.174752)
		(layer "F.Cu")
		(net "PE_TX4_DR5_N")
	)
	(segment
		(start 3.657854 -447.141854)
		(end 3.856736 -446.942972)
		(width 0.174752)
		(layer "F.Cu")
		(net "PE_TX4_DR5_N")
	)
	(segment
		(start 37.966396 -489.790232)
		(end 37.7063 -489.530136)
		(width 0.174752)
		(layer "F.Cu")
		(net "PE_TX4_DR5_N")
	)
	(segment
		(start 37.7063 -489.530136)
		(end 35.596576 -489.530136)
		(width 0.174752)
		(layer "F.Cu")
		(net "PE_TX4_DR5_N")
	)
	(segment
		(start 39.200074 -489.790232)
		(end 37.966396 -489.790232)
		(width 0.174752)
		(layer "F.Cu")
		(net "PE_TX4_DR5_N")
	)
	(via
		(at 6.992366 -447.196972)
		(size 0.508)
		(drill 0.254)
		(layers "F.Cu" "B.Cu")
		(net "PE_TX4_DR5_N")
	)
	(via
		(at 35.33013 -489.796582)
		(size 0.508)
		(drill 0.254)
		(layers "F.Cu" "B.Cu")
		(net "PE_TX4_DR5_N")
	)
	(segment
		(start 35.33013 -489.796582)
		(end 35.101784 -489.568236)
		(width 0.1651)
		(layer "In5.Cu")
		(net "PE_TX4_DR5_N")
	)
	(segment
		(start 8.031734 -446.992502)
		(end 7.895082 -446.968372)
		(width 0.1651)
		(layer "In5.Cu")
		(net "PE_TX4_DR5_N")
	)
	(segment
		(start 12.803632 -471.34018)
		(end 8.63346 -447.70167)
		(width 0.1651)
		(layer "In5.Cu")
		(net "PE_TX4_DR5_N")
	)
	(segment
		(start 35.101784 -489.568236)
		(end 34.014918 -489.568236)
		(width 0.1651)
		(layer "In5.Cu")
		(net "PE_TX4_DR5_N")
	)
	(segment
		(start 22.580854 -485.302052)
		(end 12.803632 -471.34018)
		(width 0.1651)
		(layer "In5.Cu")
		(net "PE_TX4_DR5_N")
	)
	(segment
		(start 26.876502 -488.309666)
		(end 22.580854 -485.302052)
		(width 0.1651)
		(layer "In5.Cu")
		(net "PE_TX4_DR5_N")
	)
	(segment
		(start 8.237982 -447.136774)
		(end 8.031734 -446.992502)
		(width 0.1651)
		(layer "In5.Cu")
		(net "PE_TX4_DR5_N")
	)
	(segment
		(start 8.63346 -447.70167)
		(end 8.237982 -447.136774)
		(width 0.1651)
		(layer "In5.Cu")
		(net "PE_TX4_DR5_N")
	)
	(segment
		(start 7.895082 -446.968372)
		(end 7.220966 -446.968372)
		(width 0.1651)
		(layer "In5.Cu")
		(net "PE_TX4_DR5_N")
	)
	(segment
		(start 34.014918 -489.568236)
		(end 26.876502 -488.309666)
		(width 0.1651)
		(layer "In5.Cu")
		(net "PE_TX4_DR5_N")
	)
	(segment
		(start 7.220966 -446.968372)
		(end 6.992366 -447.196972)
		(width 0.1651)
		(layer "In5.Cu")
		(net "PE_TX4_DR5_N")
	)
	(segment
		(start 3.875532 -282.5242)
		(end 3.6576 -282.742132)
		(width 0.174752)
		(layer "F.Cu")
		(net "PE_TX4_DR4_P")
	)
	(segment
		(start 224.199958 -77.79004)
		(end 223.132396 -77.79004)
		(width 0.174752)
		(layer "F.Cu")
		(net "PE_TX4_DR4_P")
	)
	(segment
		(start 222.885 -77.542644)
		(end 220.58376 -77.542644)
		(width 0.174752)
		(layer "F.Cu")
		(net "PE_TX4_DR4_P")
	)
	(segment
		(start 220.58376 -77.542644)
		(end 220.330014 -77.79639)
		(width 0.174752)
		(layer "F.Cu")
		(net "PE_TX4_DR4_P")
	)
	(segment
		(start 6.992366 -282.799536)
		(end 6.71703 -282.5242)
		(width 0.174752)
		(layer "F.Cu")
		(net "PE_TX4_DR4_P")
	)
	(segment
		(start 3.6576 -282.742132)
		(end 2.249932 -282.742132)
		(width 0.174752)
		(layer "F.Cu")
		(net "PE_TX4_DR4_P")
	)
	(segment
		(start 223.132396 -77.79004)
		(end 222.885 -77.542644)
		(width 0.174752)
		(layer "F.Cu")
		(net "PE_TX4_DR4_P")
	)
	(segment
		(start 6.71703 -282.5242)
		(end 3.875532 -282.5242)
		(width 0.174752)
		(layer "F.Cu")
		(net "PE_TX4_DR4_P")
	)
	(via
		(at 220.330014 -77.79639)
		(size 0.508)
		(drill 0.254)
		(layers "F.Cu" "B.Cu")
		(net "PE_TX4_DR4_P")
	)
	(via
		(at 6.992366 -282.799536)
		(size 0.508)
		(drill 0.254)
		(layers "F.Cu" "B.Cu")
		(net "PE_TX4_DR4_P")
	)
	(segment
		(start 219.202 -77.568044)
		(end 204.37348 -80.191864)
		(width 0.1651)
		(layer "In5.Cu")
		(net "PE_TX4_DR4_P")
	)
	(segment
		(start 204.37348 -80.191864)
		(end 90.206576 -160.135062)
		(width 0.1651)
		(layer "In5.Cu")
		(net "PE_TX4_DR4_P")
	)
	(segment
		(start 90.206576 -160.135062)
		(end 34.793174 -239.250474)
		(width 0.1651)
		(layer "In5.Cu")
		(net "PE_TX4_DR4_P")
	)
	(segment
		(start 20.53844 -276.351238)
		(end 13.099034 -281.560016)
		(width 0.1651)
		(layer "In5.Cu")
		(net "PE_TX4_DR4_P")
	)
	(segment
		(start 7.362952 -282.570936)
		(end 7.220966 -282.570936)
		(width 0.1651)
		(layer "In5.Cu")
		(net "PE_TX4_DR4_P")
	)
	(segment
		(start 220.330014 -77.79639)
		(end 220.101668 -77.568044)
		(width 0.1651)
		(layer "In5.Cu")
		(net "PE_TX4_DR4_P")
	)
	(segment
		(start 34.793174 -239.250474)
		(end 33.195768 -248.307098)
		(width 0.1651)
		(layer "In5.Cu")
		(net "PE_TX4_DR4_P")
	)
	(segment
		(start 26.598626 -257.727958)
		(end 24.24938 -271.051274)
		(width 0.1651)
		(layer "In5.Cu")
		(net "PE_TX4_DR4_P")
	)
	(segment
		(start 24.24938 -271.051274)
		(end 20.53844 -276.351238)
		(width 0.1651)
		(layer "In5.Cu")
		(net "PE_TX4_DR4_P")
	)
	(segment
		(start 13.099034 -281.560016)
		(end 7.362952 -282.570936)
		(width 0.1651)
		(layer "In5.Cu")
		(net "PE_TX4_DR4_P")
	)
	(segment
		(start 220.101668 -77.568044)
		(end 219.202 -77.568044)
		(width 0.1651)
		(layer "In5.Cu")
		(net "PE_TX4_DR4_P")
	)
	(segment
		(start 33.195768 -248.307098)
		(end 26.598626 -257.727958)
		(width 0.1651)
		(layer "In5.Cu")
		(net "PE_TX4_DR4_P")
	)
	(segment
		(start 7.220966 -282.570936)
		(end 6.992366 -282.799536)
		(width 0.1651)
		(layer "In5.Cu")
		(net "PE_TX4_DR4_P")
	)
	(segment
		(start 220.584014 -77.23759)
		(end 220.330014 -76.98359)
		(width 0.174752)
		(layer "F.Cu")
		(net "PE_TX4_DR4_N")
	)
	(segment
		(start 6.992366 -281.986736)
		(end 6.759956 -282.219146)
		(width 0.174752)
		(layer "F.Cu")
		(net "PE_TX4_DR4_N")
	)
	(segment
		(start 223.139 -76.98994)
		(end 222.89135 -77.23759)
		(width 0.174752)
		(layer "F.Cu")
		(net "PE_TX4_DR4_N")
	)
	(segment
		(start 224.199958 -76.98994)
		(end 223.139 -76.98994)
		(width 0.174752)
		(layer "F.Cu")
		(net "PE_TX4_DR4_N")
	)
	(segment
		(start 3.934968 -282.219146)
		(end 3.657854 -281.942032)
		(width 0.174752)
		(layer "F.Cu")
		(net "PE_TX4_DR4_N")
	)
	(segment
		(start 222.89135 -77.23759)
		(end 220.584014 -77.23759)
		(width 0.174752)
		(layer "F.Cu")
		(net "PE_TX4_DR4_N")
	)
	(segment
		(start 3.657854 -281.942032)
		(end 2.249932 -281.942032)
		(width 0.174752)
		(layer "F.Cu")
		(net "PE_TX4_DR4_N")
	)
	(segment
		(start 6.759956 -282.219146)
		(end 3.934968 -282.219146)
		(width 0.174752)
		(layer "F.Cu")
		(net "PE_TX4_DR4_N")
	)
	(via
		(at 6.992366 -281.986736)
		(size 0.508)
		(drill 0.254)
		(layers "F.Cu" "B.Cu")
		(net "PE_TX4_DR4_N")
	)
	(via
		(at 220.330014 -76.98359)
		(size 0.508)
		(drill 0.254)
		(layers "F.Cu" "B.Cu")
		(net "PE_TX4_DR4_N")
	)
	(segment
		(start 12.959588 -281.223466)
		(end 7.33171 -282.215336)
		(width 0.1651)
		(layer "In5.Cu")
		(net "PE_TX4_DR4_N")
	)
	(segment
		(start 220.10116 -77.212444)
		(end 219.170758 -77.212444)
		(width 0.1651)
		(layer "In5.Cu")
		(net "PE_TX4_DR4_N")
	)
	(segment
		(start 34.456624 -239.111028)
		(end 32.859218 -248.167652)
		(width 0.1651)
		(layer "In5.Cu")
		(net "PE_TX4_DR4_N")
	)
	(segment
		(start 26.262076 -257.588512)
		(end 23.91283 -270.911828)
		(width 0.1651)
		(layer "In5.Cu")
		(net "PE_TX4_DR4_N")
	)
	(segment
		(start 89.951052 -159.879538)
		(end 34.456624 -239.111028)
		(width 0.1651)
		(layer "In5.Cu")
		(net "PE_TX4_DR4_N")
	)
	(segment
		(start 7.33171 -282.215336)
		(end 7.220966 -282.215336)
		(width 0.1651)
		(layer "In5.Cu")
		(net "PE_TX4_DR4_N")
	)
	(segment
		(start 204.234034 -79.855314)
		(end 89.951052 -159.879538)
		(width 0.1651)
		(layer "In5.Cu")
		(net "PE_TX4_DR4_N")
	)
	(segment
		(start 7.220966 -282.215336)
		(end 6.992366 -281.986736)
		(width 0.1651)
		(layer "In5.Cu")
		(net "PE_TX4_DR4_N")
	)
	(segment
		(start 32.859218 -248.167652)
		(end 26.262076 -257.588512)
		(width 0.1651)
		(layer "In5.Cu")
		(net "PE_TX4_DR4_N")
	)
	(segment
		(start 219.170758 -77.212444)
		(end 204.234034 -79.855314)
		(width 0.1651)
		(layer "In5.Cu")
		(net "PE_TX4_DR4_N")
	)
	(segment
		(start 220.330014 -76.98359)
		(end 220.10116 -77.212444)
		(width 0.1651)
		(layer "In5.Cu")
		(net "PE_TX4_DR4_N")
	)
	(segment
		(start 23.91283 -270.911828)
		(end 20.282916 -276.095714)
		(width 0.1651)
		(layer "In5.Cu")
		(net "PE_TX4_DR4_N")
	)
	(segment
		(start 20.282916 -276.095714)
		(end 12.959588 -281.223466)
		(width 0.1651)
		(layer "In5.Cu")
		(net "PE_TX4_DR4_N")
	)
	(segment
		(start 3.657854 -298.7421)
		(end 3.905504 -298.49445)
		(width 0.174752)
		(layer "F.Cu")
		(net "PE_TX4_DR3_P")
	)
	(segment
		(start 222.891604 -180.542692)
		(end 220.58376 -180.542692)
		(width 0.174752)
		(layer "F.Cu")
		(net "PE_TX4_DR3_P")
	)
	(segment
		(start 3.905504 -298.49445)
		(end 6.738112 -298.49445)
		(width 0.174752)
		(layer "F.Cu")
		(net "PE_TX4_DR3_P")
	)
	(segment
		(start 6.738112 -298.49445)
		(end 6.992366 -298.748704)
		(width 0.174752)
		(layer "F.Cu")
		(net "PE_TX4_DR3_P")
	)
	(segment
		(start 2.249932 -298.7421)
		(end 3.657854 -298.7421)
		(width 0.174752)
		(layer "F.Cu")
		(net "PE_TX4_DR3_P")
	)
	(segment
		(start 223.139 -180.790088)
		(end 222.891604 -180.542692)
		(width 0.174752)
		(layer "F.Cu")
		(net "PE_TX4_DR3_P")
	)
	(segment
		(start 220.58376 -180.542692)
		(end 220.330014 -180.796438)
		(width 0.174752)
		(layer "F.Cu")
		(net "PE_TX4_DR3_P")
	)
	(segment
		(start 224.199958 -180.790088)
		(end 223.139 -180.790088)
		(width 0.174752)
		(layer "F.Cu")
		(net "PE_TX4_DR3_P")
	)
	(via
		(at 220.330014 -180.796438)
		(size 0.508)
		(drill 0.254)
		(layers "F.Cu" "B.Cu")
		(net "PE_TX4_DR3_P")
	)
	(via
		(at 6.992366 -298.748704)
		(size 0.508)
		(drill 0.254)
		(layers "F.Cu" "B.Cu")
		(net "PE_TX4_DR3_P")
	)
	(segment
		(start 58.294524 -213.663022)
		(end 83.530694 -195.993766)
		(width 0.1651)
		(layer "In5.Cu")
		(net "PE_TX4_DR3_P")
	)
	(segment
		(start 194.41287 -176.44237)
		(end 217.811096 -180.568092)
		(width 0.1651)
		(layer "In5.Cu")
		(net "PE_TX4_DR3_P")
	)
	(segment
		(start 31.85541 -257.302)
		(end 37.02812 -249.914156)
		(width 0.1651)
		(layer "In5.Cu")
		(net "PE_TX4_DR3_P")
	)
	(segment
		(start 38.41369 -242.061492)
		(end 58.294524 -213.663022)
		(width 0.1651)
		(layer "In5.Cu")
		(net "PE_TX4_DR3_P")
	)
	(segment
		(start 7.220966 -298.520104)
		(end 7.57047 -298.520104)
		(width 0.1651)
		(layer "In5.Cu")
		(net "PE_TX4_DR3_P")
	)
	(segment
		(start 220.101668 -180.568092)
		(end 220.330014 -180.796438)
		(width 0.1651)
		(layer "In5.Cu")
		(net "PE_TX4_DR3_P")
	)
	(segment
		(start 15.607538 -293.68877)
		(end 28.748228 -274.921218)
		(width 0.1651)
		(layer "In5.Cu")
		(net "PE_TX4_DR3_P")
	)
	(segment
		(start 37.02812 -249.914156)
		(end 38.41369 -242.061492)
		(width 0.1651)
		(layer "In5.Cu")
		(net "PE_TX4_DR3_P")
	)
	(segment
		(start 6.992366 -298.748704)
		(end 7.220966 -298.520104)
		(width 0.1651)
		(layer "In5.Cu")
		(net "PE_TX4_DR3_P")
	)
	(segment
		(start 9.089136 -298.252896)
		(end 15.607538 -293.68877)
		(width 0.1651)
		(layer "In5.Cu")
		(net "PE_TX4_DR3_P")
	)
	(segment
		(start 7.57047 -298.520104)
		(end 9.089136 -298.252896)
		(width 0.1651)
		(layer "In5.Cu")
		(net "PE_TX4_DR3_P")
	)
	(segment
		(start 217.811096 -180.568092)
		(end 220.101668 -180.568092)
		(width 0.1651)
		(layer "In5.Cu")
		(net "PE_TX4_DR3_P")
	)
	(segment
		(start 83.530694 -195.993766)
		(end 194.41287 -176.44237)
		(width 0.1651)
		(layer "In5.Cu")
		(net "PE_TX4_DR3_P")
	)
	(segment
		(start 28.748228 -274.921218)
		(end 31.85541 -257.302)
		(width 0.1651)
		(layer "In5.Cu")
		(net "PE_TX4_DR3_P")
	)
	(segment
		(start 224.199958 -179.989988)
		(end 223.139 -179.989988)
		(width 0.174752)
		(layer "F.Cu")
		(net "PE_TX4_DR3_N")
	)
	(segment
		(start 6.738874 -298.189396)
		(end 6.992366 -297.935904)
		(width 0.174752)
		(layer "F.Cu")
		(net "PE_TX4_DR3_N")
	)
	(segment
		(start 220.584014 -180.237638)
		(end 220.330014 -179.983638)
		(width 0.174752)
		(layer "F.Cu")
		(net "PE_TX4_DR3_N")
	)
	(segment
		(start 223.139 -179.989988)
		(end 222.89135 -180.237638)
		(width 0.174752)
		(layer "F.Cu")
		(net "PE_TX4_DR3_N")
	)
	(segment
		(start 3.658108 -297.942)
		(end 3.905504 -298.189396)
		(width 0.174752)
		(layer "F.Cu")
		(net "PE_TX4_DR3_N")
	)
	(segment
		(start 222.89135 -180.237638)
		(end 220.584014 -180.237638)
		(width 0.174752)
		(layer "F.Cu")
		(net "PE_TX4_DR3_N")
	)
	(segment
		(start 3.905504 -298.189396)
		(end 6.738874 -298.189396)
		(width 0.174752)
		(layer "F.Cu")
		(net "PE_TX4_DR3_N")
	)
	(segment
		(start 2.249932 -297.942)
		(end 3.658108 -297.942)
		(width 0.174752)
		(layer "F.Cu")
		(net "PE_TX4_DR3_N")
	)
	(via
		(at 220.330014 -179.983638)
		(size 0.508)
		(drill 0.254)
		(layers "F.Cu" "B.Cu")
		(net "PE_TX4_DR3_N")
	)
	(via
		(at 6.992366 -297.935904)
		(size 0.508)
		(drill 0.254)
		(layers "F.Cu" "B.Cu")
		(net "PE_TX4_DR3_N")
	)
	(segment
		(start 58.039 -213.407498)
		(end 83.391248 -195.657216)
		(width 0.1651)
		(layer "In5.Cu")
		(net "PE_TX4_DR3_N")
	)
	(segment
		(start 7.220966 -298.164504)
		(end 7.539228 -298.164504)
		(width 0.1651)
		(layer "In5.Cu")
		(net "PE_TX4_DR3_N")
	)
	(segment
		(start 8.94969 -297.916346)
		(end 15.352014 -293.433246)
		(width 0.1651)
		(layer "In5.Cu")
		(net "PE_TX4_DR3_N")
	)
	(segment
		(start 36.69157 -249.77471)
		(end 38.07714 -241.922046)
		(width 0.1651)
		(layer "In5.Cu")
		(net "PE_TX4_DR3_N")
	)
	(segment
		(start 83.391248 -195.657216)
		(end 194.41287 -176.081182)
		(width 0.1651)
		(layer "In5.Cu")
		(net "PE_TX4_DR3_N")
	)
	(segment
		(start 217.842338 -180.212492)
		(end 220.10116 -180.212492)
		(width 0.1651)
		(layer "In5.Cu")
		(net "PE_TX4_DR3_N")
	)
	(segment
		(start 194.41287 -176.081182)
		(end 217.842338 -180.212492)
		(width 0.1651)
		(layer "In5.Cu")
		(net "PE_TX4_DR3_N")
	)
	(segment
		(start 38.07714 -241.922046)
		(end 58.039 -213.407498)
		(width 0.1651)
		(layer "In5.Cu")
		(net "PE_TX4_DR3_N")
	)
	(segment
		(start 7.539228 -298.164504)
		(end 8.94969 -297.916346)
		(width 0.1651)
		(layer "In5.Cu")
		(net "PE_TX4_DR3_N")
	)
	(segment
		(start 220.10116 -180.212492)
		(end 220.330014 -179.983638)
		(width 0.1651)
		(layer "In5.Cu")
		(net "PE_TX4_DR3_N")
	)
	(segment
		(start 31.51886 -257.162554)
		(end 36.69157 -249.77471)
		(width 0.1651)
		(layer "In5.Cu")
		(net "PE_TX4_DR3_N")
	)
	(segment
		(start 6.992366 -297.935904)
		(end 7.220966 -298.164504)
		(width 0.1651)
		(layer "In5.Cu")
		(net "PE_TX4_DR3_N")
	)
	(segment
		(start 28.411678 -274.781772)
		(end 31.51886 -257.162554)
		(width 0.1651)
		(layer "In5.Cu")
		(net "PE_TX4_DR3_N")
	)
	(segment
		(start 15.352014 -293.433246)
		(end 28.411678 -274.781772)
		(width 0.1651)
		(layer "In5.Cu")
		(net "PE_TX4_DR3_N")
	)
	(segment
		(start 223.132396 -283.790136)
		(end 222.885 -283.54274)
		(width 0.174752)
		(layer "F.Cu")
		(net "PE_TX4_DR2_P")
	)
	(segment
		(start 220.58376 -283.54274)
		(end 220.330014 -283.796486)
		(width 0.174752)
		(layer "F.Cu")
		(net "PE_TX4_DR2_P")
	)
	(segment
		(start 224.199958 -283.790136)
		(end 223.132396 -283.790136)
		(width 0.174752)
		(layer "F.Cu")
		(net "PE_TX4_DR2_P")
	)
	(segment
		(start 2.249932 -329.14209)
		(end 3.657854 -329.14209)
		(width 0.174752)
		(layer "F.Cu")
		(net "PE_TX4_DR2_P")
	)
	(segment
		(start 3.905504 -328.89444)
		(end 6.738112 -328.89444)
		(width 0.174752)
		(layer "F.Cu")
		(net "PE_TX4_DR2_P")
	)
	(segment
		(start 222.885 -283.54274)
		(end 220.58376 -283.54274)
		(width 0.174752)
		(layer "F.Cu")
		(net "PE_TX4_DR2_P")
	)
	(segment
		(start 6.738112 -328.89444)
		(end 6.992366 -329.148694)
		(width 0.174752)
		(layer "F.Cu")
		(net "PE_TX4_DR2_P")
	)
	(segment
		(start 3.657854 -329.14209)
		(end 3.905504 -328.89444)
		(width 0.174752)
		(layer "F.Cu")
		(net "PE_TX4_DR2_P")
	)
	(via
		(at 6.992366 -329.148694)
		(size 0.508)
		(drill 0.254)
		(layers "F.Cu" "B.Cu")
		(net "PE_TX4_DR2_P")
	)
	(via
		(at 220.330014 -283.796486)
		(size 0.508)
		(drill 0.254)
		(layers "F.Cu" "B.Cu")
		(net "PE_TX4_DR2_P")
	)
	(segment
		(start 46.307502 -305.630834)
		(end 67.83324 -290.558728)
		(width 0.1651)
		(layer "In5.Cu")
		(net "PE_TX4_DR2_P")
	)
	(segment
		(start 219.014802 -283.56814)
		(end 220.101668 -283.56814)
		(width 0.1651)
		(layer "In5.Cu")
		(net "PE_TX4_DR2_P")
	)
	(segment
		(start 220.101668 -283.56814)
		(end 220.330014 -283.796486)
		(width 0.1651)
		(layer "In5.Cu")
		(net "PE_TX4_DR2_P")
	)
	(segment
		(start 6.992366 -329.148694)
		(end 7.220966 -328.920094)
		(width 0.1651)
		(layer "In5.Cu")
		(net "PE_TX4_DR2_P")
	)
	(segment
		(start 8.35025 -328.802492)
		(end 8.360664 -328.795126)
		(width 0.1651)
		(layer "In5.Cu")
		(net "PE_TX4_DR2_P")
	)
	(segment
		(start 16.452088 -308.567836)
		(end 17.52473 -307.036216)
		(width 0.1651)
		(layer "In5.Cu")
		(net "PE_TX4_DR2_P")
	)
	(segment
		(start 115.0366 -282.23591)
		(end 127.487426 -280.040588)
		(width 0.1651)
		(layer "In5.Cu")
		(net "PE_TX4_DR2_P")
	)
	(segment
		(start 11.153394 -326.839072)
		(end 12.132056 -325.44131)
		(width 0.1651)
		(layer "In5.Cu")
		(net "PE_TX4_DR2_P")
	)
	(segment
		(start 17.52473 -307.036216)
		(end 21.21027 -304.45583)
		(width 0.1651)
		(layer "In5.Cu")
		(net "PE_TX4_DR2_P")
	)
	(segment
		(start 21.21027 -304.45583)
		(end 22.979634 -304.143664)
		(width 0.1651)
		(layer "In5.Cu")
		(net "PE_TX4_DR2_P")
	)
	(segment
		(start 163.247324 -273.735038)
		(end 219.014802 -283.56814)
		(width 0.1651)
		(layer "In5.Cu")
		(net "PE_TX4_DR2_P")
	)
	(segment
		(start 12.132056 -325.44131)
		(end 13.92936 -322.87464)
		(width 0.1651)
		(layer "In5.Cu")
		(net "PE_TX4_DR2_P")
	)
	(segment
		(start 7.220966 -328.920094)
		(end 7.682484 -328.920094)
		(width 0.1651)
		(layer "In5.Cu")
		(net "PE_TX4_DR2_P")
	)
	(segment
		(start 8.349742 -328.802492)
		(end 8.35025 -328.802492)
		(width 0.1651)
		(layer "In5.Cu")
		(net "PE_TX4_DR2_P")
	)
	(segment
		(start 8.360664 -328.795126)
		(end 11.153394 -326.839072)
		(width 0.1651)
		(layer "In5.Cu")
		(net "PE_TX4_DR2_P")
	)
	(segment
		(start 67.83324 -290.558728)
		(end 115.0366 -282.23591)
		(width 0.1651)
		(layer "In5.Cu")
		(net "PE_TX4_DR2_P")
	)
	(segment
		(start 7.682484 -328.920094)
		(end 8.349742 -328.802492)
		(width 0.1651)
		(layer "In5.Cu")
		(net "PE_TX4_DR2_P")
	)
	(segment
		(start 22.979634 -304.143664)
		(end 38.863778 -306.94376)
		(width 0.1651)
		(layer "In5.Cu")
		(net "PE_TX4_DR2_P")
	)
	(segment
		(start 13.92936 -322.87464)
		(end 16.452088 -308.567836)
		(width 0.1651)
		(layer "In5.Cu")
		(net "PE_TX4_DR2_P")
	)
	(segment
		(start 38.863778 -306.94376)
		(end 46.307502 -305.630834)
		(width 0.1651)
		(layer "In5.Cu")
		(net "PE_TX4_DR2_P")
	)
	(segment
		(start 127.487426 -280.040588)
		(end 163.247324 -273.735038)
		(width 0.1651)
		(layer "In5.Cu")
		(net "PE_TX4_DR2_P")
	)
	(segment
		(start 222.89135 -283.237686)
		(end 220.584014 -283.237686)
		(width 0.174752)
		(layer "F.Cu")
		(net "PE_TX4_DR2_N")
	)
	(segment
		(start 6.738874 -328.589386)
		(end 6.992366 -328.335894)
		(width 0.174752)
		(layer "F.Cu")
		(net "PE_TX4_DR2_N")
	)
	(segment
		(start 3.905504 -328.589386)
		(end 6.738874 -328.589386)
		(width 0.174752)
		(layer "F.Cu")
		(net "PE_TX4_DR2_N")
	)
	(segment
		(start 3.658108 -328.34199)
		(end 3.905504 -328.589386)
		(width 0.174752)
		(layer "F.Cu")
		(net "PE_TX4_DR2_N")
	)
	(segment
		(start 220.584014 -283.237686)
		(end 220.330014 -282.983686)
		(width 0.174752)
		(layer "F.Cu")
		(net "PE_TX4_DR2_N")
	)
	(segment
		(start 224.199958 -282.990036)
		(end 223.139 -282.990036)
		(width 0.174752)
		(layer "F.Cu")
		(net "PE_TX4_DR2_N")
	)
	(segment
		(start 223.139 -282.990036)
		(end 222.89135 -283.237686)
		(width 0.174752)
		(layer "F.Cu")
		(net "PE_TX4_DR2_N")
	)
	(segment
		(start 2.249932 -328.34199)
		(end 3.658108 -328.34199)
		(width 0.174752)
		(layer "F.Cu")
		(net "PE_TX4_DR2_N")
	)
	(via
		(at 6.992366 -328.335894)
		(size 0.508)
		(drill 0.254)
		(layers "F.Cu" "B.Cu")
		(net "PE_TX4_DR2_N")
	)
	(via
		(at 220.330014 -282.983686)
		(size 0.508)
		(drill 0.254)
		(layers "F.Cu" "B.Cu")
		(net "PE_TX4_DR2_N")
	)
	(segment
		(start 46.168056 -305.294284)
		(end 67.693794 -290.222178)
		(width 0.1651)
		(layer "In5.Cu")
		(net "PE_TX4_DR2_N")
	)
	(segment
		(start 13.59281 -322.735194)
		(end 16.115538 -308.42839)
		(width 0.1651)
		(layer "In5.Cu")
		(net "PE_TX4_DR2_N")
	)
	(segment
		(start 22.979634 -303.782476)
		(end 38.863778 -306.582572)
		(width 0.1651)
		(layer "In5.Cu")
		(net "PE_TX4_DR2_N")
	)
	(segment
		(start 38.863778 -306.582572)
		(end 46.168056 -305.294284)
		(width 0.1651)
		(layer "In5.Cu")
		(net "PE_TX4_DR2_N")
	)
	(segment
		(start 8.736076 -328.097896)
		(end 10.89787 -326.583548)
		(width 0.1651)
		(layer "In5.Cu")
		(net "PE_TX4_DR2_N")
	)
	(segment
		(start 163.247578 -273.37385)
		(end 219.046044 -283.21254)
		(width 0.1651)
		(layer "In5.Cu")
		(net "PE_TX4_DR2_N")
	)
	(segment
		(start 17.269206 -306.780692)
		(end 21.070824 -304.11928)
		(width 0.1651)
		(layer "In5.Cu")
		(net "PE_TX4_DR2_N")
	)
	(segment
		(start 16.115538 -308.42839)
		(end 17.269206 -306.780692)
		(width 0.1651)
		(layer "In5.Cu")
		(net "PE_TX4_DR2_N")
	)
	(segment
		(start 10.89787 -326.583548)
		(end 11.840718 -325.237348)
		(width 0.1651)
		(layer "In5.Cu")
		(net "PE_TX4_DR2_N")
	)
	(segment
		(start 8.210296 -328.465942)
		(end 8.21055 -328.465942)
		(width 0.1651)
		(layer "In5.Cu")
		(net "PE_TX4_DR2_N")
	)
	(segment
		(start 7.220966 -328.564494)
		(end 7.651242 -328.564494)
		(width 0.1651)
		(layer "In5.Cu")
		(net "PE_TX4_DR2_N")
	)
	(segment
		(start 11.840718 -325.237348)
		(end 13.59281 -322.735194)
		(width 0.1651)
		(layer "In5.Cu")
		(net "PE_TX4_DR2_N")
	)
	(segment
		(start 219.046044 -283.21254)
		(end 220.10116 -283.21254)
		(width 0.1651)
		(layer "In5.Cu")
		(net "PE_TX4_DR2_N")
	)
	(segment
		(start 67.693794 -290.222178)
		(end 163.247578 -273.37385)
		(width 0.1651)
		(layer "In5.Cu")
		(net "PE_TX4_DR2_N")
	)
	(segment
		(start 220.10116 -283.21254)
		(end 220.330014 -282.983686)
		(width 0.1651)
		(layer "In5.Cu")
		(net "PE_TX4_DR2_N")
	)
	(segment
		(start 6.992366 -328.335894)
		(end 7.220966 -328.564494)
		(width 0.1651)
		(layer "In5.Cu")
		(net "PE_TX4_DR2_N")
	)
	(segment
		(start 8.21055 -328.465942)
		(end 8.736076 -328.097896)
		(width 0.1651)
		(layer "In5.Cu")
		(net "PE_TX4_DR2_N")
	)
	(segment
		(start 21.070824 -304.11928)
		(end 22.979634 -303.782476)
		(width 0.1651)
		(layer "In5.Cu")
		(net "PE_TX4_DR2_N")
	)
	(segment
		(start 7.651242 -328.564494)
		(end 8.210296 -328.465942)
		(width 0.1651)
		(layer "In5.Cu")
		(net "PE_TX4_DR2_N")
	)
	(segment
		(start 26.416254 -16.457168)
		(end 26.67 -16.203422)
		(width 0.174752)
		(layer "F.Cu")
		(net "PE_TX4_DR14_P")
	)
	(segment
		(start 2.249932 -163.142168)
		(end 3.6576 -163.142168)
		(width 0.174752)
		(layer "F.Cu")
		(net "PE_TX4_DR14_P")
	)
	(segment
		(start 3.6576 -163.142168)
		(end 3.85445 -162.945318)
		(width 0.174752)
		(layer "F.Cu")
		(net "PE_TX4_DR14_P")
	)
	(segment
		(start 24.123396 -16.457168)
		(end 26.416254 -16.457168)
		(width 0.174752)
		(layer "F.Cu")
		(net "PE_TX4_DR14_P")
	)
	(segment
		(start 3.85445 -162.945318)
		(end 6.738112 -162.945318)
		(width 0.174752)
		(layer "F.Cu")
		(net "PE_TX4_DR14_P")
	)
	(segment
		(start 23.876 -16.209772)
		(end 24.123396 -16.457168)
		(width 0.174752)
		(layer "F.Cu")
		(net "PE_TX4_DR14_P")
	)
	(segment
		(start 22.800056 -16.209772)
		(end 23.876 -16.209772)
		(width 0.174752)
		(layer "F.Cu")
		(net "PE_TX4_DR14_P")
	)
	(segment
		(start 6.738112 -162.945318)
		(end 6.992366 -163.199572)
		(width 0.174752)
		(layer "F.Cu")
		(net "PE_TX4_DR14_P")
	)
	(via
		(at 26.67 -16.203422)
		(size 0.508)
		(drill 0.254)
		(layers "F.Cu" "B.Cu")
		(net "PE_TX4_DR14_P")
	)
	(via
		(at 6.992366 -163.199572)
		(size 0.508)
		(drill 0.254)
		(layers "F.Cu" "B.Cu")
		(net "PE_TX4_DR14_P")
	)
	(segment
		(start 26.67 -16.203422)
		(end 26.898346 -16.431768)
		(width 0.1651)
		(layer "In5.Cu")
		(net "PE_TX4_DR14_P")
	)
	(segment
		(start 7.363206 -162.970972)
		(end 7.220966 -162.970972)
		(width 0.1651)
		(layer "In5.Cu")
		(net "PE_TX4_DR14_P")
	)
	(segment
		(start 29.41701 -66.658998)
		(end 18.662142 -82.017108)
		(width 0.1651)
		(layer "In5.Cu")
		(net "PE_TX4_DR14_P")
	)
	(segment
		(start 18.662142 -82.017108)
		(end 12.132056 -119.081296)
		(width 0.1651)
		(layer "In5.Cu")
		(net "PE_TX4_DR14_P")
	)
	(segment
		(start 27.985212 -16.431768)
		(end 28.977844 -16.606774)
		(width 0.1651)
		(layer "In5.Cu")
		(net "PE_TX4_DR14_P")
	)
	(segment
		(start 34.974784 -21.651976)
		(end 36.16452 -28.398978)
		(width 0.1651)
		(layer "In5.Cu")
		(net "PE_TX4_DR14_P")
	)
	(segment
		(start 12.872974 -158.21152)
		(end 12.873482 -158.21152)
		(width 0.1651)
		(layer "In5.Cu")
		(net "PE_TX4_DR14_P")
	)
	(segment
		(start 10.54735 -161.534094)
		(end 8.875776 -162.704272)
		(width 0.1651)
		(layer "In5.Cu")
		(net "PE_TX4_DR14_P")
	)
	(segment
		(start 26.898346 -16.431768)
		(end 27.985212 -16.431768)
		(width 0.1651)
		(layer "In5.Cu")
		(net "PE_TX4_DR14_P")
	)
	(segment
		(start 28.977844 -16.606774)
		(end 33.812734 -19.991832)
		(width 0.1651)
		(layer "In5.Cu")
		(net "PE_TX4_DR14_P")
	)
	(segment
		(start 7.220966 -162.970972)
		(end 6.992366 -163.199572)
		(width 0.1651)
		(layer "In5.Cu")
		(net "PE_TX4_DR14_P")
	)
	(segment
		(start 33.812734 -19.991832)
		(end 34.974784 -21.651976)
		(width 0.1651)
		(layer "In5.Cu")
		(net "PE_TX4_DR14_P")
	)
	(segment
		(start 15.94993 -140.761466)
		(end 12.872974 -158.21152)
		(width 0.1651)
		(layer "In5.Cu")
		(net "PE_TX4_DR14_P")
	)
	(segment
		(start 8.875776 -162.704272)
		(end 7.363206 -162.970972)
		(width 0.1651)
		(layer "In5.Cu")
		(net "PE_TX4_DR14_P")
	)
	(segment
		(start 36.16452 -28.398978)
		(end 29.41701 -66.658998)
		(width 0.1651)
		(layer "In5.Cu")
		(net "PE_TX4_DR14_P")
	)
	(segment
		(start 12.132056 -119.081296)
		(end 15.94993 -140.761466)
		(width 0.1651)
		(layer "In5.Cu")
		(net "PE_TX4_DR14_P")
	)
	(segment
		(start 12.873482 -158.21152)
		(end 10.54735 -161.534094)
		(width 0.1651)
		(layer "In5.Cu")
		(net "PE_TX4_DR14_P")
	)
	(segment
		(start 22.800056 -17.009872)
		(end 23.88235 -17.009872)
		(width 0.174752)
		(layer "F.Cu")
		(net "PE_TX4_DR14_N")
	)
	(segment
		(start 3.657854 -162.342068)
		(end 3.95605 -162.640264)
		(width 0.174752)
		(layer "F.Cu")
		(net "PE_TX4_DR14_N")
	)
	(segment
		(start 3.95605 -162.640264)
		(end 6.738874 -162.640264)
		(width 0.174752)
		(layer "F.Cu")
		(net "PE_TX4_DR14_N")
	)
	(segment
		(start 24.13 -16.762222)
		(end 26.416 -16.762222)
		(width 0.174752)
		(layer "F.Cu")
		(net "PE_TX4_DR14_N")
	)
	(segment
		(start 2.249932 -162.342068)
		(end 3.657854 -162.342068)
		(width 0.174752)
		(layer "F.Cu")
		(net "PE_TX4_DR14_N")
	)
	(segment
		(start 23.88235 -17.009872)
		(end 24.13 -16.762222)
		(width 0.174752)
		(layer "F.Cu")
		(net "PE_TX4_DR14_N")
	)
	(segment
		(start 6.738874 -162.640264)
		(end 6.992366 -162.386772)
		(width 0.174752)
		(layer "F.Cu")
		(net "PE_TX4_DR14_N")
	)
	(segment
		(start 26.416 -16.762222)
		(end 26.67 -17.016222)
		(width 0.174752)
		(layer "F.Cu")
		(net "PE_TX4_DR14_N")
	)
	(via
		(at 6.992366 -162.386772)
		(size 0.508)
		(drill 0.254)
		(layers "F.Cu" "B.Cu")
		(net "PE_TX4_DR14_N")
	)
	(via
		(at 26.67 -17.016222)
		(size 0.508)
		(drill 0.254)
		(layers "F.Cu" "B.Cu")
		(net "PE_TX4_DR14_N")
	)
	(segment
		(start 35.27679 -25.412954)
		(end 35.190684 -24.925274)
		(width 0.1651)
		(layer "In5.Cu")
		(net "PE_TX4_DR14_N")
	)
	(segment
		(start 35.039554 -24.067262)
		(end 34.953448 -23.579582)
		(width 0.1651)
		(layer "In5.Cu")
		(net "PE_TX4_DR14_N")
	)
	(segment
		(start 35.190684 -24.925274)
		(end 34.973006 -24.772874)
		(width 0.1651)
		(layer "In5.Cu")
		(net "PE_TX4_DR14_N")
	)
	(segment
		(start 30.24505 -18.157698)
		(end 30.199076 -17.896078)
		(width 0.1651)
		(layer "In5.Cu")
		(net "PE_TX4_DR14_N")
	)
	(segment
		(start 15.588742 -140.761466)
		(end 11.770868 -119.081296)
		(width 0.1651)
		(layer "In5.Cu")
		(net "PE_TX4_DR14_N")
	)
	(segment
		(start 35.210242 -26.118566)
		(end 35.124136 -25.630886)
		(width 0.1651)
		(layer "In5.Cu")
		(net "PE_TX4_DR14_N")
	)
	(segment
		(start 10.291826 -161.27857)
		(end 10.575798 -160.872932)
		(width 0.1651)
		(layer "In5.Cu")
		(net "PE_TX4_DR14_N")
	)
	(segment
		(start 30.650942 -18.441924)
		(end 30.24505 -18.157698)
		(width 0.1651)
		(layer "In5.Cu")
		(net "PE_TX4_DR14_N")
	)
	(segment
		(start 30.912562 -18.395696)
		(end 30.650942 -18.441924)
		(width 0.1651)
		(layer "In5.Cu")
		(net "PE_TX4_DR14_N")
	)
	(segment
		(start 34.973006 -24.772874)
		(end 34.8869 -24.285194)
		(width 0.1651)
		(layer "In5.Cu")
		(net "PE_TX4_DR14_N")
	)
	(segment
		(start 11.770868 -119.081296)
		(end 18.325592 -81.877662)
		(width 0.1651)
		(layer "In5.Cu")
		(net "PE_TX4_DR14_N")
	)
	(segment
		(start 6.992366 -162.386772)
		(end 7.220966 -162.615372)
		(width 0.1651)
		(layer "In5.Cu")
		(net "PE_TX4_DR14_N")
	)
	(segment
		(start 34.638234 -21.791422)
		(end 33.55721 -20.247356)
		(width 0.1651)
		(layer "In5.Cu")
		(net "PE_TX4_DR14_N")
	)
	(segment
		(start 26.898854 -16.787368)
		(end 26.67 -17.016222)
		(width 0.1651)
		(layer "In5.Cu")
		(net "PE_TX4_DR14_N")
	)
	(segment
		(start 34.649918 -22.939502)
		(end 34.802318 -22.721824)
		(width 0.1651)
		(layer "In5.Cu")
		(net "PE_TX4_DR14_N")
	)
	(segment
		(start 32.032194 -19.17954)
		(end 31.77032 -19.225768)
		(width 0.1651)
		(layer "In5.Cu")
		(net "PE_TX4_DR14_N")
	)
	(segment
		(start 7.220966 -162.615372)
		(end 7.331964 -162.615372)
		(width 0.1651)
		(layer "In5.Cu")
		(net "PE_TX4_DR14_N")
	)
	(segment
		(start 31.77032 -19.225768)
		(end 31.364682 -18.941542)
		(width 0.1651)
		(layer "In5.Cu")
		(net "PE_TX4_DR14_N")
	)
	(segment
		(start 10.575798 -160.872932)
		(end 10.529824 -160.611058)
		(width 0.1651)
		(layer "In5.Cu")
		(net "PE_TX4_DR14_N")
	)
	(segment
		(start 34.8869 -24.285194)
		(end 35.039554 -24.067262)
		(width 0.1651)
		(layer "In5.Cu")
		(net "PE_TX4_DR14_N")
	)
	(segment
		(start 30.199076 -17.896078)
		(end 28.838398 -16.943324)
		(width 0.1651)
		(layer "In5.Cu")
		(net "PE_TX4_DR14_N")
	)
	(segment
		(start 33.55721 -20.247356)
		(end 33.151572 -19.963384)
		(width 0.1651)
		(layer "In5.Cu")
		(net "PE_TX4_DR14_N")
	)
	(segment
		(start 12.53617 -158.07309)
		(end 15.588742 -140.761466)
		(width 0.1651)
		(layer "In5.Cu")
		(net "PE_TX4_DR14_N")
	)
	(segment
		(start 10.813796 -160.20542)
		(end 11.07567 -160.159192)
		(width 0.1651)
		(layer "In5.Cu")
		(net "PE_TX4_DR14_N")
	)
	(segment
		(start 32.889698 -20.009358)
		(end 32.48406 -19.725386)
		(width 0.1651)
		(layer "In5.Cu")
		(net "PE_TX4_DR14_N")
	)
	(segment
		(start 35.42792 -26.270966)
		(end 35.210242 -26.118566)
		(width 0.1651)
		(layer "In5.Cu")
		(net "PE_TX4_DR14_N")
	)
	(segment
		(start 32.437832 -19.463512)
		(end 32.032194 -19.17954)
		(width 0.1651)
		(layer "In5.Cu")
		(net "PE_TX4_DR14_N")
	)
	(segment
		(start 27.95397 -16.787368)
		(end 26.898854 -16.787368)
		(width 0.1651)
		(layer "In5.Cu")
		(net "PE_TX4_DR14_N")
	)
	(segment
		(start 31.318454 -18.679668)
		(end 30.912562 -18.395696)
		(width 0.1651)
		(layer "In5.Cu")
		(net "PE_TX4_DR14_N")
	)
	(segment
		(start 34.953448 -23.579582)
		(end 34.73577 -23.427182)
		(width 0.1651)
		(layer "In5.Cu")
		(net "PE_TX4_DR14_N")
	)
	(segment
		(start 31.364682 -18.941542)
		(end 31.318454 -18.679668)
		(width 0.1651)
		(layer "In5.Cu")
		(net "PE_TX4_DR14_N")
	)
	(segment
		(start 33.151572 -19.963384)
		(end 32.889698 -20.009358)
		(width 0.1651)
		(layer "In5.Cu")
		(net "PE_TX4_DR14_N")
	)
	(segment
		(start 32.48406 -19.725386)
		(end 32.437832 -19.463512)
		(width 0.1651)
		(layer "In5.Cu")
		(net "PE_TX4_DR14_N")
	)
	(segment
		(start 29.08046 -66.519552)
		(end 35.803332 -28.398978)
		(width 0.1651)
		(layer "In5.Cu")
		(net "PE_TX4_DR14_N")
	)
	(segment
		(start 11.07567 -160.159192)
		(end 12.53617 -158.07309)
		(width 0.1651)
		(layer "In5.Cu")
		(net "PE_TX4_DR14_N")
	)
	(segment
		(start 34.73577 -23.427182)
		(end 34.649918 -22.939502)
		(width 0.1651)
		(layer "In5.Cu")
		(net "PE_TX4_DR14_N")
	)
	(segment
		(start 8.73633 -162.367722)
		(end 10.291826 -161.27857)
		(width 0.1651)
		(layer "In5.Cu")
		(net "PE_TX4_DR14_N")
	)
	(segment
		(start 7.331964 -162.615372)
		(end 8.73633 -162.367722)
		(width 0.1651)
		(layer "In5.Cu")
		(net "PE_TX4_DR14_N")
	)
	(segment
		(start 35.803332 -28.398978)
		(end 35.42792 -26.270966)
		(width 0.1651)
		(layer "In5.Cu")
		(net "PE_TX4_DR14_N")
	)
	(segment
		(start 34.802318 -22.721824)
		(end 34.638234 -21.791422)
		(width 0.1651)
		(layer "In5.Cu")
		(net "PE_TX4_DR14_N")
	)
	(segment
		(start 18.325592 -81.877662)
		(end 29.08046 -66.519552)
		(width 0.1651)
		(layer "In5.Cu")
		(net "PE_TX4_DR14_N")
	)
	(segment
		(start 28.838398 -16.943324)
		(end 27.95397 -16.787368)
		(width 0.1651)
		(layer "In5.Cu")
		(net "PE_TX4_DR14_N")
	)
	(segment
		(start 10.529824 -160.611058)
		(end 10.813796 -160.20542)
		(width 0.1651)
		(layer "In5.Cu")
		(net "PE_TX4_DR14_N")
	)
	(segment
		(start 35.124136 -25.630886)
		(end 35.27679 -25.412954)
		(width 0.1651)
		(layer "In5.Cu")
		(net "PE_TX4_DR14_N")
	)
	(segment
		(start 22.800056 -119.20982)
		(end 23.876 -119.20982)
		(width 0.174752)
		(layer "F.Cu")
		(net "PE_TX4_DR13_P")
	)
	(segment
		(start 24.123396 -119.457216)
		(end 26.416254 -119.457216)
		(width 0.174752)
		(layer "F.Cu")
		(net "PE_TX4_DR13_P")
	)
	(segment
		(start 2.249932 -179.142136)
		(end 3.6576 -179.142136)
		(width 0.174752)
		(layer "F.Cu")
		(net "PE_TX4_DR13_P")
	)
	(segment
		(start 26.416254 -119.457216)
		(end 26.67 -119.20347)
		(width 0.174752)
		(layer "F.Cu")
		(net "PE_TX4_DR13_P")
	)
	(segment
		(start 3.6576 -179.142136)
		(end 3.85445 -178.945286)
		(width 0.174752)
		(layer "F.Cu")
		(net "PE_TX4_DR13_P")
	)
	(segment
		(start 23.876 -119.20982)
		(end 24.123396 -119.457216)
		(width 0.174752)
		(layer "F.Cu")
		(net "PE_TX4_DR13_P")
	)
	(segment
		(start 3.85445 -178.945286)
		(end 6.738112 -178.945286)
		(width 0.174752)
		(layer "F.Cu")
		(net "PE_TX4_DR13_P")
	)
	(segment
		(start 6.738112 -178.945286)
		(end 6.992366 -179.19954)
		(width 0.174752)
		(layer "F.Cu")
		(net "PE_TX4_DR13_P")
	)
	(via
		(at 6.992366 -179.19954)
		(size 0.508)
		(drill 0.254)
		(layers "F.Cu" "B.Cu")
		(net "PE_TX4_DR13_P")
	)
	(via
		(at 26.67 -119.20347)
		(size 0.508)
		(drill 0.254)
		(layers "F.Cu" "B.Cu")
		(net "PE_TX4_DR13_P")
	)
	(segment
		(start 34.368232 -124.592842)
		(end 32.24022 -121.55297)
		(width 0.1651)
		(layer "In5.Cu")
		(net "PE_TX4_DR13_P")
	)
	(segment
		(start 30.138624 -120.081802)
		(end 29.006292 -119.611648)
		(width 0.1651)
		(layer "In5.Cu")
		(net "PE_TX4_DR13_P")
	)
	(segment
		(start 7.362952 -178.97094)
		(end 15.996666 -177.44948)
		(width 0.1651)
		(layer "In5.Cu")
		(net "PE_TX4_DR13_P")
	)
	(segment
		(start 29.112464 -150.463504)
		(end 32.002984 -146.33321)
		(width 0.1651)
		(layer "In5.Cu")
		(net "PE_TX4_DR13_P")
	)
	(segment
		(start 7.220966 -178.97094)
		(end 7.362952 -178.97094)
		(width 0.1651)
		(layer "In5.Cu")
		(net "PE_TX4_DR13_P")
	)
	(segment
		(start 15.996666 -177.44948)
		(end 24.912066 -171.206922)
		(width 0.1651)
		(layer "In5.Cu")
		(net "PE_TX4_DR13_P")
	)
	(segment
		(start 29.006292 -119.611648)
		(end 27.985212 -119.431816)
		(width 0.1651)
		(layer "In5.Cu")
		(net "PE_TX4_DR13_P")
	)
	(segment
		(start 32.002984 -146.33321)
		(end 35.103054 -128.761236)
		(width 0.1651)
		(layer "In5.Cu")
		(net "PE_TX4_DR13_P")
	)
	(segment
		(start 35.103054 -128.761236)
		(end 34.368232 -124.592842)
		(width 0.1651)
		(layer "In5.Cu")
		(net "PE_TX4_DR13_P")
	)
	(segment
		(start 24.912066 -171.206922)
		(end 25.636728 -170.172126)
		(width 0.1651)
		(layer "In5.Cu")
		(net "PE_TX4_DR13_P")
	)
	(segment
		(start 32.24022 -121.55297)
		(end 30.138624 -120.081802)
		(width 0.1651)
		(layer "In5.Cu")
		(net "PE_TX4_DR13_P")
	)
	(segment
		(start 25.636728 -170.172126)
		(end 29.112464 -150.463504)
		(width 0.1651)
		(layer "In5.Cu")
		(net "PE_TX4_DR13_P")
	)
	(segment
		(start 27.985212 -119.431816)
		(end 26.898346 -119.431816)
		(width 0.1651)
		(layer "In5.Cu")
		(net "PE_TX4_DR13_P")
	)
	(segment
		(start 6.992366 -179.19954)
		(end 7.220966 -178.97094)
		(width 0.1651)
		(layer "In5.Cu")
		(net "PE_TX4_DR13_P")
	)
	(segment
		(start 26.898346 -119.431816)
		(end 26.67 -119.20347)
		(width 0.1651)
		(layer "In5.Cu")
		(net "PE_TX4_DR13_P")
	)
	(segment
		(start 6.738874 -178.640232)
		(end 6.992366 -178.38674)
		(width 0.174752)
		(layer "F.Cu")
		(net "PE_TX4_DR13_N")
	)
	(segment
		(start 26.416 -119.76227)
		(end 26.67 -120.01627)
		(width 0.174752)
		(layer "F.Cu")
		(net "PE_TX4_DR13_N")
	)
	(segment
		(start 2.249932 -178.342036)
		(end 3.657854 -178.342036)
		(width 0.174752)
		(layer "F.Cu")
		(net "PE_TX4_DR13_N")
	)
	(segment
		(start 23.88235 -120.00992)
		(end 24.13 -119.76227)
		(width 0.174752)
		(layer "F.Cu")
		(net "PE_TX4_DR13_N")
	)
	(segment
		(start 24.13 -119.76227)
		(end 26.416 -119.76227)
		(width 0.174752)
		(layer "F.Cu")
		(net "PE_TX4_DR13_N")
	)
	(segment
		(start 3.95605 -178.640232)
		(end 6.738874 -178.640232)
		(width 0.174752)
		(layer "F.Cu")
		(net "PE_TX4_DR13_N")
	)
	(segment
		(start 3.657854 -178.342036)
		(end 3.95605 -178.640232)
		(width 0.174752)
		(layer "F.Cu")
		(net "PE_TX4_DR13_N")
	)
	(segment
		(start 22.800056 -120.00992)
		(end 23.88235 -120.00992)
		(width 0.174752)
		(layer "F.Cu")
		(net "PE_TX4_DR13_N")
	)
	(via
		(at 6.992366 -178.38674)
		(size 0.508)
		(drill 0.254)
		(layers "F.Cu" "B.Cu")
		(net "PE_TX4_DR13_N")
	)
	(via
		(at 26.67 -120.01627)
		(size 0.508)
		(drill 0.254)
		(layers "F.Cu" "B.Cu")
		(net "PE_TX4_DR13_N")
	)
	(segment
		(start 31.666434 -146.193764)
		(end 34.741866 -128.761236)
		(width 0.1651)
		(layer "In5.Cu")
		(net "PE_TX4_DR13_N")
	)
	(segment
		(start 31.984696 -121.808494)
		(end 31.08579 -121.179336)
		(width 0.1651)
		(layer "In5.Cu")
		(net "PE_TX4_DR13_N")
	)
	(segment
		(start 14.634718 -177.137568)
		(end 14.852396 -177.289968)
		(width 0.1651)
		(layer "In5.Cu")
		(net "PE_TX4_DR13_N")
	)
	(segment
		(start 23.583392 -171.473368)
		(end 23.98903 -171.189396)
		(width 0.1651)
		(layer "In5.Cu")
		(net "PE_TX4_DR13_N")
	)
	(segment
		(start 31.08579 -121.179336)
		(end 30.82417 -121.22531)
		(width 0.1651)
		(layer "In5.Cu")
		(net "PE_TX4_DR13_N")
	)
	(segment
		(start 15.85722 -177.11293)
		(end 16.419576 -176.71923)
		(width 0.1651)
		(layer "In5.Cu")
		(net "PE_TX4_DR13_N")
	)
	(segment
		(start 30.82417 -121.22531)
		(end 30.418278 -120.941338)
		(width 0.1651)
		(layer "In5.Cu")
		(net "PE_TX4_DR13_N")
	)
	(segment
		(start 22.417786 -172.519086)
		(end 22.464014 -172.257212)
		(width 0.1651)
		(layer "In5.Cu")
		(net "PE_TX4_DR13_N")
	)
	(segment
		(start 28.905454 -119.955056)
		(end 27.95397 -119.787416)
		(width 0.1651)
		(layer "In5.Cu")
		(net "PE_TX4_DR13_N")
	)
	(segment
		(start 23.131526 -172.019214)
		(end 23.537164 -171.735242)
		(width 0.1651)
		(layer "In5.Cu")
		(net "PE_TX4_DR13_N")
	)
	(segment
		(start 24.250904 -171.235624)
		(end 24.656542 -170.951398)
		(width 0.1651)
		(layer "In5.Cu")
		(net "PE_TX4_DR13_N")
	)
	(segment
		(start 14.852396 -177.289968)
		(end 15.85722 -177.11293)
		(width 0.1651)
		(layer "In5.Cu")
		(net "PE_TX4_DR13_N")
	)
	(segment
		(start 17.584928 -175.673766)
		(end 17.990566 -175.38954)
		(width 0.1651)
		(layer "In5.Cu")
		(net "PE_TX4_DR13_N")
	)
	(segment
		(start 25.300178 -170.03268)
		(end 28.775914 -150.324058)
		(width 0.1651)
		(layer "In5.Cu")
		(net "PE_TX4_DR13_N")
	)
	(segment
		(start 17.133062 -176.219612)
		(end 17.5387 -175.935386)
		(width 0.1651)
		(layer "In5.Cu")
		(net "PE_TX4_DR13_N")
	)
	(segment
		(start 23.537164 -171.735242)
		(end 23.583392 -171.473368)
		(width 0.1651)
		(layer "In5.Cu")
		(net "PE_TX4_DR13_N")
	)
	(segment
		(start 7.33171 -178.61534)
		(end 12.648692 -177.678334)
		(width 0.1651)
		(layer "In5.Cu")
		(net "PE_TX4_DR13_N")
	)
	(segment
		(start 7.220966 -178.61534)
		(end 7.33171 -178.61534)
		(width 0.1651)
		(layer "In5.Cu")
		(net "PE_TX4_DR13_N")
	)
	(segment
		(start 17.5387 -175.935386)
		(end 17.584928 -175.673766)
		(width 0.1651)
		(layer "In5.Cu")
		(net "PE_TX4_DR13_N")
	)
	(segment
		(start 22.464014 -172.257212)
		(end 22.869652 -171.97324)
		(width 0.1651)
		(layer "In5.Cu")
		(net "PE_TX4_DR13_N")
	)
	(segment
		(start 17.990566 -175.38954)
		(end 18.252186 -175.435768)
		(width 0.1651)
		(layer "In5.Cu")
		(net "PE_TX4_DR13_N")
	)
	(segment
		(start 24.656542 -170.951398)
		(end 25.300178 -170.03268)
		(width 0.1651)
		(layer "In5.Cu")
		(net "PE_TX4_DR13_N")
	)
	(segment
		(start 13.994384 -177.441098)
		(end 14.147038 -177.22342)
		(width 0.1651)
		(layer "In5.Cu")
		(net "PE_TX4_DR13_N")
	)
	(segment
		(start 18.252186 -175.435768)
		(end 22.417532 -172.519086)
		(width 0.1651)
		(layer "In5.Cu")
		(net "PE_TX4_DR13_N")
	)
	(segment
		(start 16.871442 -176.173384)
		(end 17.133062 -176.219612)
		(width 0.1651)
		(layer "In5.Cu")
		(net "PE_TX4_DR13_N")
	)
	(segment
		(start 13.506704 -177.52695)
		(end 13.994384 -177.441098)
		(width 0.1651)
		(layer "In5.Cu")
		(net "PE_TX4_DR13_N")
	)
	(segment
		(start 16.419576 -176.71923)
		(end 16.46555 -176.457356)
		(width 0.1651)
		(layer "In5.Cu")
		(net "PE_TX4_DR13_N")
	)
	(segment
		(start 34.741866 -128.761236)
		(end 34.031682 -124.732288)
		(width 0.1651)
		(layer "In5.Cu")
		(net "PE_TX4_DR13_N")
	)
	(segment
		(start 30.37205 -120.679464)
		(end 29.966412 -120.395492)
		(width 0.1651)
		(layer "In5.Cu")
		(net "PE_TX4_DR13_N")
	)
	(segment
		(start 22.869652 -171.97324)
		(end 23.131526 -172.019214)
		(width 0.1651)
		(layer "In5.Cu")
		(net "PE_TX4_DR13_N")
	)
	(segment
		(start 13.288772 -177.37455)
		(end 13.506704 -177.52695)
		(width 0.1651)
		(layer "In5.Cu")
		(net "PE_TX4_DR13_N")
	)
	(segment
		(start 34.031682 -124.732288)
		(end 31.984696 -121.808494)
		(width 0.1651)
		(layer "In5.Cu")
		(net "PE_TX4_DR13_N")
	)
	(segment
		(start 14.147038 -177.22342)
		(end 14.634718 -177.137568)
		(width 0.1651)
		(layer "In5.Cu")
		(net "PE_TX4_DR13_N")
	)
	(segment
		(start 22.417532 -172.519086)
		(end 22.417786 -172.519086)
		(width 0.1651)
		(layer "In5.Cu")
		(net "PE_TX4_DR13_N")
	)
	(segment
		(start 12.648692 -177.678334)
		(end 12.801092 -177.460656)
		(width 0.1651)
		(layer "In5.Cu")
		(net "PE_TX4_DR13_N")
	)
	(segment
		(start 30.418278 -120.941338)
		(end 30.37205 -120.679464)
		(width 0.1651)
		(layer "In5.Cu")
		(net "PE_TX4_DR13_N")
	)
	(segment
		(start 29.966412 -120.395492)
		(end 28.905454 -119.955056)
		(width 0.1651)
		(layer "In5.Cu")
		(net "PE_TX4_DR13_N")
	)
	(segment
		(start 27.95397 -119.787416)
		(end 26.898854 -119.787416)
		(width 0.1651)
		(layer "In5.Cu")
		(net "PE_TX4_DR13_N")
	)
	(segment
		(start 6.992366 -178.38674)
		(end 7.220966 -178.61534)
		(width 0.1651)
		(layer "In5.Cu")
		(net "PE_TX4_DR13_N")
	)
	(segment
		(start 16.46555 -176.457356)
		(end 16.871442 -176.173384)
		(width 0.1651)
		(layer "In5.Cu")
		(net "PE_TX4_DR13_N")
	)
	(segment
		(start 28.775914 -150.324058)
		(end 31.666434 -146.193764)
		(width 0.1651)
		(layer "In5.Cu")
		(net "PE_TX4_DR13_N")
	)
	(segment
		(start 26.898854 -119.787416)
		(end 26.67 -120.01627)
		(width 0.1651)
		(layer "In5.Cu")
		(net "PE_TX4_DR13_N")
	)
	(segment
		(start 12.801092 -177.460656)
		(end 13.288772 -177.37455)
		(width 0.1651)
		(layer "In5.Cu")
		(net "PE_TX4_DR13_N")
	)
	(segment
		(start 23.98903 -171.189396)
		(end 24.250904 -171.235624)
		(width 0.1651)
		(layer "In5.Cu")
		(net "PE_TX4_DR13_N")
	)
	(segment
		(start 2.249932 -224.741994)
		(end 3.619754 -224.741994)
		(width 0.174752)
		(layer "F.Cu")
		(net "PE_TX4_DR12_P")
	)
	(segment
		(start 3.905504 -224.456244)
		(end 6.738112 -224.456244)
		(width 0.174752)
		(layer "F.Cu")
		(net "PE_TX4_DR12_P")
	)
	(segment
		(start 22.800056 -222.209868)
		(end 23.835868 -222.209868)
		(width 0.174752)
		(layer "F.Cu")
		(net "PE_TX4_DR12_P")
	)
	(segment
		(start 3.619754 -224.741994)
		(end 3.905504 -224.456244)
		(width 0.174752)
		(layer "F.Cu")
		(net "PE_TX4_DR12_P")
	)
	(segment
		(start 24.083264 -222.457264)
		(end 26.416254 -222.457264)
		(width 0.174752)
		(layer "F.Cu")
		(net "PE_TX4_DR12_P")
	)
	(segment
		(start 6.738112 -224.456244)
		(end 6.992366 -224.710498)
		(width 0.174752)
		(layer "F.Cu")
		(net "PE_TX4_DR12_P")
	)
	(segment
		(start 26.416254 -222.457264)
		(end 26.67 -222.203518)
		(width 0.174752)
		(layer "F.Cu")
		(net "PE_TX4_DR12_P")
	)
	(segment
		(start 23.835868 -222.209868)
		(end 24.083264 -222.457264)
		(width 0.174752)
		(layer "F.Cu")
		(net "PE_TX4_DR12_P")
	)
	(via
		(at 6.992366 -224.710498)
		(size 0.508)
		(drill 0.254)
		(layers "F.Cu" "B.Cu")
		(net "PE_TX4_DR12_P")
	)
	(via
		(at 26.67 -222.203518)
		(size 0.508)
		(drill 0.254)
		(layers "F.Cu" "B.Cu")
		(net "PE_TX4_DR12_P")
	)
	(segment
		(start 39.801546 -213.588854)
		(end 39.51732 -213.994492)
		(width 0.1651)
		(layer "In5.Cu")
		(net "PE_TX4_DR12_P")
	)
	(segment
		(start 37.949632 -216.233248)
		(end 32.94253 -219.73921)
		(width 0.1651)
		(layer "In5.Cu")
		(net "PE_TX4_DR12_P")
	)
	(segment
		(start 41.453054 -207.59928)
		(end 41.718484 -209.105754)
		(width 0.1651)
		(layer "In5.Cu")
		(net "PE_TX4_DR12_P")
	)
	(segment
		(start 32.94253 -219.73921)
		(end 32.68091 -219.692982)
		(width 0.1651)
		(layer "In5.Cu")
		(net "PE_TX4_DR12_P")
	)
	(segment
		(start 39.51732 -213.994492)
		(end 39.255446 -214.04072)
		(width 0.1651)
		(layer "In5.Cu")
		(net "PE_TX4_DR12_P")
	)
	(segment
		(start 25.5397 -201.841354)
		(end 37.144198 -203.890118)
		(width 0.1651)
		(layer "In5.Cu")
		(net "PE_TX4_DR12_P")
	)
	(segment
		(start 40.03929 -212.921342)
		(end 39.755318 -213.32698)
		(width 0.1651)
		(layer "In5.Cu")
		(net "PE_TX4_DR12_P")
	)
	(segment
		(start 40.503856 -206.243682)
		(end 41.453054 -207.59928)
		(width 0.1651)
		(layer "In5.Cu")
		(net "PE_TX4_DR12_P")
	)
	(segment
		(start 26.898346 -222.431864)
		(end 26.67 -222.203518)
		(width 0.1651)
		(layer "In5.Cu")
		(net "PE_TX4_DR12_P")
	)
	(segment
		(start 31.561532 -220.476826)
		(end 31.15564 -220.760798)
		(width 0.1651)
		(layer "In5.Cu")
		(net "PE_TX4_DR12_P")
	)
	(segment
		(start 39.384478 -205.459584)
		(end 39.430706 -205.721458)
		(width 0.1651)
		(layer "In5.Cu")
		(net "PE_TX4_DR12_P")
	)
	(segment
		(start 14.290294 -219.782136)
		(end 16.335756 -208.171796)
		(width 0.1651)
		(layer "In5.Cu")
		(net "PE_TX4_DR12_P")
	)
	(segment
		(start 32.275018 -219.976954)
		(end 32.229044 -220.238828)
		(width 0.1651)
		(layer "In5.Cu")
		(net "PE_TX4_DR12_P")
	)
	(segment
		(start 29.453586 -222.182182)
		(end 28.037536 -222.431864)
		(width 0.1651)
		(layer "In5.Cu")
		(net "PE_TX4_DR12_P")
	)
	(segment
		(start 41.307258 -211.43849)
		(end 40.301164 -212.875114)
		(width 0.1651)
		(layer "In5.Cu")
		(net "PE_TX4_DR12_P")
	)
	(segment
		(start 38.471602 -215.160098)
		(end 38.18763 -215.565736)
		(width 0.1651)
		(layer "In5.Cu")
		(net "PE_TX4_DR12_P")
	)
	(segment
		(start 6.992366 -224.710498)
		(end 7.220966 -224.481898)
		(width 0.1651)
		(layer "In5.Cu")
		(net "PE_TX4_DR12_P")
	)
	(segment
		(start 28.037536 -222.431864)
		(end 26.898346 -222.431864)
		(width 0.1651)
		(layer "In5.Cu")
		(net "PE_TX4_DR12_P")
	)
	(segment
		(start 32.68091 -219.692982)
		(end 32.275018 -219.976954)
		(width 0.1651)
		(layer "In5.Cu")
		(net "PE_TX4_DR12_P")
	)
	(segment
		(start 16.335756 -208.171796)
		(end 19.804126 -203.217272)
		(width 0.1651)
		(layer "In5.Cu")
		(net "PE_TX4_DR12_P")
	)
	(segment
		(start 9.63295 -224.138236)
		(end 12.797028 -221.918276)
		(width 0.1651)
		(layer "In5.Cu")
		(net "PE_TX4_DR12_P")
	)
	(segment
		(start 37.144198 -203.890118)
		(end 39.384478 -205.459584)
		(width 0.1651)
		(layer "In5.Cu")
		(net "PE_TX4_DR12_P")
	)
	(segment
		(start 32.229044 -220.238828)
		(end 31.823152 -220.5228)
		(width 0.1651)
		(layer "In5.Cu")
		(net "PE_TX4_DR12_P")
	)
	(segment
		(start 19.804126 -203.217272)
		(end 20.498816 -202.730608)
		(width 0.1651)
		(layer "In5.Cu")
		(net "PE_TX4_DR12_P")
	)
	(segment
		(start 29.990034 -221.806516)
		(end 29.453586 -222.182182)
		(width 0.1651)
		(layer "In5.Cu")
		(net "PE_TX4_DR12_P")
	)
	(segment
		(start 7.220966 -224.481898)
		(end 7.682484 -224.481898)
		(width 0.1651)
		(layer "In5.Cu")
		(net "PE_TX4_DR12_P")
	)
	(segment
		(start 38.733476 -215.11387)
		(end 38.471602 -215.160098)
		(width 0.1651)
		(layer "In5.Cu")
		(net "PE_TX4_DR12_P")
	)
	(segment
		(start 38.233858 -215.82761)
		(end 37.949632 -216.233248)
		(width 0.1651)
		(layer "In5.Cu")
		(net "PE_TX4_DR12_P")
	)
	(segment
		(start 31.823152 -220.5228)
		(end 31.561532 -220.476826)
		(width 0.1651)
		(layer "In5.Cu")
		(net "PE_TX4_DR12_P")
	)
	(segment
		(start 39.255446 -214.04072)
		(end 38.971474 -214.446358)
		(width 0.1651)
		(layer "In5.Cu")
		(net "PE_TX4_DR12_P")
	)
	(segment
		(start 30.036262 -221.544642)
		(end 29.990034 -221.806516)
		(width 0.1651)
		(layer "In5.Cu")
		(net "PE_TX4_DR12_P")
	)
	(segment
		(start 12.933934 -221.813882)
		(end 12.97051 -221.761558)
		(width 0.1651)
		(layer "In5.Cu")
		(net "PE_TX4_DR12_P")
	)
	(segment
		(start 31.109412 -221.022672)
		(end 30.703774 -221.306644)
		(width 0.1651)
		(layer "In5.Cu")
		(net "PE_TX4_DR12_P")
	)
	(segment
		(start 30.703774 -221.306644)
		(end 30.4419 -221.260416)
		(width 0.1651)
		(layer "In5.Cu")
		(net "PE_TX4_DR12_P")
	)
	(segment
		(start 38.971474 -214.446358)
		(end 39.017702 -214.708232)
		(width 0.1651)
		(layer "In5.Cu")
		(net "PE_TX4_DR12_P")
	)
	(segment
		(start 41.718484 -209.105754)
		(end 41.307258 -211.43849)
		(width 0.1651)
		(layer "In5.Cu")
		(net "PE_TX4_DR12_P")
	)
	(segment
		(start 39.017702 -214.708232)
		(end 38.733476 -215.11387)
		(width 0.1651)
		(layer "In5.Cu")
		(net "PE_TX4_DR12_P")
	)
	(segment
		(start 12.800838 -221.915482)
		(end 12.933934 -221.813882)
		(width 0.1651)
		(layer "In5.Cu")
		(net "PE_TX4_DR12_P")
	)
	(segment
		(start 39.755318 -213.32698)
		(end 39.801546 -213.588854)
		(width 0.1651)
		(layer "In5.Cu")
		(net "PE_TX4_DR12_P")
	)
	(segment
		(start 7.682484 -224.481898)
		(end 9.63295 -224.138236)
		(width 0.1651)
		(layer "In5.Cu")
		(net "PE_TX4_DR12_P")
	)
	(segment
		(start 38.18763 -215.565736)
		(end 38.233858 -215.82761)
		(width 0.1651)
		(layer "In5.Cu")
		(net "PE_TX4_DR12_P")
	)
	(segment
		(start 40.098218 -205.959456)
		(end 40.503856 -206.243682)
		(width 0.1651)
		(layer "In5.Cu")
		(net "PE_TX4_DR12_P")
	)
	(segment
		(start 12.797028 -221.918276)
		(end 12.800838 -221.915482)
		(width 0.1651)
		(layer "In5.Cu")
		(net "PE_TX4_DR12_P")
	)
	(segment
		(start 40.301164 -212.875114)
		(end 40.03929 -212.921342)
		(width 0.1651)
		(layer "In5.Cu")
		(net "PE_TX4_DR12_P")
	)
	(segment
		(start 39.430706 -205.721458)
		(end 39.836344 -206.005684)
		(width 0.1651)
		(layer "In5.Cu")
		(net "PE_TX4_DR12_P")
	)
	(segment
		(start 31.15564 -220.760798)
		(end 31.109412 -221.022672)
		(width 0.1651)
		(layer "In5.Cu")
		(net "PE_TX4_DR12_P")
	)
	(segment
		(start 39.836344 -206.005684)
		(end 40.098218 -205.959456)
		(width 0.1651)
		(layer "In5.Cu")
		(net "PE_TX4_DR12_P")
	)
	(segment
		(start 30.4419 -221.260416)
		(end 30.036262 -221.544642)
		(width 0.1651)
		(layer "In5.Cu")
		(net "PE_TX4_DR12_P")
	)
	(segment
		(start 20.498816 -202.730608)
		(end 25.5397 -201.841354)
		(width 0.1651)
		(layer "In5.Cu")
		(net "PE_TX4_DR12_P")
	)
	(segment
		(start 12.97051 -221.761558)
		(end 14.290294 -219.782136)
		(width 0.1651)
		(layer "In5.Cu")
		(net "PE_TX4_DR12_P")
	)
	(segment
		(start 3.905504 -224.15119)
		(end 6.738874 -224.15119)
		(width 0.174752)
		(layer "F.Cu")
		(net "PE_TX4_DR12_N")
	)
	(segment
		(start 22.800056 -223.009968)
		(end 23.876 -223.009968)
		(width 0.174752)
		(layer "F.Cu")
		(net "PE_TX4_DR12_N")
	)
	(segment
		(start 2.249932 -223.942148)
		(end 3.696462 -223.942148)
		(width 0.174752)
		(layer "F.Cu")
		(net "PE_TX4_DR12_N")
	)
	(segment
		(start 23.876 -223.009968)
		(end 24.12365 -222.762318)
		(width 0.174752)
		(layer "F.Cu")
		(net "PE_TX4_DR12_N")
	)
	(segment
		(start 24.12365 -222.762318)
		(end 26.416 -222.762318)
		(width 0.174752)
		(layer "F.Cu")
		(net "PE_TX4_DR12_N")
	)
	(segment
		(start 26.416 -222.762318)
		(end 26.67 -223.016318)
		(width 0.174752)
		(layer "F.Cu")
		(net "PE_TX4_DR12_N")
	)
	(segment
		(start 3.696462 -223.942148)
		(end 3.905504 -224.15119)
		(width 0.174752)
		(layer "F.Cu")
		(net "PE_TX4_DR12_N")
	)
	(segment
		(start 6.738874 -224.15119)
		(end 6.992366 -223.897698)
		(width 0.174752)
		(layer "F.Cu")
		(net "PE_TX4_DR12_N")
	)
	(via
		(at 26.67 -223.016318)
		(size 0.508)
		(drill 0.254)
		(layers "F.Cu" "B.Cu")
		(net "PE_TX4_DR12_N")
	)
	(via
		(at 6.992366 -223.897698)
		(size 0.508)
		(drill 0.254)
		(layers "F.Cu" "B.Cu")
		(net "PE_TX4_DR12_N")
	)
	(segment
		(start 19.548602 -202.961748)
		(end 15.999206 -208.03235)
		(width 0.1651)
		(layer "In5.Cu")
		(net "PE_TX4_DR12_N")
	)
	(segment
		(start 9.493504 -223.801686)
		(end 8.572246 -223.963992)
		(width 0.1651)
		(layer "In5.Cu")
		(net "PE_TX4_DR12_N")
	)
	(segment
		(start 40.75938 -205.988158)
		(end 37.283644 -203.553568)
		(width 0.1651)
		(layer "In5.Cu")
		(net "PE_TX4_DR12_N")
	)
	(segment
		(start 26.898854 -222.787464)
		(end 28.068778 -222.787464)
		(width 0.1651)
		(layer "In5.Cu")
		(net "PE_TX4_DR12_N")
	)
	(segment
		(start 41.643808 -211.577936)
		(end 42.079672 -209.105754)
		(width 0.1651)
		(layer "In5.Cu")
		(net "PE_TX4_DR12_N")
	)
	(segment
		(start 37.283644 -203.553568)
		(end 25.5397 -201.480166)
		(width 0.1651)
		(layer "In5.Cu")
		(net "PE_TX4_DR12_N")
	)
	(segment
		(start 12.541504 -221.663006)
		(end 9.49325 -223.801432)
		(width 0.1651)
		(layer "In5.Cu")
		(net "PE_TX4_DR12_N")
	)
	(segment
		(start 9.49325 -223.801432)
		(end 9.493504 -223.801686)
		(width 0.1651)
		(layer "In5.Cu")
		(net "PE_TX4_DR12_N")
	)
	(segment
		(start 38.205156 -216.488772)
		(end 41.643808 -211.577936)
		(width 0.1651)
		(layer "In5.Cu")
		(net "PE_TX4_DR12_N")
	)
	(segment
		(start 7.651242 -224.126298)
		(end 7.220966 -224.126298)
		(width 0.1651)
		(layer "In5.Cu")
		(net "PE_TX4_DR12_N")
	)
	(segment
		(start 29.593032 -222.518732)
		(end 38.205156 -216.488772)
		(width 0.1651)
		(layer "In5.Cu")
		(net "PE_TX4_DR12_N")
	)
	(segment
		(start 42.079672 -209.105754)
		(end 41.789604 -207.459834)
		(width 0.1651)
		(layer "In5.Cu")
		(net "PE_TX4_DR12_N")
	)
	(segment
		(start 15.999206 -208.03235)
		(end 13.952982 -219.647008)
		(width 0.1651)
		(layer "In5.Cu")
		(net "PE_TX4_DR12_N")
	)
	(segment
		(start 12.6746 -221.5642)
		(end 12.541504 -221.663006)
		(width 0.1651)
		(layer "In5.Cu")
		(net "PE_TX4_DR12_N")
	)
	(segment
		(start 13.952982 -219.647008)
		(end 12.6746 -221.5642)
		(width 0.1651)
		(layer "In5.Cu")
		(net "PE_TX4_DR12_N")
	)
	(segment
		(start 28.068778 -222.787464)
		(end 29.593032 -222.518732)
		(width 0.1651)
		(layer "In5.Cu")
		(net "PE_TX4_DR12_N")
	)
	(segment
		(start 25.5397 -201.480166)
		(end 20.35937 -202.394058)
		(width 0.1651)
		(layer "In5.Cu")
		(net "PE_TX4_DR12_N")
	)
	(segment
		(start 7.220966 -224.126298)
		(end 6.992366 -223.897698)
		(width 0.1651)
		(layer "In5.Cu")
		(net "PE_TX4_DR12_N")
	)
	(segment
		(start 26.67 -223.016318)
		(end 26.898854 -222.787464)
		(width 0.1651)
		(layer "In5.Cu")
		(net "PE_TX4_DR12_N")
	)
	(segment
		(start 8.572246 -223.963992)
		(end 7.651242 -224.126298)
		(width 0.1651)
		(layer "In5.Cu")
		(net "PE_TX4_DR12_N")
	)
	(segment
		(start 20.35937 -202.394058)
		(end 19.548602 -202.961748)
		(width 0.1651)
		(layer "In5.Cu")
		(net "PE_TX4_DR12_N")
	)
	(segment
		(start 41.789604 -207.459834)
		(end 40.75938 -205.988158)
		(width 0.1651)
		(layer "In5.Cu")
		(net "PE_TX4_DR12_N")
	)
	(segment
		(start 24.123396 -325.457312)
		(end 26.416254 -325.457312)
		(width 0.174752)
		(layer "F.Cu")
		(net "PE_TX4_DR11_P")
	)
	(segment
		(start 3.85445 -344.145362)
		(end 6.738112 -344.145362)
		(width 0.174752)
		(layer "F.Cu")
		(net "PE_TX4_DR11_P")
	)
	(segment
		(start 2.249932 -344.342212)
		(end 3.6576 -344.342212)
		(width 0.174752)
		(layer "F.Cu")
		(net "PE_TX4_DR11_P")
	)
	(segment
		(start 6.738112 -344.145362)
		(end 6.992366 -344.399616)
		(width 0.174752)
		(layer "F.Cu")
		(net "PE_TX4_DR11_P")
	)
	(segment
		(start 23.876 -325.209916)
		(end 24.123396 -325.457312)
		(width 0.174752)
		(layer "F.Cu")
		(net "PE_TX4_DR11_P")
	)
	(segment
		(start 3.6576 -344.342212)
		(end 3.85445 -344.145362)
		(width 0.174752)
		(layer "F.Cu")
		(net "PE_TX4_DR11_P")
	)
	(segment
		(start 22.800056 -325.209916)
		(end 23.876 -325.209916)
		(width 0.174752)
		(layer "F.Cu")
		(net "PE_TX4_DR11_P")
	)
	(segment
		(start 26.416254 -325.457312)
		(end 26.67 -325.203566)
		(width 0.174752)
		(layer "F.Cu")
		(net "PE_TX4_DR11_P")
	)
	(via
		(at 26.67 -325.203566)
		(size 0.508)
		(drill 0.254)
		(layers "F.Cu" "B.Cu")
		(net "PE_TX4_DR11_P")
	)
	(via
		(at 6.992366 -344.399616)
		(size 0.508)
		(drill 0.254)
		(layers "F.Cu" "B.Cu")
		(net "PE_TX4_DR11_P")
	)
	(segment
		(start 27.8638 -325.416418)
		(end 27.815286 -325.431912)
		(width 0.1651)
		(layer "In5.Cu")
		(net "PE_TX4_DR11_P")
	)
	(segment
		(start 29.349446 -325.67245)
		(end 27.8638 -325.416418)
		(width 0.1651)
		(layer "In5.Cu")
		(net "PE_TX4_DR11_P")
	)
	(segment
		(start 30.997398 -352.426524)
		(end 31.701232 -351.420176)
		(width 0.1651)
		(layer "In5.Cu")
		(net "PE_TX4_DR11_P")
	)
	(segment
		(start 31.047436 -340.798404)
		(end 32.425386 -332.980538)
		(width 0.1651)
		(layer "In5.Cu")
		(net "PE_TX4_DR11_P")
	)
	(segment
		(start 27.815286 -325.431912)
		(end 26.898346 -325.431912)
		(width 0.1651)
		(layer "In5.Cu")
		(net "PE_TX4_DR11_P")
	)
	(segment
		(start 32.425386 -332.980538)
		(end 31.66745 -328.682096)
		(width 0.1651)
		(layer "In5.Cu")
		(net "PE_TX4_DR11_P")
	)
	(segment
		(start 18.798794 -359.353866)
		(end 21.880068 -358.810306)
		(width 0.1651)
		(layer "In5.Cu")
		(net "PE_TX4_DR11_P")
	)
	(segment
		(start 32.311086 -347.965268)
		(end 31.047436 -340.798404)
		(width 0.1651)
		(layer "In5.Cu")
		(net "PE_TX4_DR11_P")
	)
	(segment
		(start 9.555734 -344.979244)
		(end 14.749272 -352.396298)
		(width 0.1651)
		(layer "In5.Cu")
		(net "PE_TX4_DR11_P")
	)
	(segment
		(start 7.220966 -344.171016)
		(end 7.876794 -344.171016)
		(width 0.1651)
		(layer "In5.Cu")
		(net "PE_TX4_DR11_P")
	)
	(segment
		(start 26.898346 -325.431912)
		(end 26.67 -325.203566)
		(width 0.1651)
		(layer "In5.Cu")
		(net "PE_TX4_DR11_P")
	)
	(segment
		(start 16.68145 -358.654096)
		(end 17.304004 -359.089198)
		(width 0.1651)
		(layer "In5.Cu")
		(net "PE_TX4_DR11_P")
	)
	(segment
		(start 14.749272 -352.396298)
		(end 14.749526 -352.396298)
		(width 0.1651)
		(layer "In5.Cu")
		(net "PE_TX4_DR11_P")
	)
	(segment
		(start 21.880068 -358.810306)
		(end 30.997398 -352.426524)
		(width 0.1651)
		(layer "In5.Cu")
		(net "PE_TX4_DR11_P")
	)
	(segment
		(start 14.749526 -352.396298)
		(end 15.574518 -357.071168)
		(width 0.1651)
		(layer "In5.Cu")
		(net "PE_TX4_DR11_P")
	)
	(segment
		(start 7.876794 -344.171016)
		(end 8.578596 -344.294714)
		(width 0.1651)
		(layer "In5.Cu")
		(net "PE_TX4_DR11_P")
	)
	(segment
		(start 31.700978 -351.419922)
		(end 32.311086 -347.965268)
		(width 0.1651)
		(layer "In5.Cu")
		(net "PE_TX4_DR11_P")
	)
	(segment
		(start 15.574518 -357.071168)
		(end 16.68145 -358.654096)
		(width 0.1651)
		(layer "In5.Cu")
		(net "PE_TX4_DR11_P")
	)
	(segment
		(start 8.578596 -344.294714)
		(end 9.555734 -344.979244)
		(width 0.1651)
		(layer "In5.Cu")
		(net "PE_TX4_DR11_P")
	)
	(segment
		(start 29.764228 -325.962772)
		(end 29.349446 -325.67245)
		(width 0.1651)
		(layer "In5.Cu")
		(net "PE_TX4_DR11_P")
	)
	(segment
		(start 31.66745 -328.682096)
		(end 29.764228 -325.962772)
		(width 0.1651)
		(layer "In5.Cu")
		(net "PE_TX4_DR11_P")
	)
	(segment
		(start 6.992366 -344.399616)
		(end 7.220966 -344.171016)
		(width 0.1651)
		(layer "In5.Cu")
		(net "PE_TX4_DR11_P")
	)
	(segment
		(start 31.701232 -351.420176)
		(end 31.700978 -351.419922)
		(width 0.1651)
		(layer "In5.Cu")
		(net "PE_TX4_DR11_P")
	)
	(segment
		(start 17.304004 -359.089198)
		(end 18.798794 -359.353866)
		(width 0.1651)
		(layer "In5.Cu")
		(net "PE_TX4_DR11_P")
	)
	(segment
		(start 23.88235 -326.010016)
		(end 24.13 -325.762366)
		(width 0.174752)
		(layer "F.Cu")
		(net "PE_TX4_DR11_N")
	)
	(segment
		(start 24.13 -325.762366)
		(end 26.416 -325.762366)
		(width 0.174752)
		(layer "F.Cu")
		(net "PE_TX4_DR11_N")
	)
	(segment
		(start 3.95605 -343.840308)
		(end 6.738874 -343.840308)
		(width 0.174752)
		(layer "F.Cu")
		(net "PE_TX4_DR11_N")
	)
	(segment
		(start 26.416 -325.762366)
		(end 26.67 -326.016366)
		(width 0.174752)
		(layer "F.Cu")
		(net "PE_TX4_DR11_N")
	)
	(segment
		(start 3.657854 -343.542112)
		(end 3.95605 -343.840308)
		(width 0.174752)
		(layer "F.Cu")
		(net "PE_TX4_DR11_N")
	)
	(segment
		(start 22.800056 -326.010016)
		(end 23.88235 -326.010016)
		(width 0.174752)
		(layer "F.Cu")
		(net "PE_TX4_DR11_N")
	)
	(segment
		(start 6.738874 -343.840308)
		(end 6.992366 -343.586816)
		(width 0.174752)
		(layer "F.Cu")
		(net "PE_TX4_DR11_N")
	)
	(segment
		(start 2.249932 -343.542112)
		(end 3.657854 -343.542112)
		(width 0.174752)
		(layer "F.Cu")
		(net "PE_TX4_DR11_N")
	)
	(via
		(at 26.67 -326.016366)
		(size 0.508)
		(drill 0.254)
		(layers "F.Cu" "B.Cu")
		(net "PE_TX4_DR11_N")
	)
	(via
		(at 6.992366 -343.586816)
		(size 0.508)
		(drill 0.254)
		(layers "F.Cu" "B.Cu")
		(net "PE_TX4_DR11_N")
	)
	(segment
		(start 31.589726 -330.2889)
		(end 31.589472 -330.2889)
		(width 0.1651)
		(layer "In5.Cu")
		(net "PE_TX4_DR11_N")
	)
	(segment
		(start 27.870912 -325.787512)
		(end 26.898854 -325.787512)
		(width 0.1651)
		(layer "In5.Cu")
		(net "PE_TX4_DR11_N")
	)
	(segment
		(start 31.949898 -347.965268)
		(end 30.686248 -340.798404)
		(width 0.1651)
		(layer "In5.Cu")
		(net "PE_TX4_DR11_N")
	)
	(segment
		(start 31.760414 -332.340204)
		(end 31.674562 -331.852524)
		(width 0.1651)
		(layer "In5.Cu")
		(net "PE_TX4_DR11_N")
	)
	(segment
		(start 10.879074 -346.248736)
		(end 11.140948 -346.294964)
		(width 0.1651)
		(layer "In5.Cu")
		(net "PE_TX4_DR11_N")
	)
	(segment
		(start 32.064198 -332.980538)
		(end 31.978092 -332.492858)
		(width 0.1651)
		(layer "In5.Cu")
		(net "PE_TX4_DR11_N")
	)
	(segment
		(start 15.074392 -352.189796)
		(end 15.673578 -355.58603)
		(width 0.1651)
		(layer "In5.Cu")
		(net "PE_TX4_DR11_N")
	)
	(segment
		(start 8.718042 -343.958164)
		(end 9.811258 -344.72372)
		(width 0.1651)
		(layer "In5.Cu")
		(net "PE_TX4_DR11_N")
	)
	(segment
		(start 16.936974 -358.398572)
		(end 17.44345 -358.752648)
		(width 0.1651)
		(layer "In5.Cu")
		(net "PE_TX4_DR11_N")
	)
	(segment
		(start 31.740856 -331.146912)
		(end 31.523178 -330.994512)
		(width 0.1651)
		(layer "In5.Cu")
		(net "PE_TX4_DR11_N")
	)
	(segment
		(start 12.16279 -348.081854)
		(end 15.00505 -352.141028)
		(width 0.1651)
		(layer "In5.Cu")
		(net "PE_TX4_DR11_N")
	)
	(segment
		(start 21.740622 -358.473756)
		(end 30.741874 -352.171254)
		(width 0.1651)
		(layer "In5.Cu")
		(net "PE_TX4_DR11_N")
	)
	(segment
		(start 29.508704 -326.218296)
		(end 29.210508 -326.009508)
		(width 0.1651)
		(layer "In5.Cu")
		(net "PE_TX4_DR11_N")
	)
	(segment
		(start 11.378946 -346.962476)
		(end 11.662918 -347.368114)
		(width 0.1651)
		(layer "In5.Cu")
		(net "PE_TX4_DR11_N")
	)
	(segment
		(start 15.89151 -355.73843)
		(end 15.977616 -356.22611)
		(width 0.1651)
		(layer "In5.Cu")
		(net "PE_TX4_DR11_N")
	)
	(segment
		(start 30.54731 -327.70191)
		(end 29.508704 -326.218296)
		(width 0.1651)
		(layer "In5.Cu")
		(net "PE_TX4_DR11_N")
	)
	(segment
		(start 15.977616 -356.22611)
		(end 15.825216 -356.444042)
		(width 0.1651)
		(layer "In5.Cu")
		(net "PE_TX4_DR11_N")
	)
	(segment
		(start 11.662918 -347.368114)
		(end 11.924792 -347.414342)
		(width 0.1651)
		(layer "In5.Cu")
		(net "PE_TX4_DR11_N")
	)
	(segment
		(start 30.741874 -352.171254)
		(end 31.364428 -351.28073)
		(width 0.1651)
		(layer "In5.Cu")
		(net "PE_TX4_DR11_N")
	)
	(segment
		(start 15.00505 -352.141028)
		(end 15.074392 -352.189796)
		(width 0.1651)
		(layer "In5.Cu")
		(net "PE_TX4_DR11_N")
	)
	(segment
		(start 10.095484 -345.129358)
		(end 10.357104 -345.175586)
		(width 0.1651)
		(layer "In5.Cu")
		(net "PE_TX4_DR11_N")
	)
	(segment
		(start 17.44345 -358.752648)
		(end 18.798794 -358.992678)
		(width 0.1651)
		(layer "In5.Cu")
		(net "PE_TX4_DR11_N")
	)
	(segment
		(start 11.425174 -346.700602)
		(end 11.378946 -346.962476)
		(width 0.1651)
		(layer "In5.Cu")
		(net "PE_TX4_DR11_N")
	)
	(segment
		(start 6.992366 -343.586816)
		(end 7.220966 -343.815416)
		(width 0.1651)
		(layer "In5.Cu")
		(net "PE_TX4_DR11_N")
	)
	(segment
		(start 10.64133 -345.581224)
		(end 10.595102 -345.843098)
		(width 0.1651)
		(layer "In5.Cu")
		(net "PE_TX4_DR11_N")
	)
	(segment
		(start 29.210508 -326.009508)
		(end 27.8892 -325.78167)
		(width 0.1651)
		(layer "In5.Cu")
		(net "PE_TX4_DR11_N")
	)
	(segment
		(start 15.825216 -356.444042)
		(end 15.911322 -356.931722)
		(width 0.1651)
		(layer "In5.Cu")
		(net "PE_TX4_DR11_N")
	)
	(segment
		(start 31.437326 -330.506832)
		(end 31.589726 -330.2889)
		(width 0.1651)
		(layer "In5.Cu")
		(net "PE_TX4_DR11_N")
	)
	(segment
		(start 27.8892 -325.78167)
		(end 27.870912 -325.787512)
		(width 0.1651)
		(layer "In5.Cu")
		(net "PE_TX4_DR11_N")
	)
	(segment
		(start 7.220966 -343.815416)
		(end 7.908036 -343.815416)
		(width 0.1651)
		(layer "In5.Cu")
		(net "PE_TX4_DR11_N")
	)
	(segment
		(start 31.589472 -330.2889)
		(end 31.3309 -328.821542)
		(width 0.1651)
		(layer "In5.Cu")
		(net "PE_TX4_DR11_N")
	)
	(segment
		(start 30.501082 -327.963784)
		(end 30.54731 -327.70191)
		(width 0.1651)
		(layer "In5.Cu")
		(net "PE_TX4_DR11_N")
	)
	(segment
		(start 10.595102 -345.843098)
		(end 10.879074 -346.248736)
		(width 0.1651)
		(layer "In5.Cu")
		(net "PE_TX4_DR11_N")
	)
	(segment
		(start 31.674562 -331.852524)
		(end 31.826962 -331.634846)
		(width 0.1651)
		(layer "In5.Cu")
		(net "PE_TX4_DR11_N")
	)
	(segment
		(start 7.908036 -343.815416)
		(end 8.718042 -343.958164)
		(width 0.1651)
		(layer "In5.Cu")
		(net "PE_TX4_DR11_N")
	)
	(segment
		(start 26.898854 -325.787512)
		(end 26.67 -326.016366)
		(width 0.1651)
		(layer "In5.Cu")
		(net "PE_TX4_DR11_N")
	)
	(segment
		(start 31.3309 -328.821542)
		(end 31.046928 -328.41565)
		(width 0.1651)
		(layer "In5.Cu")
		(net "PE_TX4_DR11_N")
	)
	(segment
		(start 31.978092 -332.492858)
		(end 31.760414 -332.340204)
		(width 0.1651)
		(layer "In5.Cu")
		(net "PE_TX4_DR11_N")
	)
	(segment
		(start 11.924792 -347.414342)
		(end 12.208764 -347.81998)
		(width 0.1651)
		(layer "In5.Cu")
		(net "PE_TX4_DR11_N")
	)
	(segment
		(start 11.140948 -346.294964)
		(end 11.425174 -346.700602)
		(width 0.1651)
		(layer "In5.Cu")
		(net "PE_TX4_DR11_N")
	)
	(segment
		(start 12.208764 -347.81998)
		(end 12.16279 -348.081854)
		(width 0.1651)
		(layer "In5.Cu")
		(net "PE_TX4_DR11_N")
	)
	(segment
		(start 9.811258 -344.72372)
		(end 10.095484 -345.129358)
		(width 0.1651)
		(layer "In5.Cu")
		(net "PE_TX4_DR11_N")
	)
	(segment
		(start 10.357104 -345.175586)
		(end 10.64133 -345.581224)
		(width 0.1651)
		(layer "In5.Cu")
		(net "PE_TX4_DR11_N")
	)
	(segment
		(start 31.046928 -328.41565)
		(end 30.785054 -328.369676)
		(width 0.1651)
		(layer "In5.Cu")
		(net "PE_TX4_DR11_N")
	)
	(segment
		(start 15.911322 -356.931722)
		(end 16.936974 -358.398572)
		(width 0.1651)
		(layer "In5.Cu")
		(net "PE_TX4_DR11_N")
	)
	(segment
		(start 30.785054 -328.369676)
		(end 30.501082 -327.963784)
		(width 0.1651)
		(layer "In5.Cu")
		(net "PE_TX4_DR11_N")
	)
	(segment
		(start 31.364428 -351.28073)
		(end 31.949898 -347.965268)
		(width 0.1651)
		(layer "In5.Cu")
		(net "PE_TX4_DR11_N")
	)
	(segment
		(start 18.798794 -358.992678)
		(end 21.740622 -358.473756)
		(width 0.1651)
		(layer "In5.Cu")
		(net "PE_TX4_DR11_N")
	)
	(segment
		(start 31.523178 -330.994512)
		(end 31.437326 -330.506832)
		(width 0.1651)
		(layer "In5.Cu")
		(net "PE_TX4_DR11_N")
	)
	(segment
		(start 30.686248 -340.798404)
		(end 32.064198 -332.980538)
		(width 0.1651)
		(layer "In5.Cu")
		(net "PE_TX4_DR11_N")
	)
	(segment
		(start 31.826962 -331.634846)
		(end 31.740856 -331.146912)
		(width 0.1651)
		(layer "In5.Cu")
		(net "PE_TX4_DR11_N")
	)
	(segment
		(start 15.673578 -355.58603)
		(end 15.89151 -355.73843)
		(width 0.1651)
		(layer "In5.Cu")
		(net "PE_TX4_DR11_N")
	)
	(segment
		(start 3.658108 -411.941772)
		(end 3.905504 -412.189168)
		(width 0.174752)
		(layer "F.Cu")
		(net "PE_TX4_DR10_P")
	)
	(segment
		(start 6.738874 -412.189168)
		(end 6.992366 -411.935676)
		(width 0.174752)
		(layer "F.Cu")
		(net "PE_TX4_DR10_P")
	)
	(segment
		(start 23.88235 -429.010064)
		(end 22.800056 -429.010064)
		(width 0.174752)
		(layer "F.Cu")
		(net "PE_TX4_DR10_P")
	)
	(segment
		(start 2.249932 -411.941772)
		(end 3.658108 -411.941772)
		(width 0.174752)
		(layer "F.Cu")
		(net "PE_TX4_DR10_P")
	)
	(segment
		(start 26.4414 -428.787814)
		(end 24.1046 -428.787814)
		(width 0.174752)
		(layer "F.Cu")
		(net "PE_TX4_DR10_P")
	)
	(segment
		(start 3.905504 -412.189168)
		(end 6.738874 -412.189168)
		(width 0.174752)
		(layer "F.Cu")
		(net "PE_TX4_DR10_P")
	)
	(segment
		(start 24.1046 -428.787814)
		(end 23.88235 -429.010064)
		(width 0.174752)
		(layer "F.Cu")
		(net "PE_TX4_DR10_P")
	)
	(segment
		(start 26.67 -429.016414)
		(end 26.4414 -428.787814)
		(width 0.174752)
		(layer "F.Cu")
		(net "PE_TX4_DR10_P")
	)
	(via
		(at 6.992366 -411.935676)
		(size 0.508)
		(drill 0.254)
		(layers "F.Cu" "B.Cu")
		(net "PE_TX4_DR10_P")
	)
	(via
		(at 26.67 -429.016414)
		(size 0.508)
		(drill 0.254)
		(layers "F.Cu" "B.Cu")
		(net "PE_TX4_DR10_P")
	)
	(segment
		(start 7.220966 -412.164276)
		(end 7.62 -412.164276)
		(width 0.1651)
		(layer "In5.Cu")
		(net "PE_TX4_DR10_P")
	)
	(segment
		(start 7.62 -412.164276)
		(end 10.120884 -411.723332)
		(width 0.1651)
		(layer "In5.Cu")
		(net "PE_TX4_DR10_P")
	)
	(segment
		(start 6.992366 -411.935676)
		(end 7.220966 -412.164276)
		(width 0.1651)
		(layer "In5.Cu")
		(net "PE_TX4_DR10_P")
	)
	(segment
		(start 40.55872 -413.454342)
		(end 41.261792 -414.458404)
		(width 0.1651)
		(layer "In5.Cu")
		(net "PE_TX4_DR10_P")
	)
	(segment
		(start 38.512496 -412.021528)
		(end 40.55872 -413.454342)
		(width 0.1651)
		(layer "In5.Cu")
		(net "PE_TX4_DR10_P")
	)
	(segment
		(start 20.842986 -408.90571)
		(end 38.512496 -412.021528)
		(width 0.1651)
		(layer "In5.Cu")
		(net "PE_TX4_DR10_P")
	)
	(segment
		(start 36.415472 -424.736006)
		(end 31.651702 -428.071788)
		(width 0.1651)
		(layer "In5.Cu")
		(net "PE_TX4_DR10_P")
	)
	(segment
		(start 26.898854 -428.78756)
		(end 26.67 -429.016414)
		(width 0.1651)
		(layer "In5.Cu")
		(net "PE_TX4_DR10_P")
	)
	(segment
		(start 31.409894 -428.172372)
		(end 27.98572 -428.78756)
		(width 0.1651)
		(layer "In5.Cu")
		(net "PE_TX4_DR10_P")
	)
	(segment
		(start 41.410636 -415.302192)
		(end 40.8686 -418.376608)
		(width 0.1651)
		(layer "In5.Cu")
		(net "PE_TX4_DR10_P")
	)
	(segment
		(start 11.887454 -410.486606)
		(end 20.842986 -408.90571)
		(width 0.1651)
		(layer "In5.Cu")
		(net "PE_TX4_DR10_P")
	)
	(segment
		(start 41.261792 -414.458404)
		(end 41.410636 -415.302192)
		(width 0.1651)
		(layer "In5.Cu")
		(net "PE_TX4_DR10_P")
	)
	(segment
		(start 40.8686 -418.376608)
		(end 36.415472 -424.736006)
		(width 0.1651)
		(layer "In5.Cu")
		(net "PE_TX4_DR10_P")
	)
	(segment
		(start 27.98572 -428.78756)
		(end 26.898854 -428.78756)
		(width 0.1651)
		(layer "In5.Cu")
		(net "PE_TX4_DR10_P")
	)
	(segment
		(start 10.120884 -411.723332)
		(end 11.887454 -410.486606)
		(width 0.1651)
		(layer "In5.Cu")
		(net "PE_TX4_DR10_P")
	)
	(arc
		(start 31.651702 -428.071788)
		(mid 31.536254 -428.135188)
		(end 31.409894 -428.172372)
		(width 0.1651)
		(layer "In5.Cu")
		(net "PE_TX4_DR10_P")
	)
	(segment
		(start 3.657854 -412.741872)
		(end 3.905504 -412.494222)
		(width 0.174752)
		(layer "F.Cu")
		(net "PE_TX4_DR10_N")
	)
	(segment
		(start 23.876 -428.209964)
		(end 22.800056 -428.209964)
		(width 0.174752)
		(layer "F.Cu")
		(net "PE_TX4_DR10_N")
	)
	(segment
		(start 26.67 -428.203614)
		(end 26.390854 -428.48276)
		(width 0.174752)
		(layer "F.Cu")
		(net "PE_TX4_DR10_N")
	)
	(segment
		(start 24.148796 -428.48276)
		(end 23.876 -428.209964)
		(width 0.174752)
		(layer "F.Cu")
		(net "PE_TX4_DR10_N")
	)
	(segment
		(start 3.905504 -412.494222)
		(end 6.738112 -412.494222)
		(width 0.174752)
		(layer "F.Cu")
		(net "PE_TX4_DR10_N")
	)
	(segment
		(start 6.738112 -412.494222)
		(end 6.992366 -412.748476)
		(width 0.174752)
		(layer "F.Cu")
		(net "PE_TX4_DR10_N")
	)
	(segment
		(start 2.249932 -412.741872)
		(end 3.657854 -412.741872)
		(width 0.174752)
		(layer "F.Cu")
		(net "PE_TX4_DR10_N")
	)
	(segment
		(start 26.390854 -428.48276)
		(end 24.148796 -428.48276)
		(width 0.174752)
		(layer "F.Cu")
		(net "PE_TX4_DR10_N")
	)
	(via
		(at 26.67 -428.203614)
		(size 0.508)
		(drill 0.254)
		(layers "F.Cu" "B.Cu")
		(net "PE_TX4_DR10_N")
	)
	(via
		(at 6.992366 -412.748476)
		(size 0.508)
		(drill 0.254)
		(layers "F.Cu" "B.Cu")
		(net "PE_TX4_DR10_N")
	)
	(segment
		(start 40.53205 -418.237162)
		(end 40.247824 -418.6428)
		(width 0.1651)
		(layer "In5.Cu")
		(net "PE_TX4_DR10_N")
	)
	(segment
		(start 37.228018 -422.955466)
		(end 36.943792 -423.361104)
		(width 0.1651)
		(layer "In5.Cu")
		(net "PE_TX4_DR10_N")
	)
	(segment
		(start 40.925242 -414.59785)
		(end 41.049448 -415.302192)
		(width 0.1651)
		(layer "In5.Cu")
		(net "PE_TX4_DR10_N")
	)
	(segment
		(start 34.805874 -425.428918)
		(end 34.544 -425.38269)
		(width 0.1651)
		(layer "In5.Cu")
		(net "PE_TX4_DR10_N")
	)
	(segment
		(start 37.466016 -422.287954)
		(end 37.18179 -422.693592)
		(width 0.1651)
		(layer "In5.Cu")
		(net "PE_TX4_DR10_N")
	)
	(segment
		(start 33.686496 -426.212762)
		(end 33.424622 -426.166534)
		(width 0.1651)
		(layer "In5.Cu")
		(net "PE_TX4_DR10_N")
	)
	(segment
		(start 32.972756 -426.71238)
		(end 32.567118 -426.996606)
		(width 0.1651)
		(layer "In5.Cu")
		(net "PE_TX4_DR10_N")
	)
	(segment
		(start 40.303196 -413.709866)
		(end 40.925242 -414.59785)
		(width 0.1651)
		(layer "In5.Cu")
		(net "PE_TX4_DR10_N")
	)
	(segment
		(start 36.681918 -423.407332)
		(end 36.397946 -423.81297)
		(width 0.1651)
		(layer "In5.Cu")
		(net "PE_TX4_DR10_N")
	)
	(segment
		(start 36.397946 -423.81297)
		(end 36.444174 -424.074844)
		(width 0.1651)
		(layer "In5.Cu")
		(net "PE_TX4_DR10_N")
	)
	(segment
		(start 34.544 -425.38269)
		(end 34.138362 -425.666916)
		(width 0.1651)
		(layer "In5.Cu")
		(net "PE_TX4_DR10_N")
	)
	(segment
		(start 39.986204 -418.689028)
		(end 39.701978 -419.094666)
		(width 0.1651)
		(layer "In5.Cu")
		(net "PE_TX4_DR10_N")
	)
	(segment
		(start 34.138362 -425.666916)
		(end 34.092134 -425.928536)
		(width 0.1651)
		(layer "In5.Cu")
		(net "PE_TX4_DR10_N")
	)
	(segment
		(start 27.95397 -428.43196)
		(end 26.898346 -428.43196)
		(width 0.1651)
		(layer "In5.Cu")
		(net "PE_TX4_DR10_N")
	)
	(segment
		(start 31.853378 -427.496224)
		(end 31.44774 -427.78045)
		(width 0.1651)
		(layer "In5.Cu")
		(net "PE_TX4_DR10_N")
	)
	(segment
		(start 31.899606 -427.234604)
		(end 31.853378 -427.496224)
		(width 0.1651)
		(layer "In5.Cu")
		(net "PE_TX4_DR10_N")
	)
	(segment
		(start 36.159948 -424.480482)
		(end 34.805874 -425.428918)
		(width 0.1651)
		(layer "In5.Cu")
		(net "PE_TX4_DR10_N")
	)
	(segment
		(start 38.51148 -421.122348)
		(end 38.24986 -421.168576)
		(width 0.1651)
		(layer "In5.Cu")
		(net "PE_TX4_DR10_N")
	)
	(segment
		(start 31.346902 -427.822106)
		(end 31.346902 -427.82236)
		(width 0.1651)
		(layer "In5.Cu")
		(net "PE_TX4_DR10_N")
	)
	(segment
		(start 39.701978 -419.094666)
		(end 39.748206 -419.35654)
		(width 0.1651)
		(layer "In5.Cu")
		(net "PE_TX4_DR10_N")
	)
	(segment
		(start 38.24986 -421.168576)
		(end 37.965634 -421.574214)
		(width 0.1651)
		(layer "In5.Cu")
		(net "PE_TX4_DR10_N")
	)
	(segment
		(start 40.247824 -418.6428)
		(end 39.986204 -418.689028)
		(width 0.1651)
		(layer "In5.Cu")
		(net "PE_TX4_DR10_N")
	)
	(segment
		(start 38.37305 -412.358078)
		(end 40.302942 -413.709358)
		(width 0.1651)
		(layer "In5.Cu")
		(net "PE_TX4_DR10_N")
	)
	(segment
		(start 33.018984 -426.45076)
		(end 32.972756 -426.71238)
		(width 0.1651)
		(layer "In5.Cu")
		(net "PE_TX4_DR10_N")
	)
	(segment
		(start 37.18179 -422.693592)
		(end 37.228018 -422.955466)
		(width 0.1651)
		(layer "In5.Cu")
		(net "PE_TX4_DR10_N")
	)
	(segment
		(start 6.992366 -412.748476)
		(end 7.220966 -412.519876)
		(width 0.1651)
		(layer "In5.Cu")
		(net "PE_TX4_DR10_N")
	)
	(segment
		(start 36.943792 -423.361104)
		(end 36.681918 -423.407332)
		(width 0.1651)
		(layer "In5.Cu")
		(net "PE_TX4_DR10_N")
	)
	(segment
		(start 31.346902 -427.82236)
		(end 27.95397 -428.43196)
		(width 0.1651)
		(layer "In5.Cu")
		(net "PE_TX4_DR10_N")
	)
	(segment
		(start 7.651242 -412.519876)
		(end 10.260584 -412.059882)
		(width 0.1651)
		(layer "In5.Cu")
		(net "PE_TX4_DR10_N")
	)
	(segment
		(start 32.567118 -426.996606)
		(end 32.305244 -426.950378)
		(width 0.1651)
		(layer "In5.Cu")
		(net "PE_TX4_DR10_N")
	)
	(segment
		(start 12.0269 -410.823156)
		(end 20.842986 -409.266898)
		(width 0.1651)
		(layer "In5.Cu")
		(net "PE_TX4_DR10_N")
	)
	(segment
		(start 7.220966 -412.519876)
		(end 7.651242 -412.519876)
		(width 0.1651)
		(layer "In5.Cu")
		(net "PE_TX4_DR10_N")
	)
	(segment
		(start 10.260584 -412.059882)
		(end 12.0269 -410.823156)
		(width 0.1651)
		(layer "In5.Cu")
		(net "PE_TX4_DR10_N")
	)
	(segment
		(start 26.898346 -428.43196)
		(end 26.67 -428.203614)
		(width 0.1651)
		(layer "In5.Cu")
		(net "PE_TX4_DR10_N")
	)
	(segment
		(start 34.092134 -425.928536)
		(end 33.686496 -426.212762)
		(width 0.1651)
		(layer "In5.Cu")
		(net "PE_TX4_DR10_N")
	)
	(segment
		(start 40.302942 -413.709358)
		(end 40.303196 -413.709866)
		(width 0.1651)
		(layer "In5.Cu")
		(net "PE_TX4_DR10_N")
	)
	(segment
		(start 38.011862 -421.836088)
		(end 37.727636 -422.241726)
		(width 0.1651)
		(layer "In5.Cu")
		(net "PE_TX4_DR10_N")
	)
	(segment
		(start 37.727636 -422.241726)
		(end 37.466016 -422.287954)
		(width 0.1651)
		(layer "In5.Cu")
		(net "PE_TX4_DR10_N")
	)
	(segment
		(start 41.049448 -415.302192)
		(end 40.53205 -418.237162)
		(width 0.1651)
		(layer "In5.Cu")
		(net "PE_TX4_DR10_N")
	)
	(segment
		(start 37.965634 -421.574214)
		(end 38.011862 -421.836088)
		(width 0.1651)
		(layer "In5.Cu")
		(net "PE_TX4_DR10_N")
	)
	(segment
		(start 36.444174 -424.074844)
		(end 36.159948 -424.480482)
		(width 0.1651)
		(layer "In5.Cu")
		(net "PE_TX4_DR10_N")
	)
	(segment
		(start 33.424622 -426.166534)
		(end 33.018984 -426.45076)
		(width 0.1651)
		(layer "In5.Cu")
		(net "PE_TX4_DR10_N")
	)
	(segment
		(start 32.305244 -426.950378)
		(end 31.899606 -427.234604)
		(width 0.1651)
		(layer "In5.Cu")
		(net "PE_TX4_DR10_N")
	)
	(segment
		(start 39.748206 -419.35654)
		(end 38.51148 -421.122348)
		(width 0.1651)
		(layer "In5.Cu")
		(net "PE_TX4_DR10_N")
	)
	(segment
		(start 20.842986 -409.266898)
		(end 38.37305 -412.358078)
		(width 0.1651)
		(layer "In5.Cu")
		(net "PE_TX4_DR10_N")
	)
	(arc
		(start 31.44774 -427.78045)
		(mid 31.399584 -427.806755)
		(end 31.346902 -427.822106)
		(width 0.1651)
		(layer "In5.Cu")
		(net "PE_TX4_DR10_N")
	)
	(segment
		(start 223.132396 -386.790184)
		(end 222.885 -386.542788)
		(width 0.174752)
		(layer "F.Cu")
		(net "PE_TX4_DR1_P")
	)
	(segment
		(start 6.738112 -397.294354)
		(end 6.992366 -397.548608)
		(width 0.174752)
		(layer "F.Cu")
		(net "PE_TX4_DR1_P")
	)
	(segment
		(start 222.885 -386.542788)
		(end 220.58376 -386.542788)
		(width 0.174752)
		(layer "F.Cu")
		(net "PE_TX4_DR1_P")
	)
	(segment
		(start 3.905504 -397.294354)
		(end 6.738112 -397.294354)
		(width 0.174752)
		(layer "F.Cu")
		(net "PE_TX4_DR1_P")
	)
	(segment
		(start 3.657854 -397.542004)
		(end 3.905504 -397.294354)
		(width 0.174752)
		(layer "F.Cu")
		(net "PE_TX4_DR1_P")
	)
	(segment
		(start 220.58376 -386.542788)
		(end 220.330014 -386.796534)
		(width 0.174752)
		(layer "F.Cu")
		(net "PE_TX4_DR1_P")
	)
	(segment
		(start 2.249932 -397.542004)
		(end 3.657854 -397.542004)
		(width 0.174752)
		(layer "F.Cu")
		(net "PE_TX4_DR1_P")
	)
	(segment
		(start 224.199958 -386.790184)
		(end 223.132396 -386.790184)
		(width 0.174752)
		(layer "F.Cu")
		(net "PE_TX4_DR1_P")
	)
	(via
		(at 6.992366 -397.548608)
		(size 0.508)
		(drill 0.254)
		(layers "F.Cu" "B.Cu")
		(net "PE_TX4_DR1_P")
	)
	(via
		(at 220.330014 -386.796534)
		(size 0.508)
		(drill 0.254)
		(layers "F.Cu" "B.Cu")
		(net "PE_TX4_DR1_P")
	)
	(segment
		(start 218.649804 -386.568188)
		(end 220.101668 -386.568188)
		(width 0.1651)
		(layer "In5.Cu")
		(net "PE_TX4_DR1_P")
	)
	(segment
		(start 7.976362 -397.382746)
		(end 8.333486 -397.445738)
		(width 0.1651)
		(layer "In5.Cu")
		(net "PE_TX4_DR1_P")
	)
	(segment
		(start 7.693914 -397.333216)
		(end 7.976362 -397.382746)
		(width 0.1651)
		(layer "In5.Cu")
		(net "PE_TX4_DR1_P")
	)
	(segment
		(start 7.62 -397.320008)
		(end 7.693914 -397.333216)
		(width 0.1651)
		(layer "In5.Cu")
		(net "PE_TX4_DR1_P")
	)
	(segment
		(start 7.220966 -397.320008)
		(end 7.62 -397.320008)
		(width 0.1651)
		(layer "In5.Cu")
		(net "PE_TX4_DR1_P")
	)
	(segment
		(start 18.725896 -404.722584)
		(end 44.814744 -409.322524)
		(width 0.1651)
		(layer "In5.Cu")
		(net "PE_TX4_DR1_P")
	)
	(segment
		(start 6.992366 -397.548608)
		(end 7.220966 -397.320008)
		(width 0.1651)
		(layer "In5.Cu")
		(net "PE_TX4_DR1_P")
	)
	(segment
		(start 196.501258 -382.662938)
		(end 218.649804 -386.568188)
		(width 0.1651)
		(layer "In5.Cu")
		(net "PE_TX4_DR1_P")
	)
	(segment
		(start 45.15866 -409.322524)
		(end 196.280786 -382.662938)
		(width 0.1651)
		(layer "In5.Cu")
		(net "PE_TX4_DR1_P")
	)
	(segment
		(start 220.101668 -386.568188)
		(end 220.330014 -386.796534)
		(width 0.1651)
		(layer "In5.Cu")
		(net "PE_TX4_DR1_P")
	)
	(segment
		(start 8.333486 -397.445738)
		(end 18.725896 -404.722584)
		(width 0.1651)
		(layer "In5.Cu")
		(net "PE_TX4_DR1_P")
	)
	(arc
		(start 196.280786 -382.662938)
		(mid 196.391022 -382.653296)
		(end 196.501258 -382.662938)
		(width 0.1651)
		(layer "In5.Cu")
		(net "PE_TX4_DR1_P")
	)
	(arc
		(start 44.814744 -409.322524)
		(mid 44.986702 -409.337562)
		(end 45.15866 -409.322524)
		(width 0.1651)
		(layer "In5.Cu")
		(net "PE_TX4_DR1_P")
	)
	(segment
		(start 222.89135 -386.237734)
		(end 220.584014 -386.237734)
		(width 0.174752)
		(layer "F.Cu")
		(net "PE_TX4_DR1_N")
	)
	(segment
		(start 2.249932 -396.741904)
		(end 3.658108 -396.741904)
		(width 0.174752)
		(layer "F.Cu")
		(net "PE_TX4_DR1_N")
	)
	(segment
		(start 3.905504 -396.9893)
		(end 6.738874 -396.9893)
		(width 0.174752)
		(layer "F.Cu")
		(net "PE_TX4_DR1_N")
	)
	(segment
		(start 224.199958 -385.990084)
		(end 223.139 -385.990084)
		(width 0.174752)
		(layer "F.Cu")
		(net "PE_TX4_DR1_N")
	)
	(segment
		(start 3.658108 -396.741904)
		(end 3.905504 -396.9893)
		(width 0.174752)
		(layer "F.Cu")
		(net "PE_TX4_DR1_N")
	)
	(segment
		(start 223.139 -385.990084)
		(end 222.89135 -386.237734)
		(width 0.174752)
		(layer "F.Cu")
		(net "PE_TX4_DR1_N")
	)
	(segment
		(start 220.584014 -386.237734)
		(end 220.330014 -385.983734)
		(width 0.174752)
		(layer "F.Cu")
		(net "PE_TX4_DR1_N")
	)
	(segment
		(start 6.738874 -396.9893)
		(end 6.992366 -396.735808)
		(width 0.174752)
		(layer "F.Cu")
		(net "PE_TX4_DR1_N")
	)
	(via
		(at 220.330014 -385.983734)
		(size 0.508)
		(drill 0.254)
		(layers "F.Cu" "B.Cu")
		(net "PE_TX4_DR1_N")
	)
	(via
		(at 6.992366 -396.735808)
		(size 0.508)
		(drill 0.254)
		(layers "F.Cu" "B.Cu")
		(net "PE_TX4_DR1_N")
	)
	(segment
		(start 196.56298 -382.312418)
		(end 218.681046 -386.212588)
		(width 0.1651)
		(layer "In5.Cu")
		(net "PE_TX4_DR1_N")
	)
	(segment
		(start 7.651242 -396.964408)
		(end 8.472932 -397.109188)
		(width 0.1651)
		(layer "In5.Cu")
		(net "PE_TX4_DR1_N")
	)
	(segment
		(start 6.992366 -396.735808)
		(end 7.220966 -396.964408)
		(width 0.1651)
		(layer "In5.Cu")
		(net "PE_TX4_DR1_N")
	)
	(segment
		(start 18.865342 -404.386034)
		(end 44.876466 -408.972004)
		(width 0.1651)
		(layer "In5.Cu")
		(net "PE_TX4_DR1_N")
	)
	(segment
		(start 7.220966 -396.964408)
		(end 7.651242 -396.964408)
		(width 0.1651)
		(layer "In5.Cu")
		(net "PE_TX4_DR1_N")
	)
	(segment
		(start 220.10116 -386.212588)
		(end 220.330014 -385.983734)
		(width 0.1651)
		(layer "In5.Cu")
		(net "PE_TX4_DR1_N")
	)
	(segment
		(start 45.096938 -408.972004)
		(end 196.219064 -382.312418)
		(width 0.1651)
		(layer "In5.Cu")
		(net "PE_TX4_DR1_N")
	)
	(segment
		(start 218.681046 -386.212588)
		(end 220.10116 -386.212588)
		(width 0.1651)
		(layer "In5.Cu")
		(net "PE_TX4_DR1_N")
	)
	(segment
		(start 8.472932 -397.109188)
		(end 18.865342 -404.386034)
		(width 0.1651)
		(layer "In5.Cu")
		(net "PE_TX4_DR1_N")
	)
	(arc
		(start 44.876466 -408.972004)
		(mid 44.986702 -408.981646)
		(end 45.096938 -408.972004)
		(width 0.1651)
		(layer "In5.Cu")
		(net "PE_TX4_DR1_N")
	)
	(arc
		(start 196.219064 -382.312418)
		(mid 196.391022 -382.29738)
		(end 196.56298 -382.312418)
		(width 0.1651)
		(layer "In5.Cu")
		(net "PE_TX4_DR1_N")
	)
	(segment
		(start 6.719062 -431.7238)
		(end 3.876294 -431.7238)
		(width 0.174752)
		(layer "F.Cu")
		(net "PE_TX4_DR0_P")
	)
	(segment
		(start 223.139 -489.790232)
		(end 222.891604 -489.542836)
		(width 0.174752)
		(layer "F.Cu")
		(net "PE_TX4_DR0_P")
	)
	(segment
		(start 6.992366 -431.997104)
		(end 6.719062 -431.7238)
		(width 0.174752)
		(layer "F.Cu")
		(net "PE_TX4_DR0_P")
	)
	(segment
		(start 222.891604 -489.542836)
		(end 220.58376 -489.542836)
		(width 0.174752)
		(layer "F.Cu")
		(net "PE_TX4_DR0_P")
	)
	(segment
		(start 3.658108 -431.941986)
		(end 2.249932 -431.941986)
		(width 0.174752)
		(layer "F.Cu")
		(net "PE_TX4_DR0_P")
	)
	(segment
		(start 220.58376 -489.542836)
		(end 220.330014 -489.796582)
		(width 0.174752)
		(layer "F.Cu")
		(net "PE_TX4_DR0_P")
	)
	(segment
		(start 3.876294 -431.7238)
		(end 3.658108 -431.941986)
		(width 0.174752)
		(layer "F.Cu")
		(net "PE_TX4_DR0_P")
	)
	(segment
		(start 224.199958 -489.790232)
		(end 223.139 -489.790232)
		(width 0.174752)
		(layer "F.Cu")
		(net "PE_TX4_DR0_P")
	)
	(via
		(at 220.330014 -489.796582)
		(size 0.508)
		(drill 0.254)
		(layers "F.Cu" "B.Cu")
		(net "PE_TX4_DR0_P")
	)
	(via
		(at 6.992366 -431.997104)
		(size 0.508)
		(drill 0.254)
		(layers "F.Cu" "B.Cu")
		(net "PE_TX4_DR0_P")
	)
	(segment
		(start 7.878572 -431.768504)
		(end 7.220966 -431.768504)
		(width 0.1651)
		(layer "In5.Cu")
		(net "PE_TX4_DR0_P")
	)
	(segment
		(start 14.867636 -459.438248)
		(end 10.292334 -433.49164)
		(width 0.1651)
		(layer "In5.Cu")
		(net "PE_TX4_DR0_P")
	)
	(segment
		(start 9.752076 -432.721004)
		(end 9.683496 -432.672998)
		(width 0.1651)
		(layer "In5.Cu")
		(net "PE_TX4_DR0_P")
	)
	(segment
		(start 23.362412 -462.838038)
		(end 23.148798 -462.92643)
		(width 0.1651)
		(layer "In5.Cu")
		(net "PE_TX4_DR0_P")
	)
	(segment
		(start 23.480268 -462.773522)
		(end 23.362412 -462.838038)
		(width 0.1651)
		(layer "In5.Cu")
		(net "PE_TX4_DR0_P")
	)
	(segment
		(start 7.220966 -431.768504)
		(end 6.992366 -431.997104)
		(width 0.1651)
		(layer "In5.Cu")
		(net "PE_TX4_DR0_P")
	)
	(segment
		(start 23.076662 -462.956148)
		(end 23.008336 -462.975198)
		(width 0.1651)
		(layer "In5.Cu")
		(net "PE_TX4_DR0_P")
	)
	(segment
		(start 188.684408 -470.064084)
		(end 41.910762 -444.18885)
		(width 0.1651)
		(layer "In5.Cu")
		(net "PE_TX4_DR0_P")
	)
	(segment
		(start 27.94 -459.650084)
		(end 27.94 -459.6511)
		(width 0.1651)
		(layer "In5.Cu")
		(net "PE_TX4_DR0_P")
	)
	(segment
		(start 215.738964 -489.008166)
		(end 188.684408 -470.064084)
		(width 0.1651)
		(layer "In5.Cu")
		(net "PE_TX4_DR0_P")
	)
	(segment
		(start 41.910762 -444.18885)
		(end 40.397938 -444.45555)
		(width 0.1651)
		(layer "In5.Cu")
		(net "PE_TX4_DR0_P")
	)
	(segment
		(start 36.767516 -447.044826)
		(end 27.975052 -459.6003)
		(width 0.1651)
		(layer "In5.Cu")
		(net "PE_TX4_DR0_P")
	)
	(segment
		(start 220.330014 -489.796582)
		(end 220.101668 -489.568236)
		(width 0.1651)
		(layer "In5.Cu")
		(net "PE_TX4_DR0_P")
	)
	(segment
		(start 8.564372 -431.889408)
		(end 7.878572 -431.768504)
		(width 0.1651)
		(layer "In5.Cu")
		(net "PE_TX4_DR0_P")
	)
	(segment
		(start 9.158478 -432.305206)
		(end 8.564372 -431.889408)
		(width 0.1651)
		(layer "In5.Cu")
		(net "PE_TX4_DR0_P")
	)
	(segment
		(start 27.887168 -459.688184)
		(end 27.887168 -459.688438)
		(width 0.1651)
		(layer "In5.Cu")
		(net "PE_TX4_DR0_P")
	)
	(segment
		(start 27.975052 -459.6003)
		(end 27.974544 -459.601062)
		(width 0.1651)
		(layer "In5.Cu")
		(net "PE_TX4_DR0_P")
	)
	(segment
		(start 27.974544 -459.600808)
		(end 27.94 -459.650084)
		(width 0.1651)
		(layer "In5.Cu")
		(net "PE_TX4_DR0_P")
	)
	(segment
		(start 9.683496 -432.672998)
		(end 9.158478 -432.305206)
		(width 0.1651)
		(layer "In5.Cu")
		(net "PE_TX4_DR0_P")
	)
	(segment
		(start 218.915742 -489.568236)
		(end 215.738964 -489.008166)
		(width 0.1651)
		(layer "In5.Cu")
		(net "PE_TX4_DR0_P")
	)
	(segment
		(start 16.74241 -462.124806)
		(end 14.867636 -459.438248)
		(width 0.1651)
		(layer "In5.Cu")
		(net "PE_TX4_DR0_P")
	)
	(segment
		(start 220.101668 -489.568236)
		(end 218.915742 -489.568236)
		(width 0.1651)
		(layer "In5.Cu")
		(net "PE_TX4_DR0_P")
	)
	(segment
		(start 23.148798 -462.92643)
		(end 23.076662 -462.956148)
		(width 0.1651)
		(layer "In5.Cu")
		(net "PE_TX4_DR0_P")
	)
	(segment
		(start 17.916906 -462.947004)
		(end 16.74241 -462.124806)
		(width 0.1651)
		(layer "In5.Cu")
		(net "PE_TX4_DR0_P")
	)
	(segment
		(start 27.94 -459.6511)
		(end 27.887168 -459.688184)
		(width 0.1651)
		(layer "In5.Cu")
		(net "PE_TX4_DR0_P")
	)
	(segment
		(start 10.292334 -433.49164)
		(end 9.752076 -432.721004)
		(width 0.1651)
		(layer "In5.Cu")
		(net "PE_TX4_DR0_P")
	)
	(segment
		(start 27.887168 -459.688438)
		(end 23.480268 -462.773522)
		(width 0.1651)
		(layer "In5.Cu")
		(net "PE_TX4_DR0_P")
	)
	(segment
		(start 27.974544 -459.601062)
		(end 27.974544 -459.600808)
		(width 0.1651)
		(layer "In5.Cu")
		(net "PE_TX4_DR0_P")
	)
	(segment
		(start 40.397938 -444.45555)
		(end 36.923472 -446.88887)
		(width 0.1651)
		(layer "In5.Cu")
		(net "PE_TX4_DR0_P")
	)
	(segment
		(start 23.008336 -462.975198)
		(end 20.651216 -463.391504)
		(width 0.1651)
		(layer "In5.Cu")
		(net "PE_TX4_DR0_P")
	)
	(segment
		(start 20.439126 -463.391504)
		(end 17.916906 -462.947004)
		(width 0.1651)
		(layer "In5.Cu")
		(net "PE_TX4_DR0_P")
	)
	(arc
		(start 20.651216 -463.391504)
		(mid 20.545173 -463.400778)
		(end 20.439126 -463.391504)
		(width 0.1651)
		(layer "In5.Cu")
		(net "PE_TX4_DR0_P")
	)
	(arc
		(start 36.923472 -446.88887)
		(mid 36.838671 -446.960025)
		(end 36.767516 -447.044826)
		(width 0.1651)
		(layer "In5.Cu")
		(net "PE_TX4_DR0_P")
	)
	(segment
		(start 223.139 -488.990132)
		(end 222.89135 -489.237782)
		(width 0.174752)
		(layer "F.Cu")
		(net "PE_TX4_DR0_N")
	)
	(segment
		(start 6.757924 -431.418746)
		(end 3.934714 -431.418746)
		(width 0.174752)
		(layer "F.Cu")
		(net "PE_TX4_DR0_N")
	)
	(segment
		(start 3.934714 -431.418746)
		(end 3.657854 -431.141886)
		(width 0.174752)
		(layer "F.Cu")
		(net "PE_TX4_DR0_N")
	)
	(segment
		(start 222.89135 -489.237782)
		(end 220.584014 -489.237782)
		(width 0.174752)
		(layer "F.Cu")
		(net "PE_TX4_DR0_N")
	)
	(segment
		(start 3.657854 -431.141886)
		(end 2.249932 -431.141886)
		(width 0.174752)
		(layer "F.Cu")
		(net "PE_TX4_DR0_N")
	)
	(segment
		(start 220.584014 -489.237782)
		(end 220.330014 -488.983782)
		(width 0.174752)
		(layer "F.Cu")
		(net "PE_TX4_DR0_N")
	)
	(segment
		(start 6.992366 -431.184304)
		(end 6.757924 -431.418746)
		(width 0.174752)
		(layer "F.Cu")
		(net "PE_TX4_DR0_N")
	)
	(segment
		(start 224.199958 -488.990132)
		(end 223.139 -488.990132)
		(width 0.174752)
		(layer "F.Cu")
		(net "PE_TX4_DR0_N")
	)
	(via
		(at 220.330014 -488.983782)
		(size 0.508)
		(drill 0.254)
		(layers "F.Cu" "B.Cu")
		(net "PE_TX4_DR0_N")
	)
	(via
		(at 6.992366 -431.184304)
		(size 0.508)
		(drill 0.254)
		(layers "F.Cu" "B.Cu")
		(net "PE_TX4_DR0_N")
	)
	(segment
		(start 220.330014 -488.983782)
		(end 220.10116 -489.212636)
		(width 0.1651)
		(layer "In5.Cu")
		(net "PE_TX4_DR0_N")
	)
	(segment
		(start 10.628884 -433.352194)
		(end 10.0076 -432.46548)
		(width 0.1651)
		(layer "In5.Cu")
		(net "PE_TX4_DR0_N")
	)
	(segment
		(start 41.91 -443.827662)
		(end 40.258492 -444.119)
		(width 0.1651)
		(layer "In5.Cu")
		(net "PE_TX4_DR0_N")
	)
	(segment
		(start 16.997934 -461.869536)
		(end 15.204186 -459.299056)
		(width 0.1651)
		(layer "In5.Cu")
		(net "PE_TX4_DR0_N")
	)
	(segment
		(start 218.946984 -489.212636)
		(end 215.87841 -488.671616)
		(width 0.1651)
		(layer "In5.Cu")
		(net "PE_TX4_DR0_N")
	)
	(segment
		(start 7.909814 -431.412904)
		(end 7.220966 -431.412904)
		(width 0.1651)
		(layer "In5.Cu")
		(net "PE_TX4_DR0_N")
	)
	(segment
		(start 22.960584 -462.619344)
		(end 22.929596 -462.62798)
		(width 0.1651)
		(layer "In5.Cu")
		(net "PE_TX4_DR0_N")
	)
	(segment
		(start 23.292308 -462.471008)
		(end 23.208742 -462.516728)
		(width 0.1651)
		(layer "In5.Cu")
		(net "PE_TX4_DR0_N")
	)
	(segment
		(start 7.220966 -431.412904)
		(end 6.992366 -431.184304)
		(width 0.1651)
		(layer "In5.Cu")
		(net "PE_TX4_DR0_N")
	)
	(segment
		(start 27.683206 -459.396592)
		(end 23.292308 -462.471008)
		(width 0.1651)
		(layer "In5.Cu")
		(net "PE_TX4_DR0_N")
	)
	(segment
		(start 36.475416 -446.841372)
		(end 27.683968 -459.39583)
		(width 0.1651)
		(layer "In5.Cu")
		(net "PE_TX4_DR0_N")
	)
	(segment
		(start 41.910762 -443.827662)
		(end 41.91 -443.827662)
		(width 0.1651)
		(layer "In5.Cu")
		(net "PE_TX4_DR0_N")
	)
	(segment
		(start 27.683968 -459.39583)
		(end 27.683206 -459.396592)
		(width 0.1651)
		(layer "In5.Cu")
		(net "PE_TX4_DR0_N")
	)
	(segment
		(start 22.929596 -462.62798)
		(end 20.589494 -463.040984)
		(width 0.1651)
		(layer "In5.Cu")
		(net "PE_TX4_DR0_N")
	)
	(segment
		(start 23.208742 -462.516728)
		(end 23.012908 -462.597754)
		(width 0.1651)
		(layer "In5.Cu")
		(net "PE_TX4_DR0_N")
	)
	(segment
		(start 215.87841 -488.671616)
		(end 188.823854 -469.727534)
		(width 0.1651)
		(layer "In5.Cu")
		(net "PE_TX4_DR0_N")
	)
	(segment
		(start 20.501102 -463.041238)
		(end 18.056352 -462.610454)
		(width 0.1651)
		(layer "In5.Cu")
		(net "PE_TX4_DR0_N")
	)
	(segment
		(start 18.056352 -462.610454)
		(end 16.997934 -461.869536)
		(width 0.1651)
		(layer "In5.Cu")
		(net "PE_TX4_DR0_N")
	)
	(segment
		(start 23.012908 -462.597754)
		(end 22.960584 -462.619344)
		(width 0.1651)
		(layer "In5.Cu")
		(net "PE_TX4_DR0_N")
	)
	(segment
		(start 15.204186 -459.299056)
		(end 10.628884 -433.352194)
		(width 0.1651)
		(layer "In5.Cu")
		(net "PE_TX4_DR0_N")
	)
	(segment
		(start 8.703818 -431.552858)
		(end 7.909814 -431.412904)
		(width 0.1651)
		(layer "In5.Cu")
		(net "PE_TX4_DR0_N")
	)
	(segment
		(start 188.823854 -469.727534)
		(end 41.910762 -443.827662)
		(width 0.1651)
		(layer "In5.Cu")
		(net "PE_TX4_DR0_N")
	)
	(segment
		(start 10.0076 -432.46548)
		(end 8.703818 -431.552858)
		(width 0.1651)
		(layer "In5.Cu")
		(net "PE_TX4_DR0_N")
	)
	(segment
		(start 40.258492 -444.119)
		(end 36.718494 -446.59804)
		(width 0.1651)
		(layer "In5.Cu")
		(net "PE_TX4_DR0_N")
	)
	(segment
		(start 220.10116 -489.212636)
		(end 218.946984 -489.212636)
		(width 0.1651)
		(layer "In5.Cu")
		(net "PE_TX4_DR0_N")
	)
	(arc
		(start 20.589494 -463.040984)
		(mid 20.545308 -463.044994)
		(end 20.501102 -463.041238)
		(width 0.1651)
		(layer "In5.Cu")
		(net "PE_TX4_DR0_N")
	)
	(arc
		(start 36.718494 -446.59804)
		(mid 36.586307 -446.70907)
		(end 36.475416 -446.841372)
		(width 0.1651)
		(layer "In5.Cu")
		(net "PE_TX4_DR0_N")
	)
	(segment
		(start 37.852604 -72.742552)
		(end 35.583876 -72.742552)
		(width 0.174752)
		(layer "F.Cu")
		(net "PE_TX3_DR9_P")
	)
	(segment
		(start 35.583876 -72.742552)
		(end 35.33013 -72.996298)
		(width 0.174752)
		(layer "F.Cu")
		(net "PE_TX3_DR9_P")
	)
	(segment
		(start 3.657854 -193.542158)
		(end 3.905504 -193.294508)
		(width 0.174752)
		(layer "F.Cu")
		(net "PE_TX3_DR9_P")
	)
	(segment
		(start 39.200074 -72.989948)
		(end 38.1 -72.989948)
		(width 0.174752)
		(layer "F.Cu")
		(net "PE_TX3_DR9_P")
	)
	(segment
		(start 2.249932 -193.542158)
		(end 3.657854 -193.542158)
		(width 0.174752)
		(layer "F.Cu")
		(net "PE_TX3_DR9_P")
	)
	(segment
		(start 3.905504 -193.294508)
		(end 6.738112 -193.294508)
		(width 0.174752)
		(layer "F.Cu")
		(net "PE_TX3_DR9_P")
	)
	(segment
		(start 6.738112 -193.294508)
		(end 6.992366 -193.548762)
		(width 0.174752)
		(layer "F.Cu")
		(net "PE_TX3_DR9_P")
	)
	(segment
		(start 38.1 -72.989948)
		(end 37.852604 -72.742552)
		(width 0.174752)
		(layer "F.Cu")
		(net "PE_TX3_DR9_P")
	)
	(via
		(at 6.992366 -193.548762)
		(size 0.508)
		(drill 0.254)
		(layers "F.Cu" "B.Cu")
		(net "PE_TX3_DR9_P")
	)
	(via
		(at 35.33013 -72.996298)
		(size 0.508)
		(drill 0.254)
		(layers "F.Cu" "B.Cu")
		(net "PE_TX3_DR9_P")
	)
	(segment
		(start 44.928028 -106.321352)
		(end 44.397422 -103.31323)
		(width 0.1651)
		(layer "In5.Cu")
		(net "PE_TX3_DR9_P")
	)
	(segment
		(start 31.960566 -73.118472)
		(end 31.961328 -73.117964)
		(width 0.1651)
		(layer "In5.Cu")
		(net "PE_TX3_DR9_P")
	)
	(segment
		(start 10.181844 -192.879472)
		(end 17.025874 -188.087508)
		(width 0.1651)
		(layer "In5.Cu")
		(net "PE_TX3_DR9_P")
	)
	(segment
		(start 28.619704 -171.529248)
		(end 31.973266 -152.507442)
		(width 0.1651)
		(layer "In5.Cu")
		(net "PE_TX3_DR9_P")
	)
	(segment
		(start 41.531794 -115.860068)
		(end 43.823636 -112.584992)
		(width 0.1651)
		(layer "In5.Cu")
		(net "PE_TX3_DR9_P")
	)
	(segment
		(start 7.220966 -193.320162)
		(end 7.682484 -193.320162)
		(width 0.1651)
		(layer "In5.Cu")
		(net "PE_TX3_DR9_P")
	)
	(segment
		(start 17.025874 -188.087508)
		(end 28.619704 -171.529248)
		(width 0.1651)
		(layer "In5.Cu")
		(net "PE_TX3_DR9_P")
	)
	(segment
		(start 21.332444 -90.614754)
		(end 22.376384 -84.69503)
		(width 0.1651)
		(layer "In5.Cu")
		(net "PE_TX3_DR9_P")
	)
	(segment
		(start 31.973266 -152.507442)
		(end 36.103814 -146.608038)
		(width 0.1651)
		(layer "In5.Cu")
		(net "PE_TX3_DR9_P")
	)
	(segment
		(start 33.947862 -72.767952)
		(end 35.101784 -72.767952)
		(width 0.1651)
		(layer "In5.Cu")
		(net "PE_TX3_DR9_P")
	)
	(segment
		(start 40.366696 -99.626166)
		(end 25.40381 -96.988376)
		(width 0.1651)
		(layer "In5.Cu")
		(net "PE_TX3_DR9_P")
	)
	(segment
		(start 23.32355 -95.530924)
		(end 21.82114 -93.385386)
		(width 0.1651)
		(layer "In5.Cu")
		(net "PE_TX3_DR9_P")
	)
	(segment
		(start 29.060902 -75.148948)
		(end 31.960566 -73.118472)
		(width 0.1651)
		(layer "In5.Cu")
		(net "PE_TX3_DR9_P")
	)
	(segment
		(start 6.992366 -193.548762)
		(end 7.220966 -193.320162)
		(width 0.1651)
		(layer "In5.Cu")
		(net "PE_TX3_DR9_P")
	)
	(segment
		(start 21.82114 -93.385386)
		(end 21.332444 -90.614754)
		(width 0.1651)
		(layer "In5.Cu")
		(net "PE_TX3_DR9_P")
	)
	(segment
		(start 44.397422 -103.31323)
		(end 43.210734 -101.617018)
		(width 0.1651)
		(layer "In5.Cu")
		(net "PE_TX3_DR9_P")
	)
	(segment
		(start 43.823636 -112.584992)
		(end 44.928028 -106.321352)
		(width 0.1651)
		(layer "In5.Cu")
		(net "PE_TX3_DR9_P")
	)
	(segment
		(start 43.210734 -101.617018)
		(end 40.366696 -99.626166)
		(width 0.1651)
		(layer "In5.Cu")
		(net "PE_TX3_DR9_P")
	)
	(segment
		(start 7.682484 -193.320162)
		(end 10.181844 -192.879472)
		(width 0.1651)
		(layer "In5.Cu")
		(net "PE_TX3_DR9_P")
	)
	(segment
		(start 22.376384 -84.69503)
		(end 29.060902 -75.148948)
		(width 0.1651)
		(layer "In5.Cu")
		(net "PE_TX3_DR9_P")
	)
	(segment
		(start 31.961328 -73.117964)
		(end 33.947862 -72.767952)
		(width 0.1651)
		(layer "In5.Cu")
		(net "PE_TX3_DR9_P")
	)
	(segment
		(start 35.101784 -72.767952)
		(end 35.33013 -72.996298)
		(width 0.1651)
		(layer "In5.Cu")
		(net "PE_TX3_DR9_P")
	)
	(segment
		(start 25.40381 -96.988376)
		(end 23.32355 -95.530924)
		(width 0.1651)
		(layer "In5.Cu")
		(net "PE_TX3_DR9_P")
	)
	(segment
		(start 36.103814 -146.608038)
		(end 41.531794 -115.860068)
		(width 0.1651)
		(layer "In5.Cu")
		(net "PE_TX3_DR9_P")
	)
	(segment
		(start 35.58413 -72.437498)
		(end 35.33013 -72.183498)
		(width 0.174752)
		(layer "F.Cu")
		(net "PE_TX3_DR9_N")
	)
	(segment
		(start 6.738874 -192.989454)
		(end 6.992366 -192.735962)
		(width 0.174752)
		(layer "F.Cu")
		(net "PE_TX3_DR9_N")
	)
	(segment
		(start 2.249932 -192.742058)
		(end 3.658108 -192.742058)
		(width 0.174752)
		(layer "F.Cu")
		(net "PE_TX3_DR9_N")
	)
	(segment
		(start 3.658108 -192.742058)
		(end 3.905504 -192.989454)
		(width 0.174752)
		(layer "F.Cu")
		(net "PE_TX3_DR9_N")
	)
	(segment
		(start 37.85235 -72.437498)
		(end 35.58413 -72.437498)
		(width 0.174752)
		(layer "F.Cu")
		(net "PE_TX3_DR9_N")
	)
	(segment
		(start 3.905504 -192.989454)
		(end 6.738874 -192.989454)
		(width 0.174752)
		(layer "F.Cu")
		(net "PE_TX3_DR9_N")
	)
	(segment
		(start 38.1 -72.189848)
		(end 37.85235 -72.437498)
		(width 0.174752)
		(layer "F.Cu")
		(net "PE_TX3_DR9_N")
	)
	(segment
		(start 39.200074 -72.189848)
		(end 38.1 -72.189848)
		(width 0.174752)
		(layer "F.Cu")
		(net "PE_TX3_DR9_N")
	)
	(via
		(at 35.33013 -72.183498)
		(size 0.508)
		(drill 0.254)
		(layers "F.Cu" "B.Cu")
		(net "PE_TX3_DR9_N")
	)
	(via
		(at 6.992366 -192.735962)
		(size 0.508)
		(drill 0.254)
		(layers "F.Cu" "B.Cu")
		(net "PE_TX3_DR9_N")
	)
	(segment
		(start 33.91662 -72.412352)
		(end 31.821882 -72.781414)
		(width 0.1651)
		(layer "In5.Cu")
		(net "PE_TX3_DR9_N")
	)
	(segment
		(start 43.487086 -112.445546)
		(end 41.195244 -115.720622)
		(width 0.1651)
		(layer "In5.Cu")
		(net "PE_TX3_DR9_N")
	)
	(segment
		(start 23.068026 -95.786448)
		(end 25.264364 -97.324926)
		(width 0.1651)
		(layer "In5.Cu")
		(net "PE_TX3_DR9_N")
	)
	(segment
		(start 10.042398 -192.542922)
		(end 7.651242 -192.964562)
		(width 0.1651)
		(layer "In5.Cu")
		(net "PE_TX3_DR9_N")
	)
	(segment
		(start 7.220966 -192.964562)
		(end 6.992366 -192.735962)
		(width 0.1651)
		(layer "In5.Cu")
		(net "PE_TX3_DR9_N")
	)
	(segment
		(start 22.039834 -84.55533)
		(end 20.971256 -90.614754)
		(width 0.1651)
		(layer "In5.Cu")
		(net "PE_TX3_DR9_N")
	)
	(segment
		(start 31.636716 -152.367996)
		(end 28.283154 -171.389802)
		(width 0.1651)
		(layer "In5.Cu")
		(net "PE_TX3_DR9_N")
	)
	(segment
		(start 28.805378 -74.893424)
		(end 22.039834 -84.55533)
		(width 0.1651)
		(layer "In5.Cu")
		(net "PE_TX3_DR9_N")
	)
	(segment
		(start 21.48459 -93.524832)
		(end 23.068026 -95.786448)
		(width 0.1651)
		(layer "In5.Cu")
		(net "PE_TX3_DR9_N")
	)
	(segment
		(start 44.060872 -103.452676)
		(end 44.56684 -106.321352)
		(width 0.1651)
		(layer "In5.Cu")
		(net "PE_TX3_DR9_N")
	)
	(segment
		(start 25.264364 -97.324926)
		(end 40.22725 -99.962716)
		(width 0.1651)
		(layer "In5.Cu")
		(net "PE_TX3_DR9_N")
	)
	(segment
		(start 7.651242 -192.964562)
		(end 7.220966 -192.964562)
		(width 0.1651)
		(layer "In5.Cu")
		(net "PE_TX3_DR9_N")
	)
	(segment
		(start 20.971256 -90.614754)
		(end 21.48459 -93.524832)
		(width 0.1651)
		(layer "In5.Cu")
		(net "PE_TX3_DR9_N")
	)
	(segment
		(start 35.101276 -72.412352)
		(end 33.91662 -72.412352)
		(width 0.1651)
		(layer "In5.Cu")
		(net "PE_TX3_DR9_N")
	)
	(segment
		(start 42.95521 -101.872542)
		(end 44.060872 -103.452676)
		(width 0.1651)
		(layer "In5.Cu")
		(net "PE_TX3_DR9_N")
	)
	(segment
		(start 35.33013 -72.183498)
		(end 35.101276 -72.412352)
		(width 0.1651)
		(layer "In5.Cu")
		(net "PE_TX3_DR9_N")
	)
	(segment
		(start 35.767264 -146.468592)
		(end 31.636716 -152.367996)
		(width 0.1651)
		(layer "In5.Cu")
		(net "PE_TX3_DR9_N")
	)
	(segment
		(start 44.56684 -106.321352)
		(end 43.487086 -112.445546)
		(width 0.1651)
		(layer "In5.Cu")
		(net "PE_TX3_DR9_N")
	)
	(segment
		(start 40.22725 -99.962716)
		(end 42.95521 -101.872542)
		(width 0.1651)
		(layer "In5.Cu")
		(net "PE_TX3_DR9_N")
	)
	(segment
		(start 16.77035 -187.831984)
		(end 10.042398 -192.542922)
		(width 0.1651)
		(layer "In5.Cu")
		(net "PE_TX3_DR9_N")
	)
	(segment
		(start 31.821882 -72.781414)
		(end 31.821628 -72.781414)
		(width 0.1651)
		(layer "In5.Cu")
		(net "PE_TX3_DR9_N")
	)
	(segment
		(start 28.283154 -171.389802)
		(end 16.77035 -187.831984)
		(width 0.1651)
		(layer "In5.Cu")
		(net "PE_TX3_DR9_N")
	)
	(segment
		(start 31.821628 -72.781414)
		(end 28.805378 -74.893424)
		(width 0.1651)
		(layer "In5.Cu")
		(net "PE_TX3_DR9_N")
	)
	(segment
		(start 41.195244 -115.720622)
		(end 35.767264 -146.468592)
		(width 0.1651)
		(layer "In5.Cu")
		(net "PE_TX3_DR9_N")
	)
	(segment
		(start 6.738112 -208.494376)
		(end 6.992366 -208.74863)
		(width 0.174752)
		(layer "F.Cu")
		(net "PE_TX3_DR8_P")
	)
	(segment
		(start 37.852604 -175.7426)
		(end 35.583876 -175.7426)
		(width 0.174752)
		(layer "F.Cu")
		(net "PE_TX3_DR8_P")
	)
	(segment
		(start 35.583876 -175.7426)
		(end 35.33013 -175.996346)
		(width 0.174752)
		(layer "F.Cu")
		(net "PE_TX3_DR8_P")
	)
	(segment
		(start 3.905504 -208.494376)
		(end 6.738112 -208.494376)
		(width 0.174752)
		(layer "F.Cu")
		(net "PE_TX3_DR8_P")
	)
	(segment
		(start 39.200074 -175.989996)
		(end 38.1 -175.989996)
		(width 0.174752)
		(layer "F.Cu")
		(net "PE_TX3_DR8_P")
	)
	(segment
		(start 38.1 -175.989996)
		(end 37.852604 -175.7426)
		(width 0.174752)
		(layer "F.Cu")
		(net "PE_TX3_DR8_P")
	)
	(segment
		(start 2.249932 -208.742026)
		(end 3.657854 -208.742026)
		(width 0.174752)
		(layer "F.Cu")
		(net "PE_TX3_DR8_P")
	)
	(segment
		(start 3.657854 -208.742026)
		(end 3.905504 -208.494376)
		(width 0.174752)
		(layer "F.Cu")
		(net "PE_TX3_DR8_P")
	)
	(via
		(at 6.992366 -208.74863)
		(size 0.508)
		(drill 0.254)
		(layers "F.Cu" "B.Cu")
		(net "PE_TX3_DR8_P")
	)
	(via
		(at 35.33013 -175.996346)
		(size 0.508)
		(drill 0.254)
		(layers "F.Cu" "B.Cu")
		(net "PE_TX3_DR8_P")
	)
	(segment
		(start 7.220966 -208.52003)
		(end 7.682484 -208.52003)
		(width 0.1651)
		(layer "In5.Cu")
		(net "PE_TX3_DR8_P")
	)
	(segment
		(start 35.101784 -175.768)
		(end 35.33013 -175.996346)
		(width 0.1651)
		(layer "In5.Cu")
		(net "PE_TX3_DR8_P")
	)
	(segment
		(start 33.979358 -175.768)
		(end 35.101784 -175.768)
		(width 0.1651)
		(layer "In5.Cu")
		(net "PE_TX3_DR8_P")
	)
	(segment
		(start 7.682484 -208.52003)
		(end 8.668004 -208.346294)
		(width 0.1651)
		(layer "In5.Cu")
		(net "PE_TX3_DR8_P")
	)
	(segment
		(start 8.668004 -208.346294)
		(end 9.428226 -207.814418)
		(width 0.1651)
		(layer "In5.Cu")
		(net "PE_TX3_DR8_P")
	)
	(segment
		(start 6.992366 -208.74863)
		(end 7.220966 -208.52003)
		(width 0.1651)
		(layer "In5.Cu")
		(net "PE_TX3_DR8_P")
	)
	(segment
		(start 31.77921 -176.156112)
		(end 33.979358 -175.768)
		(width 0.1651)
		(layer "In5.Cu")
		(net "PE_TX3_DR8_P")
	)
	(segment
		(start 10.7569 -204.99578)
		(end 30.154372 -177.294032)
		(width 0.1651)
		(layer "In5.Cu")
		(net "PE_TX3_DR8_P")
	)
	(segment
		(start 10.540238 -206.225902)
		(end 10.7569 -204.99578)
		(width 0.1651)
		(layer "In5.Cu")
		(net "PE_TX3_DR8_P")
	)
	(segment
		(start 9.428226 -207.814418)
		(end 10.540238 -206.225902)
		(width 0.1651)
		(layer "In5.Cu")
		(net "PE_TX3_DR8_P")
	)
	(segment
		(start 30.154372 -177.294032)
		(end 31.77921 -176.156112)
		(width 0.1651)
		(layer "In5.Cu")
		(net "PE_TX3_DR8_P")
	)
	(segment
		(start 39.200074 -175.189896)
		(end 38.09365 -175.189896)
		(width 0.174752)
		(layer "F.Cu")
		(net "PE_TX3_DR8_N")
	)
	(segment
		(start 2.249932 -207.94218)
		(end 3.658362 -207.94218)
		(width 0.174752)
		(layer "F.Cu")
		(net "PE_TX3_DR8_N")
	)
	(segment
		(start 37.846 -175.437546)
		(end 35.58413 -175.437546)
		(width 0.174752)
		(layer "F.Cu")
		(net "PE_TX3_DR8_N")
	)
	(segment
		(start 38.09365 -175.189896)
		(end 37.846 -175.437546)
		(width 0.174752)
		(layer "F.Cu")
		(net "PE_TX3_DR8_N")
	)
	(segment
		(start 3.905504 -208.189322)
		(end 6.738874 -208.189322)
		(width 0.174752)
		(layer "F.Cu")
		(net "PE_TX3_DR8_N")
	)
	(segment
		(start 6.738874 -208.189322)
		(end 6.992366 -207.93583)
		(width 0.174752)
		(layer "F.Cu")
		(net "PE_TX3_DR8_N")
	)
	(segment
		(start 35.58413 -175.437546)
		(end 35.33013 -175.183546)
		(width 0.174752)
		(layer "F.Cu")
		(net "PE_TX3_DR8_N")
	)
	(segment
		(start 3.658362 -207.94218)
		(end 3.905504 -208.189322)
		(width 0.174752)
		(layer "F.Cu")
		(net "PE_TX3_DR8_N")
	)
	(via
		(at 6.992366 -207.93583)
		(size 0.508)
		(drill 0.254)
		(layers "F.Cu" "B.Cu")
		(net "PE_TX3_DR8_N")
	)
	(via
		(at 35.33013 -175.183546)
		(size 0.508)
		(drill 0.254)
		(layers "F.Cu" "B.Cu")
		(net "PE_TX3_DR8_N")
	)
	(segment
		(start 8.528558 -208.009744)
		(end 7.651242 -208.16443)
		(width 0.1651)
		(layer "In5.Cu")
		(net "PE_TX3_DR8_N")
	)
	(segment
		(start 35.33013 -175.183546)
		(end 35.101276 -175.4124)
		(width 0.1651)
		(layer "In5.Cu")
		(net "PE_TX3_DR8_N")
	)
	(segment
		(start 29.898848 -177.038508)
		(end 10.42035 -204.856334)
		(width 0.1651)
		(layer "In5.Cu")
		(net "PE_TX3_DR8_N")
	)
	(segment
		(start 7.651242 -208.16443)
		(end 7.220966 -208.16443)
		(width 0.1651)
		(layer "In5.Cu")
		(net "PE_TX3_DR8_N")
	)
	(segment
		(start 10.203688 -206.086456)
		(end 9.172702 -207.558894)
		(width 0.1651)
		(layer "In5.Cu")
		(net "PE_TX3_DR8_N")
	)
	(segment
		(start 7.220966 -208.16443)
		(end 6.992366 -207.93583)
		(width 0.1651)
		(layer "In5.Cu")
		(net "PE_TX3_DR8_N")
	)
	(segment
		(start 33.948116 -175.4124)
		(end 31.639764 -175.819562)
		(width 0.1651)
		(layer "In5.Cu")
		(net "PE_TX3_DR8_N")
	)
	(segment
		(start 9.172702 -207.558894)
		(end 8.528558 -208.009744)
		(width 0.1651)
		(layer "In5.Cu")
		(net "PE_TX3_DR8_N")
	)
	(segment
		(start 31.639764 -175.819562)
		(end 29.898848 -177.038508)
		(width 0.1651)
		(layer "In5.Cu")
		(net "PE_TX3_DR8_N")
	)
	(segment
		(start 10.42035 -204.856334)
		(end 10.203688 -206.086456)
		(width 0.1651)
		(layer "In5.Cu")
		(net "PE_TX3_DR8_N")
	)
	(segment
		(start 35.101276 -175.4124)
		(end 33.948116 -175.4124)
		(width 0.1651)
		(layer "In5.Cu")
		(net "PE_TX3_DR8_N")
	)
	(segment
		(start 3.657854 -308.34203)
		(end 3.905504 -308.09438)
		(width 0.174752)
		(layer "F.Cu")
		(net "PE_TX3_DR7_P")
	)
	(segment
		(start 6.738112 -308.09438)
		(end 6.992366 -308.348634)
		(width 0.174752)
		(layer "F.Cu")
		(net "PE_TX3_DR7_P")
	)
	(segment
		(start 3.905504 -308.09438)
		(end 6.738112 -308.09438)
		(width 0.174752)
		(layer "F.Cu")
		(net "PE_TX3_DR7_P")
	)
	(segment
		(start 38.1 -278.990044)
		(end 37.852604 -278.742648)
		(width 0.174752)
		(layer "F.Cu")
		(net "PE_TX3_DR7_P")
	)
	(segment
		(start 35.583876 -278.742648)
		(end 35.33013 -278.996394)
		(width 0.174752)
		(layer "F.Cu")
		(net "PE_TX3_DR7_P")
	)
	(segment
		(start 37.852604 -278.742648)
		(end 35.583876 -278.742648)
		(width 0.174752)
		(layer "F.Cu")
		(net "PE_TX3_DR7_P")
	)
	(segment
		(start 2.249932 -308.34203)
		(end 3.657854 -308.34203)
		(width 0.174752)
		(layer "F.Cu")
		(net "PE_TX3_DR7_P")
	)
	(segment
		(start 39.200074 -278.990044)
		(end 38.1 -278.990044)
		(width 0.174752)
		(layer "F.Cu")
		(net "PE_TX3_DR7_P")
	)
	(via
		(at 35.33013 -278.996394)
		(size 0.508)
		(drill 0.254)
		(layers "F.Cu" "B.Cu")
		(net "PE_TX3_DR7_P")
	)
	(via
		(at 6.992366 -308.348634)
		(size 0.508)
		(drill 0.254)
		(layers "F.Cu" "B.Cu")
		(net "PE_TX3_DR7_P")
	)
	(segment
		(start 35.101784 -278.768048)
		(end 33.979358 -278.768048)
		(width 0.1651)
		(layer "In5.Cu")
		(net "PE_TX3_DR7_P")
	)
	(segment
		(start 35.33013 -278.996394)
		(end 35.101784 -278.768048)
		(width 0.1651)
		(layer "In5.Cu")
		(net "PE_TX3_DR7_P")
	)
	(segment
		(start 9.40054 -307.817266)
		(end 7.682484 -308.120034)
		(width 0.1651)
		(layer "In5.Cu")
		(net "PE_TX3_DR7_P")
	)
	(segment
		(start 29.272992 -280.984198)
		(end 11.561572 -306.27828)
		(width 0.1651)
		(layer "In5.Cu")
		(net "PE_TX3_DR7_P")
	)
	(segment
		(start 11.561572 -306.27828)
		(end 11.52525 -306.330096)
		(width 0.1651)
		(layer "In5.Cu")
		(net "PE_TX3_DR7_P")
	)
	(segment
		(start 7.682484 -308.120034)
		(end 7.220966 -308.120034)
		(width 0.1651)
		(layer "In5.Cu")
		(net "PE_TX3_DR7_P")
	)
	(segment
		(start 11.52525 -306.330096)
		(end 9.40054 -307.817266)
		(width 0.1651)
		(layer "In5.Cu")
		(net "PE_TX3_DR7_P")
	)
	(segment
		(start 31.91891 -279.131522)
		(end 29.272992 -280.984198)
		(width 0.1651)
		(layer "In5.Cu")
		(net "PE_TX3_DR7_P")
	)
	(segment
		(start 7.220966 -308.120034)
		(end 6.992366 -308.348634)
		(width 0.1651)
		(layer "In5.Cu")
		(net "PE_TX3_DR7_P")
	)
	(segment
		(start 33.979358 -278.768048)
		(end 31.91891 -279.131522)
		(width 0.1651)
		(layer "In5.Cu")
		(net "PE_TX3_DR7_P")
	)
	(segment
		(start 6.738874 -307.789326)
		(end 6.992366 -307.535834)
		(width 0.174752)
		(layer "F.Cu")
		(net "PE_TX3_DR7_N")
	)
	(segment
		(start 37.846 -278.437594)
		(end 35.58413 -278.437594)
		(width 0.174752)
		(layer "F.Cu")
		(net "PE_TX3_DR7_N")
	)
	(segment
		(start 39.200074 -278.189944)
		(end 38.09365 -278.189944)
		(width 0.174752)
		(layer "F.Cu")
		(net "PE_TX3_DR7_N")
	)
	(segment
		(start 38.09365 -278.189944)
		(end 37.846 -278.437594)
		(width 0.174752)
		(layer "F.Cu")
		(net "PE_TX3_DR7_N")
	)
	(segment
		(start 2.249932 -307.542184)
		(end 3.658362 -307.542184)
		(width 0.174752)
		(layer "F.Cu")
		(net "PE_TX3_DR7_N")
	)
	(segment
		(start 35.58413 -278.437594)
		(end 35.33013 -278.183594)
		(width 0.174752)
		(layer "F.Cu")
		(net "PE_TX3_DR7_N")
	)
	(segment
		(start 3.905504 -307.789326)
		(end 6.738874 -307.789326)
		(width 0.174752)
		(layer "F.Cu")
		(net "PE_TX3_DR7_N")
	)
	(segment
		(start 3.658362 -307.542184)
		(end 3.905504 -307.789326)
		(width 0.174752)
		(layer "F.Cu")
		(net "PE_TX3_DR7_N")
	)
	(via
		(at 6.992366 -307.535834)
		(size 0.508)
		(drill 0.254)
		(layers "F.Cu" "B.Cu")
		(net "PE_TX3_DR7_N")
	)
	(via
		(at 35.33013 -278.183594)
		(size 0.508)
		(drill 0.254)
		(layers "F.Cu" "B.Cu")
		(net "PE_TX3_DR7_N")
	)
	(segment
		(start 11.270488 -306.07381)
		(end 9.261094 -307.480716)
		(width 0.1651)
		(layer "In5.Cu")
		(net "PE_TX3_DR7_N")
	)
	(segment
		(start 7.220966 -307.764434)
		(end 6.992366 -307.535834)
		(width 0.1651)
		(layer "In5.Cu")
		(net "PE_TX3_DR7_N")
	)
	(segment
		(start 33.948116 -278.412448)
		(end 31.779464 -278.794972)
		(width 0.1651)
		(layer "In5.Cu")
		(net "PE_TX3_DR7_N")
	)
	(segment
		(start 35.101276 -278.412448)
		(end 33.948116 -278.412448)
		(width 0.1651)
		(layer "In5.Cu")
		(net "PE_TX3_DR7_N")
	)
	(segment
		(start 31.779464 -278.794972)
		(end 29.017468 -280.728674)
		(width 0.1651)
		(layer "In5.Cu")
		(net "PE_TX3_DR7_N")
	)
	(segment
		(start 29.017468 -280.728674)
		(end 11.270488 -306.07381)
		(width 0.1651)
		(layer "In5.Cu")
		(net "PE_TX3_DR7_N")
	)
	(segment
		(start 9.261094 -307.480716)
		(end 7.651242 -307.764434)
		(width 0.1651)
		(layer "In5.Cu")
		(net "PE_TX3_DR7_N")
	)
	(segment
		(start 35.33013 -278.183594)
		(end 35.101276 -278.412448)
		(width 0.1651)
		(layer "In5.Cu")
		(net "PE_TX3_DR7_N")
	)
	(segment
		(start 7.651242 -307.764434)
		(end 7.220966 -307.764434)
		(width 0.1651)
		(layer "In5.Cu")
		(net "PE_TX3_DR7_N")
	)
	(segment
		(start 37.852604 -381.742696)
		(end 35.583876 -381.742696)
		(width 0.174752)
		(layer "F.Cu")
		(net "PE_TX3_DR6_P")
	)
	(segment
		(start 3.657854 -353.942142)
		(end 3.905504 -353.694492)
		(width 0.174752)
		(layer "F.Cu")
		(net "PE_TX3_DR6_P")
	)
	(segment
		(start 2.249932 -353.942142)
		(end 3.657854 -353.942142)
		(width 0.174752)
		(layer "F.Cu")
		(net "PE_TX3_DR6_P")
	)
	(segment
		(start 39.200074 -381.990092)
		(end 38.1 -381.990092)
		(width 0.174752)
		(layer "F.Cu")
		(net "PE_TX3_DR6_P")
	)
	(segment
		(start 3.905504 -353.694492)
		(end 6.738112 -353.694492)
		(width 0.174752)
		(layer "F.Cu")
		(net "PE_TX3_DR6_P")
	)
	(segment
		(start 35.583876 -381.742696)
		(end 35.33013 -381.996442)
		(width 0.174752)
		(layer "F.Cu")
		(net "PE_TX3_DR6_P")
	)
	(segment
		(start 38.1 -381.990092)
		(end 37.852604 -381.742696)
		(width 0.174752)
		(layer "F.Cu")
		(net "PE_TX3_DR6_P")
	)
	(segment
		(start 6.738112 -353.694492)
		(end 6.992366 -353.948746)
		(width 0.174752)
		(layer "F.Cu")
		(net "PE_TX3_DR6_P")
	)
	(via
		(at 6.992366 -353.948746)
		(size 0.508)
		(drill 0.254)
		(layers "F.Cu" "B.Cu")
		(net "PE_TX3_DR6_P")
	)
	(via
		(at 35.33013 -381.996442)
		(size 0.508)
		(drill 0.254)
		(layers "F.Cu" "B.Cu")
		(net "PE_TX3_DR6_P")
	)
	(segment
		(start 15.752826 -377.97232)
		(end 17.46758 -380.421134)
		(width 0.1651)
		(layer "In5.Cu")
		(net "PE_TX3_DR6_P")
	)
	(segment
		(start 7.651242 -353.720146)
		(end 8.824214 -353.926902)
		(width 0.1651)
		(layer "In5.Cu")
		(net "PE_TX3_DR6_P")
	)
	(segment
		(start 7.220966 -353.720146)
		(end 7.651242 -353.720146)
		(width 0.1651)
		(layer "In5.Cu")
		(net "PE_TX3_DR6_P")
	)
	(segment
		(start 6.992366 -353.948746)
		(end 7.220966 -353.720146)
		(width 0.1651)
		(layer "In5.Cu")
		(net "PE_TX3_DR6_P")
	)
	(segment
		(start 8.826246 -353.928426)
		(end 10.294366 -354.956364)
		(width 0.1651)
		(layer "In5.Cu")
		(net "PE_TX3_DR6_P")
	)
	(segment
		(start 22.847046 -382.842262)
		(end 31.429706 -381.329692)
		(width 0.1651)
		(layer "In5.Cu")
		(net "PE_TX3_DR6_P")
	)
	(segment
		(start 35.101784 -381.768096)
		(end 35.33013 -381.996442)
		(width 0.1651)
		(layer "In5.Cu")
		(net "PE_TX3_DR6_P")
	)
	(segment
		(start 33.91662 -381.768096)
		(end 35.101784 -381.768096)
		(width 0.1651)
		(layer "In5.Cu")
		(net "PE_TX3_DR6_P")
	)
	(segment
		(start 17.46758 -380.421134)
		(end 20.27809 -382.38938)
		(width 0.1651)
		(layer "In5.Cu")
		(net "PE_TX3_DR6_P")
	)
	(segment
		(start 31.429706 -381.329692)
		(end 33.91662 -381.768096)
		(width 0.1651)
		(layer "In5.Cu")
		(net "PE_TX3_DR6_P")
	)
	(segment
		(start 12.159234 -357.619808)
		(end 15.752826 -377.97232)
		(width 0.1651)
		(layer "In5.Cu")
		(net "PE_TX3_DR6_P")
	)
	(segment
		(start 20.27809 -382.38938)
		(end 22.847046 -382.842262)
		(width 0.1651)
		(layer "In5.Cu")
		(net "PE_TX3_DR6_P")
	)
	(segment
		(start 10.294366 -354.956364)
		(end 12.159234 -357.619808)
		(width 0.1651)
		(layer "In5.Cu")
		(net "PE_TX3_DR6_P")
	)
	(segment
		(start 8.824214 -353.926902)
		(end 8.826246 -353.928426)
		(width 0.1651)
		(layer "In5.Cu")
		(net "PE_TX3_DR6_P")
	)
	(segment
		(start 3.658108 -353.142042)
		(end 3.905504 -353.389438)
		(width 0.174752)
		(layer "F.Cu")
		(net "PE_TX3_DR6_N")
	)
	(segment
		(start 2.249932 -353.142042)
		(end 3.658108 -353.142042)
		(width 0.174752)
		(layer "F.Cu")
		(net "PE_TX3_DR6_N")
	)
	(segment
		(start 35.58413 -381.437642)
		(end 35.33013 -381.183642)
		(width 0.174752)
		(layer "F.Cu")
		(net "PE_TX3_DR6_N")
	)
	(segment
		(start 3.905504 -353.389438)
		(end 6.738874 -353.389438)
		(width 0.174752)
		(layer "F.Cu")
		(net "PE_TX3_DR6_N")
	)
	(segment
		(start 38.1 -381.189992)
		(end 37.85235 -381.437642)
		(width 0.174752)
		(layer "F.Cu")
		(net "PE_TX3_DR6_N")
	)
	(segment
		(start 37.85235 -381.437642)
		(end 35.58413 -381.437642)
		(width 0.174752)
		(layer "F.Cu")
		(net "PE_TX3_DR6_N")
	)
	(segment
		(start 39.200074 -381.189992)
		(end 38.1 -381.189992)
		(width 0.174752)
		(layer "F.Cu")
		(net "PE_TX3_DR6_N")
	)
	(segment
		(start 6.738874 -353.389438)
		(end 6.992366 -353.135946)
		(width 0.174752)
		(layer "F.Cu")
		(net "PE_TX3_DR6_N")
	)
	(via
		(at 6.992366 -353.135946)
		(size 0.508)
		(drill 0.254)
		(layers "F.Cu" "B.Cu")
		(net "PE_TX3_DR6_N")
	)
	(via
		(at 35.33013 -381.183642)
		(size 0.508)
		(drill 0.254)
		(layers "F.Cu" "B.Cu")
		(net "PE_TX3_DR6_N")
	)
	(segment
		(start 16.089376 -377.832874)
		(end 17.723104 -380.16561)
		(width 0.1651)
		(layer "In5.Cu")
		(net "PE_TX3_DR6_N")
	)
	(segment
		(start 8.96366 -353.590352)
		(end 8.963914 -353.590352)
		(width 0.1651)
		(layer "In5.Cu")
		(net "PE_TX3_DR6_N")
	)
	(segment
		(start 7.682484 -353.364546)
		(end 8.96366 -353.590352)
		(width 0.1651)
		(layer "In5.Cu")
		(net "PE_TX3_DR6_N")
	)
	(segment
		(start 22.847046 -382.481074)
		(end 31.429706 -380.968504)
		(width 0.1651)
		(layer "In5.Cu")
		(net "PE_TX3_DR6_N")
	)
	(segment
		(start 12.495784 -357.480362)
		(end 16.089376 -377.832874)
		(width 0.1651)
		(layer "In5.Cu")
		(net "PE_TX3_DR6_N")
	)
	(segment
		(start 6.992366 -353.135946)
		(end 7.220966 -353.364546)
		(width 0.1651)
		(layer "In5.Cu")
		(net "PE_TX3_DR6_N")
	)
	(segment
		(start 7.220966 -353.364546)
		(end 7.682484 -353.364546)
		(width 0.1651)
		(layer "In5.Cu")
		(net "PE_TX3_DR6_N")
	)
	(segment
		(start 33.948116 -381.412496)
		(end 35.101276 -381.412496)
		(width 0.1651)
		(layer "In5.Cu")
		(net "PE_TX3_DR6_N")
	)
	(segment
		(start 17.723104 -380.16561)
		(end 20.417536 -382.05283)
		(width 0.1651)
		(layer "In5.Cu")
		(net "PE_TX3_DR6_N")
	)
	(segment
		(start 31.429706 -380.968504)
		(end 33.948116 -381.412496)
		(width 0.1651)
		(layer "In5.Cu")
		(net "PE_TX3_DR6_N")
	)
	(segment
		(start 10.54989 -354.70084)
		(end 12.495784 -357.480362)
		(width 0.1651)
		(layer "In5.Cu")
		(net "PE_TX3_DR6_N")
	)
	(segment
		(start 20.417536 -382.05283)
		(end 22.847046 -382.481074)
		(width 0.1651)
		(layer "In5.Cu")
		(net "PE_TX3_DR6_N")
	)
	(segment
		(start 35.101276 -381.412496)
		(end 35.33013 -381.183642)
		(width 0.1651)
		(layer "In5.Cu")
		(net "PE_TX3_DR6_N")
	)
	(segment
		(start 8.963914 -353.590352)
		(end 10.54989 -354.70084)
		(width 0.1651)
		(layer "In5.Cu")
		(net "PE_TX3_DR6_N")
	)
	(segment
		(start 2.249932 -443.141862)
		(end 3.657854 -443.141862)
		(width 0.174752)
		(layer "F.Cu")
		(net "PE_TX3_DR5_P")
	)
	(segment
		(start 37.83965 -484.19004)
		(end 37.6047 -484.42499)
		(width 0.174752)
		(layer "F.Cu")
		(net "PE_TX3_DR5_P")
	)
	(segment
		(start 37.6047 -484.42499)
		(end 35.57143 -484.42499)
		(width 0.174752)
		(layer "F.Cu")
		(net "PE_TX3_DR5_P")
	)
	(segment
		(start 6.73862 -443.438026)
		(end 6.992366 -443.18428)
		(width 0.174752)
		(layer "F.Cu")
		(net "PE_TX3_DR5_P")
	)
	(segment
		(start 3.657854 -443.141862)
		(end 3.954018 -443.438026)
		(width 0.174752)
		(layer "F.Cu")
		(net "PE_TX3_DR5_P")
	)
	(segment
		(start 3.954018 -443.438026)
		(end 6.73862 -443.438026)
		(width 0.174752)
		(layer "F.Cu")
		(net "PE_TX3_DR5_P")
	)
	(segment
		(start 35.57143 -484.42499)
		(end 35.33013 -484.18369)
		(width 0.174752)
		(layer "F.Cu")
		(net "PE_TX3_DR5_P")
	)
	(segment
		(start 39.200074 -484.19004)
		(end 37.83965 -484.19004)
		(width 0.174752)
		(layer "F.Cu")
		(net "PE_TX3_DR5_P")
	)
	(via
		(at 6.992366 -443.18428)
		(size 0.508)
		(drill 0.254)
		(layers "F.Cu" "B.Cu")
		(net "PE_TX3_DR5_P")
	)
	(via
		(at 35.33013 -484.18369)
		(size 0.508)
		(drill 0.254)
		(layers "F.Cu" "B.Cu")
		(net "PE_TX3_DR5_P")
	)
	(segment
		(start 33.948116 -484.412544)
		(end 25.909524 -482.995224)
		(width 0.1651)
		(layer "In5.Cu")
		(net "PE_TX3_DR5_P")
	)
	(segment
		(start 8.966454 -444.010288)
		(end 8.175498 -443.456822)
		(width 0.1651)
		(layer "In5.Cu")
		(net "PE_TX3_DR5_P")
	)
	(segment
		(start 35.101276 -484.412544)
		(end 33.948116 -484.412544)
		(width 0.1651)
		(layer "In5.Cu")
		(net "PE_TX3_DR5_P")
	)
	(segment
		(start 35.33013 -484.18369)
		(end 35.101276 -484.412544)
		(width 0.1651)
		(layer "In5.Cu")
		(net "PE_TX3_DR5_P")
	)
	(segment
		(start 7.220966 -443.41288)
		(end 6.992366 -443.18428)
		(width 0.1651)
		(layer "In5.Cu")
		(net "PE_TX3_DR5_P")
	)
	(segment
		(start 7.926324 -443.41288)
		(end 7.220966 -443.41288)
		(width 0.1651)
		(layer "In5.Cu")
		(net "PE_TX3_DR5_P")
	)
	(segment
		(start 19.35099 -478.402904)
		(end 14.056106 -470.840816)
		(width 0.1651)
		(layer "In5.Cu")
		(net "PE_TX3_DR5_P")
	)
	(segment
		(start 25.909524 -482.995224)
		(end 19.35099 -478.402904)
		(width 0.1651)
		(layer "In5.Cu")
		(net "PE_TX3_DR5_P")
	)
	(segment
		(start 8.175498 -443.456822)
		(end 7.926324 -443.41288)
		(width 0.1651)
		(layer "In5.Cu")
		(net "PE_TX3_DR5_P")
	)
	(segment
		(start 9.443466 -444.692024)
		(end 8.966454 -444.010288)
		(width 0.1651)
		(layer "In5.Cu")
		(net "PE_TX3_DR5_P")
	)
	(segment
		(start 14.056106 -470.840816)
		(end 9.443466 -444.692024)
		(width 0.1651)
		(layer "In5.Cu")
		(net "PE_TX3_DR5_P")
	)
	(segment
		(start 6.738366 -443.74308)
		(end 6.992366 -443.99708)
		(width 0.174752)
		(layer "F.Cu")
		(net "PE_TX3_DR5_N")
	)
	(segment
		(start 3.658108 -443.941962)
		(end 3.85699 -443.74308)
		(width 0.174752)
		(layer "F.Cu")
		(net "PE_TX3_DR5_N")
	)
	(segment
		(start 37.846 -484.99014)
		(end 37.585904 -484.730044)
		(width 0.174752)
		(layer "F.Cu")
		(net "PE_TX3_DR5_N")
	)
	(segment
		(start 2.249932 -443.941962)
		(end 3.658108 -443.941962)
		(width 0.174752)
		(layer "F.Cu")
		(net "PE_TX3_DR5_N")
	)
	(segment
		(start 3.85699 -443.74308)
		(end 6.738366 -443.74308)
		(width 0.174752)
		(layer "F.Cu")
		(net "PE_TX3_DR5_N")
	)
	(segment
		(start 37.585904 -484.730044)
		(end 35.596576 -484.730044)
		(width 0.174752)
		(layer "F.Cu")
		(net "PE_TX3_DR5_N")
	)
	(segment
		(start 35.596576 -484.730044)
		(end 35.33013 -484.99649)
		(width 0.174752)
		(layer "F.Cu")
		(net "PE_TX3_DR5_N")
	)
	(segment
		(start 39.200074 -484.99014)
		(end 37.846 -484.99014)
		(width 0.174752)
		(layer "F.Cu")
		(net "PE_TX3_DR5_N")
	)
	(via
		(at 35.33013 -484.99649)
		(size 0.508)
		(drill 0.254)
		(layers "F.Cu" "B.Cu")
		(net "PE_TX3_DR5_N")
	)
	(via
		(at 6.992366 -443.99708)
		(size 0.508)
		(drill 0.254)
		(layers "F.Cu" "B.Cu")
		(net "PE_TX3_DR5_N")
	)
	(segment
		(start 9.106916 -444.83147)
		(end 8.71093 -444.265812)
		(width 0.1651)
		(layer "In5.Cu")
		(net "PE_TX3_DR5_N")
	)
	(segment
		(start 35.33013 -484.99649)
		(end 35.101784 -484.768144)
		(width 0.1651)
		(layer "In5.Cu")
		(net "PE_TX3_DR5_N")
	)
	(segment
		(start 8.71093 -444.265812)
		(end 8.036052 -443.793372)
		(width 0.1651)
		(layer "In5.Cu")
		(net "PE_TX3_DR5_N")
	)
	(segment
		(start 13.719556 -470.980262)
		(end 9.106916 -444.83147)
		(width 0.1651)
		(layer "In5.Cu")
		(net "PE_TX3_DR5_N")
	)
	(segment
		(start 25.770078 -483.331774)
		(end 19.095466 -478.658428)
		(width 0.1651)
		(layer "In5.Cu")
		(net "PE_TX3_DR5_N")
	)
	(segment
		(start 7.895082 -443.76848)
		(end 7.220966 -443.76848)
		(width 0.1651)
		(layer "In5.Cu")
		(net "PE_TX3_DR5_N")
	)
	(segment
		(start 7.220966 -443.76848)
		(end 6.992366 -443.99708)
		(width 0.1651)
		(layer "In5.Cu")
		(net "PE_TX3_DR5_N")
	)
	(segment
		(start 33.916874 -484.768144)
		(end 25.770078 -483.331774)
		(width 0.1651)
		(layer "In5.Cu")
		(net "PE_TX3_DR5_N")
	)
	(segment
		(start 35.101784 -484.768144)
		(end 33.916874 -484.768144)
		(width 0.1651)
		(layer "In5.Cu")
		(net "PE_TX3_DR5_N")
	)
	(segment
		(start 8.036052 -443.793372)
		(end 7.895082 -443.76848)
		(width 0.1651)
		(layer "In5.Cu")
		(net "PE_TX3_DR5_N")
	)
	(segment
		(start 19.095466 -478.658428)
		(end 13.719556 -470.980262)
		(width 0.1651)
		(layer "In5.Cu")
		(net "PE_TX3_DR5_N")
	)
	(segment
		(start 3.657854 -279.541986)
		(end 3.86715 -279.33269)
		(width 0.174752)
		(layer "F.Cu")
		(net "PE_TX3_DR4_P")
	)
	(segment
		(start 222.885 -72.742552)
		(end 220.58376 -72.742552)
		(width 0.174752)
		(layer "F.Cu")
		(net "PE_TX3_DR4_P")
	)
	(segment
		(start 220.58376 -72.742552)
		(end 220.330014 -72.996298)
		(width 0.174752)
		(layer "F.Cu")
		(net "PE_TX3_DR4_P")
	)
	(segment
		(start 6.725666 -279.33269)
		(end 6.992366 -279.59939)
		(width 0.174752)
		(layer "F.Cu")
		(net "PE_TX3_DR4_P")
	)
	(segment
		(start 3.86715 -279.33269)
		(end 6.725666 -279.33269)
		(width 0.174752)
		(layer "F.Cu")
		(net "PE_TX3_DR4_P")
	)
	(segment
		(start 2.249932 -279.541986)
		(end 3.657854 -279.541986)
		(width 0.174752)
		(layer "F.Cu")
		(net "PE_TX3_DR4_P")
	)
	(segment
		(start 224.199958 -72.989948)
		(end 223.132396 -72.989948)
		(width 0.174752)
		(layer "F.Cu")
		(net "PE_TX3_DR4_P")
	)
	(segment
		(start 223.132396 -72.989948)
		(end 222.885 -72.742552)
		(width 0.174752)
		(layer "F.Cu")
		(net "PE_TX3_DR4_P")
	)
	(via
		(at 220.330014 -72.996298)
		(size 0.508)
		(drill 0.254)
		(layers "F.Cu" "B.Cu")
		(net "PE_TX3_DR4_P")
	)
	(via
		(at 6.992366 -279.59939)
		(size 0.508)
		(drill 0.254)
		(layers "F.Cu" "B.Cu")
		(net "PE_TX3_DR4_P")
	)
	(segment
		(start 7.220966 -279.37079)
		(end 6.992366 -279.59939)
		(width 0.1651)
		(layer "In5.Cu")
		(net "PE_TX3_DR4_P")
	)
	(segment
		(start 13.198094 -278.342344)
		(end 7.362952 -279.37079)
		(width 0.1651)
		(layer "In5.Cu")
		(net "PE_TX3_DR4_P")
	)
	(segment
		(start 21.792946 -272.325338)
		(end 13.198094 -278.342344)
		(width 0.1651)
		(layer "In5.Cu")
		(net "PE_TX3_DR4_P")
	)
	(segment
		(start 220.330014 -72.996298)
		(end 220.101668 -72.767952)
		(width 0.1651)
		(layer "In5.Cu")
		(net "PE_TX3_DR4_P")
	)
	(segment
		(start 211.344764 -74.10323)
		(end 89.63787 -159.325056)
		(width 0.1651)
		(layer "In5.Cu")
		(net "PE_TX3_DR4_P")
	)
	(segment
		(start 89.63787 -159.325056)
		(end 89.637616 -159.32531)
		(width 0.1651)
		(layer "In5.Cu")
		(net "PE_TX3_DR4_P")
	)
	(segment
		(start 25.718516 -257.2512)
		(end 23.486618 -269.907004)
		(width 0.1651)
		(layer "In5.Cu")
		(net "PE_TX3_DR4_P")
	)
	(segment
		(start 32.215328 -247.973342)
		(end 25.718516 -257.2512)
		(width 0.1651)
		(layer "In5.Cu")
		(net "PE_TX3_DR4_P")
	)
	(segment
		(start 7.362952 -279.37079)
		(end 7.220966 -279.37079)
		(width 0.1651)
		(layer "In5.Cu")
		(net "PE_TX3_DR4_P")
	)
	(segment
		(start 23.486618 -269.907004)
		(end 21.792946 -272.325338)
		(width 0.1651)
		(layer "In5.Cu")
		(net "PE_TX3_DR4_P")
	)
	(segment
		(start 89.637616 -159.32531)
		(end 33.800034 -239.078262)
		(width 0.1651)
		(layer "In5.Cu")
		(net "PE_TX3_DR4_P")
	)
	(segment
		(start 220.101668 -72.767952)
		(end 218.916758 -72.767952)
		(width 0.1651)
		(layer "In5.Cu")
		(net "PE_TX3_DR4_P")
	)
	(segment
		(start 218.916758 -72.767952)
		(end 211.344764 -74.10323)
		(width 0.1651)
		(layer "In5.Cu")
		(net "PE_TX3_DR4_P")
	)
	(segment
		(start 33.800034 -239.078262)
		(end 32.24276 -247.907302)
		(width 0.1651)
		(layer "In5.Cu")
		(net "PE_TX3_DR4_P")
	)
	(arc
		(start 32.24276 -247.907302)
		(mid 32.232682 -247.941836)
		(end 32.215328 -247.973342)
		(width 0.1651)
		(layer "In5.Cu")
		(net "PE_TX3_DR4_P")
	)
	(segment
		(start 224.199958 -72.189848)
		(end 223.13265 -72.189848)
		(width 0.174752)
		(layer "F.Cu")
		(net "PE_TX3_DR4_N")
	)
	(segment
		(start 220.584014 -72.437498)
		(end 220.330014 -72.183498)
		(width 0.174752)
		(layer "F.Cu")
		(net "PE_TX3_DR4_N")
	)
	(segment
		(start 3.58394 -278.74214)
		(end 3.869436 -279.027636)
		(width 0.174752)
		(layer "F.Cu")
		(net "PE_TX3_DR4_N")
	)
	(segment
		(start 222.885 -72.437498)
		(end 220.584014 -72.437498)
		(width 0.174752)
		(layer "F.Cu")
		(net "PE_TX3_DR4_N")
	)
	(segment
		(start 3.869436 -279.027636)
		(end 6.75132 -279.027636)
		(width 0.174752)
		(layer "F.Cu")
		(net "PE_TX3_DR4_N")
	)
	(segment
		(start 2.249932 -278.74214)
		(end 3.58394 -278.74214)
		(width 0.174752)
		(layer "F.Cu")
		(net "PE_TX3_DR4_N")
	)
	(segment
		(start 223.13265 -72.189848)
		(end 222.885 -72.437498)
		(width 0.174752)
		(layer "F.Cu")
		(net "PE_TX3_DR4_N")
	)
	(segment
		(start 6.75132 -279.027636)
		(end 6.992366 -278.78659)
		(width 0.174752)
		(layer "F.Cu")
		(net "PE_TX3_DR4_N")
	)
	(via
		(at 220.330014 -72.183498)
		(size 0.508)
		(drill 0.254)
		(layers "F.Cu" "B.Cu")
		(net "PE_TX3_DR4_N")
	)
	(via
		(at 6.992366 -278.78659)
		(size 0.508)
		(drill 0.254)
		(layers "F.Cu" "B.Cu")
		(net "PE_TX3_DR4_N")
	)
	(segment
		(start 7.220966 -279.01519)
		(end 6.992366 -278.78659)
		(width 0.1651)
		(layer "In5.Cu")
		(net "PE_TX3_DR4_N")
	)
	(segment
		(start 31.899606 -247.803924)
		(end 25.381966 -257.111754)
		(width 0.1651)
		(layer "In5.Cu")
		(net "PE_TX3_DR4_N")
	)
	(segment
		(start 21.537422 -272.069814)
		(end 13.058648 -278.005794)
		(width 0.1651)
		(layer "In5.Cu")
		(net "PE_TX3_DR4_N")
	)
	(segment
		(start 220.330014 -72.183498)
		(end 220.10116 -72.412352)
		(width 0.1651)
		(layer "In5.Cu")
		(net "PE_TX3_DR4_N")
	)
	(segment
		(start 31.89986 -247.803924)
		(end 31.899606 -247.803924)
		(width 0.1651)
		(layer "In5.Cu")
		(net "PE_TX3_DR4_N")
	)
	(segment
		(start 220.10116 -72.412352)
		(end 218.885516 -72.412352)
		(width 0.1651)
		(layer "In5.Cu")
		(net "PE_TX3_DR4_N")
	)
	(segment
		(start 13.058648 -278.005794)
		(end 7.33171 -279.01519)
		(width 0.1651)
		(layer "In5.Cu")
		(net "PE_TX3_DR4_N")
	)
	(segment
		(start 23.150068 -269.767558)
		(end 21.537422 -272.069814)
		(width 0.1651)
		(layer "In5.Cu")
		(net "PE_TX3_DR4_N")
	)
	(segment
		(start 89.381838 -159.069786)
		(end 33.463484 -238.938562)
		(width 0.1651)
		(layer "In5.Cu")
		(net "PE_TX3_DR4_N")
	)
	(segment
		(start 25.381966 -257.111754)
		(end 23.150068 -269.767558)
		(width 0.1651)
		(layer "In5.Cu")
		(net "PE_TX3_DR4_N")
	)
	(segment
		(start 218.885516 -72.412352)
		(end 211.205318 -73.76668)
		(width 0.1651)
		(layer "In5.Cu")
		(net "PE_TX3_DR4_N")
	)
	(segment
		(start 7.33171 -279.01519)
		(end 7.220966 -279.01519)
		(width 0.1651)
		(layer "In5.Cu")
		(net "PE_TX3_DR4_N")
	)
	(segment
		(start 211.205318 -73.76668)
		(end 89.381838 -159.069786)
		(width 0.1651)
		(layer "In5.Cu")
		(net "PE_TX3_DR4_N")
	)
	(segment
		(start 33.463484 -238.938562)
		(end 31.89986 -247.803924)
		(width 0.1651)
		(layer "In5.Cu")
		(net "PE_TX3_DR4_N")
	)
	(segment
		(start 6.738112 -295.294558)
		(end 6.992366 -295.548812)
		(width 0.174752)
		(layer "F.Cu")
		(net "PE_TX3_DR3_P")
	)
	(segment
		(start 224.199958 -175.989996)
		(end 223.139 -175.989996)
		(width 0.174752)
		(layer "F.Cu")
		(net "PE_TX3_DR3_P")
	)
	(segment
		(start 3.657854 -295.542208)
		(end 3.905504 -295.294558)
		(width 0.174752)
		(layer "F.Cu")
		(net "PE_TX3_DR3_P")
	)
	(segment
		(start 220.58376 -175.7426)
		(end 220.330014 -175.996346)
		(width 0.174752)
		(layer "F.Cu")
		(net "PE_TX3_DR3_P")
	)
	(segment
		(start 223.139 -175.989996)
		(end 222.891604 -175.7426)
		(width 0.174752)
		(layer "F.Cu")
		(net "PE_TX3_DR3_P")
	)
	(segment
		(start 222.891604 -175.7426)
		(end 220.58376 -175.7426)
		(width 0.174752)
		(layer "F.Cu")
		(net "PE_TX3_DR3_P")
	)
	(segment
		(start 3.905504 -295.294558)
		(end 6.738112 -295.294558)
		(width 0.174752)
		(layer "F.Cu")
		(net "PE_TX3_DR3_P")
	)
	(segment
		(start 2.249932 -295.542208)
		(end 3.657854 -295.542208)
		(width 0.174752)
		(layer "F.Cu")
		(net "PE_TX3_DR3_P")
	)
	(via
		(at 220.330014 -175.996346)
		(size 0.508)
		(drill 0.254)
		(layers "F.Cu" "B.Cu")
		(net "PE_TX3_DR3_P")
	)
	(via
		(at 6.992366 -295.548812)
		(size 0.508)
		(drill 0.254)
		(layers "F.Cu" "B.Cu")
		(net "PE_TX3_DR3_P")
	)
	(segment
		(start 211.9376 -177.303684)
		(end 219.160344 -175.768)
		(width 0.1651)
		(layer "In5.Cu")
		(net "PE_TX3_DR3_P")
	)
	(segment
		(start 37.741606 -240.360962)
		(end 56.87187 -213.046818)
		(width 0.1651)
		(layer "In5.Cu")
		(net "PE_TX3_DR3_P")
	)
	(segment
		(start 36.11118 -249.61342)
		(end 37.741606 -240.360962)
		(width 0.1651)
		(layer "In5.Cu")
		(net "PE_TX3_DR3_P")
	)
	(segment
		(start 9.1821 -295.658794)
		(end 11.878564 -295.183052)
		(width 0.1651)
		(layer "In5.Cu")
		(net "PE_TX3_DR3_P")
	)
	(segment
		(start 7.220966 -295.320212)
		(end 7.588504 -295.320212)
		(width 0.1651)
		(layer "In5.Cu")
		(net "PE_TX3_DR3_P")
	)
	(segment
		(start 6.992366 -295.548812)
		(end 7.220966 -295.320212)
		(width 0.1651)
		(layer "In5.Cu")
		(net "PE_TX3_DR3_P")
	)
	(segment
		(start 82.238342 -195.285106)
		(end 198.07301 -174.858934)
		(width 0.1651)
		(layer "In5.Cu")
		(net "PE_TX3_DR3_P")
	)
	(segment
		(start 7.588504 -295.320212)
		(end 9.1821 -295.658794)
		(width 0.1651)
		(layer "In5.Cu")
		(net "PE_TX3_DR3_P")
	)
	(segment
		(start 14.49832 -293.348918)
		(end 27.88412 -274.231354)
		(width 0.1651)
		(layer "In5.Cu")
		(net "PE_TX3_DR3_P")
	)
	(segment
		(start 198.07301 -174.858934)
		(end 211.9376 -177.303684)
		(width 0.1651)
		(layer "In5.Cu")
		(net "PE_TX3_DR3_P")
	)
	(segment
		(start 27.88412 -274.231354)
		(end 30.91688 -257.031744)
		(width 0.1651)
		(layer "In5.Cu")
		(net "PE_TX3_DR3_P")
	)
	(segment
		(start 220.101668 -175.768)
		(end 220.330014 -175.996346)
		(width 0.1651)
		(layer "In5.Cu")
		(net "PE_TX3_DR3_P")
	)
	(segment
		(start 56.87187 -213.046818)
		(end 82.238342 -195.285106)
		(width 0.1651)
		(layer "In5.Cu")
		(net "PE_TX3_DR3_P")
	)
	(segment
		(start 11.878564 -295.183052)
		(end 14.49832 -293.348918)
		(width 0.1651)
		(layer "In5.Cu")
		(net "PE_TX3_DR3_P")
	)
	(segment
		(start 219.160344 -175.768)
		(end 220.101668 -175.768)
		(width 0.1651)
		(layer "In5.Cu")
		(net "PE_TX3_DR3_P")
	)
	(segment
		(start 30.91688 -257.031744)
		(end 36.11118 -249.61342)
		(width 0.1651)
		(layer "In5.Cu")
		(net "PE_TX3_DR3_P")
	)
	(segment
		(start 224.199958 -175.189896)
		(end 223.139 -175.189896)
		(width 0.174752)
		(layer "F.Cu")
		(net "PE_TX3_DR3_N")
	)
	(segment
		(start 223.139 -175.189896)
		(end 222.89135 -175.437546)
		(width 0.174752)
		(layer "F.Cu")
		(net "PE_TX3_DR3_N")
	)
	(segment
		(start 222.89135 -175.437546)
		(end 220.584014 -175.437546)
		(width 0.174752)
		(layer "F.Cu")
		(net "PE_TX3_DR3_N")
	)
	(segment
		(start 3.905504 -294.989504)
		(end 6.738874 -294.989504)
		(width 0.174752)
		(layer "F.Cu")
		(net "PE_TX3_DR3_N")
	)
	(segment
		(start 3.658108 -294.742108)
		(end 3.905504 -294.989504)
		(width 0.174752)
		(layer "F.Cu")
		(net "PE_TX3_DR3_N")
	)
	(segment
		(start 220.584014 -175.437546)
		(end 220.330014 -175.183546)
		(width 0.174752)
		(layer "F.Cu")
		(net "PE_TX3_DR3_N")
	)
	(segment
		(start 6.738874 -294.989504)
		(end 6.992366 -294.736012)
		(width 0.174752)
		(layer "F.Cu")
		(net "PE_TX3_DR3_N")
	)
	(segment
		(start 2.249932 -294.742108)
		(end 3.658108 -294.742108)
		(width 0.174752)
		(layer "F.Cu")
		(net "PE_TX3_DR3_N")
	)
	(via
		(at 6.992366 -294.736012)
		(size 0.508)
		(drill 0.254)
		(layers "F.Cu" "B.Cu")
		(net "PE_TX3_DR3_N")
	)
	(via
		(at 220.330014 -175.183546)
		(size 0.508)
		(drill 0.254)
		(layers "F.Cu" "B.Cu")
		(net "PE_TX3_DR3_N")
	)
	(segment
		(start 7.220966 -294.964612)
		(end 7.625842 -294.964612)
		(width 0.1651)
		(layer "In5.Cu")
		(net "PE_TX3_DR3_N")
	)
	(segment
		(start 9.18845 -295.296336)
		(end 11.739118 -294.846502)
		(width 0.1651)
		(layer "In5.Cu")
		(net "PE_TX3_DR3_N")
	)
	(segment
		(start 56.616346 -212.791294)
		(end 82.098896 -194.948556)
		(width 0.1651)
		(layer "In5.Cu")
		(net "PE_TX3_DR3_N")
	)
	(segment
		(start 37.405056 -240.221516)
		(end 56.616346 -212.791294)
		(width 0.1651)
		(layer "In5.Cu")
		(net "PE_TX3_DR3_N")
	)
	(segment
		(start 27.54757 -274.091908)
		(end 30.58033 -256.892298)
		(width 0.1651)
		(layer "In5.Cu")
		(net "PE_TX3_DR3_N")
	)
	(segment
		(start 7.625842 -294.964612)
		(end 9.18845 -295.296336)
		(width 0.1651)
		(layer "In5.Cu")
		(net "PE_TX3_DR3_N")
	)
	(segment
		(start 211.93125 -176.941226)
		(end 219.122752 -175.4124)
		(width 0.1651)
		(layer "In5.Cu")
		(net "PE_TX3_DR3_N")
	)
	(segment
		(start 220.10116 -175.4124)
		(end 220.330014 -175.183546)
		(width 0.1651)
		(layer "In5.Cu")
		(net "PE_TX3_DR3_N")
	)
	(segment
		(start 11.739118 -294.846502)
		(end 14.242796 -293.093394)
		(width 0.1651)
		(layer "In5.Cu")
		(net "PE_TX3_DR3_N")
	)
	(segment
		(start 14.242796 -293.093394)
		(end 27.54757 -274.091908)
		(width 0.1651)
		(layer "In5.Cu")
		(net "PE_TX3_DR3_N")
	)
	(segment
		(start 82.098896 -194.948556)
		(end 198.07301 -174.497746)
		(width 0.1651)
		(layer "In5.Cu")
		(net "PE_TX3_DR3_N")
	)
	(segment
		(start 198.07301 -174.497746)
		(end 211.93125 -176.941226)
		(width 0.1651)
		(layer "In5.Cu")
		(net "PE_TX3_DR3_N")
	)
	(segment
		(start 30.58033 -256.892298)
		(end 35.77463 -249.473974)
		(width 0.1651)
		(layer "In5.Cu")
		(net "PE_TX3_DR3_N")
	)
	(segment
		(start 6.992366 -294.736012)
		(end 7.220966 -294.964612)
		(width 0.1651)
		(layer "In5.Cu")
		(net "PE_TX3_DR3_N")
	)
	(segment
		(start 35.77463 -249.473974)
		(end 37.405056 -240.221516)
		(width 0.1651)
		(layer "In5.Cu")
		(net "PE_TX3_DR3_N")
	)
	(segment
		(start 219.122752 -175.4124)
		(end 220.10116 -175.4124)
		(width 0.1651)
		(layer "In5.Cu")
		(net "PE_TX3_DR3_N")
	)
	(segment
		(start 2.249932 -325.942198)
		(end 3.657854 -325.942198)
		(width 0.174752)
		(layer "F.Cu")
		(net "PE_TX3_DR2_P")
	)
	(segment
		(start 220.58376 -278.742648)
		(end 220.330014 -278.996394)
		(width 0.174752)
		(layer "F.Cu")
		(net "PE_TX3_DR2_P")
	)
	(segment
		(start 3.905504 -325.694548)
		(end 6.738112 -325.694548)
		(width 0.174752)
		(layer "F.Cu")
		(net "PE_TX3_DR2_P")
	)
	(segment
		(start 222.885 -278.742648)
		(end 220.58376 -278.742648)
		(width 0.174752)
		(layer "F.Cu")
		(net "PE_TX3_DR2_P")
	)
	(segment
		(start 223.132396 -278.990044)
		(end 222.885 -278.742648)
		(width 0.174752)
		(layer "F.Cu")
		(net "PE_TX3_DR2_P")
	)
	(segment
		(start 3.657854 -325.942198)
		(end 3.905504 -325.694548)
		(width 0.174752)
		(layer "F.Cu")
		(net "PE_TX3_DR2_P")
	)
	(segment
		(start 6.738112 -325.694548)
		(end 6.992366 -325.948802)
		(width 0.174752)
		(layer "F.Cu")
		(net "PE_TX3_DR2_P")
	)
	(segment
		(start 224.199958 -278.990044)
		(end 223.132396 -278.990044)
		(width 0.174752)
		(layer "F.Cu")
		(net "PE_TX3_DR2_P")
	)
	(via
		(at 6.992366 -325.948802)
		(size 0.508)
		(drill 0.254)
		(layers "F.Cu" "B.Cu")
		(net "PE_TX3_DR2_P")
	)
	(via
		(at 220.330014 -278.996394)
		(size 0.508)
		(drill 0.254)
		(layers "F.Cu" "B.Cu")
		(net "PE_TX3_DR2_P")
	)
	(segment
		(start 218.916758 -278.768048)
		(end 173.964092 -270.841724)
		(width 0.1651)
		(layer "In5.Cu")
		(net "PE_TX3_DR2_P")
	)
	(segment
		(start 7.682484 -325.720202)
		(end 7.220966 -325.720202)
		(width 0.1651)
		(layer "In5.Cu")
		(net "PE_TX3_DR2_P")
	)
	(segment
		(start 8.706866 -325.53402)
		(end 8.699246 -325.54164)
		(width 0.1651)
		(layer "In5.Cu")
		(net "PE_TX3_DR2_P")
	)
	(segment
		(start 173.964092 -270.841724)
		(end 173.961044 -270.841216)
		(width 0.1651)
		(layer "In5.Cu")
		(net "PE_TX3_DR2_P")
	)
	(segment
		(start 173.961044 -270.841216)
		(end 67.550792 -289.59937)
		(width 0.1651)
		(layer "In5.Cu")
		(net "PE_TX3_DR2_P")
	)
	(segment
		(start 39.104824 -305.97729)
		(end 23.244048 -303.181258)
		(width 0.1651)
		(layer "In5.Cu")
		(net "PE_TX3_DR2_P")
	)
	(segment
		(start 45.8597 -304.78603)
		(end 39.104824 -305.97729)
		(width 0.1651)
		(layer "In5.Cu")
		(net "PE_TX3_DR2_P")
	)
	(segment
		(start 13.401294 -320.54419)
		(end 11.06297 -323.88429)
		(width 0.1651)
		(layer "In5.Cu")
		(net "PE_TX3_DR2_P")
	)
	(segment
		(start 220.330014 -278.996394)
		(end 220.101668 -278.768048)
		(width 0.1651)
		(layer "In5.Cu")
		(net "PE_TX3_DR2_P")
	)
	(segment
		(start 15.597378 -308.103524)
		(end 13.401294 -320.54419)
		(width 0.1651)
		(layer "In5.Cu")
		(net "PE_TX3_DR2_P")
	)
	(segment
		(start 8.695944 -325.54164)
		(end 7.682484 -325.720202)
		(width 0.1651)
		(layer "In5.Cu")
		(net "PE_TX3_DR2_P")
	)
	(segment
		(start 23.244048 -303.181258)
		(end 20.825968 -303.60747)
		(width 0.1651)
		(layer "In5.Cu")
		(net "PE_TX3_DR2_P")
	)
	(segment
		(start 220.101668 -278.768048)
		(end 218.916758 -278.768048)
		(width 0.1651)
		(layer "In5.Cu")
		(net "PE_TX3_DR2_P")
	)
	(segment
		(start 20.825968 -303.60747)
		(end 16.74495 -306.465224)
		(width 0.1651)
		(layer "In5.Cu")
		(net "PE_TX3_DR2_P")
	)
	(segment
		(start 8.699246 -325.54164)
		(end 8.695944 -325.54164)
		(width 0.1651)
		(layer "In5.Cu")
		(net "PE_TX3_DR2_P")
	)
	(segment
		(start 16.74495 -306.465224)
		(end 15.597378 -308.103524)
		(width 0.1651)
		(layer "In5.Cu")
		(net "PE_TX3_DR2_P")
	)
	(segment
		(start 7.220966 -325.720202)
		(end 6.992366 -325.948802)
		(width 0.1651)
		(layer "In5.Cu")
		(net "PE_TX3_DR2_P")
	)
	(segment
		(start 11.06297 -323.88429)
		(end 11.062462 -323.884544)
		(width 0.1651)
		(layer "In5.Cu")
		(net "PE_TX3_DR2_P")
	)
	(segment
		(start 67.550792 -289.59937)
		(end 45.8597 -304.78603)
		(width 0.1651)
		(layer "In5.Cu")
		(net "PE_TX3_DR2_P")
	)
	(segment
		(start 11.062462 -323.884544)
		(end 8.706866 -325.53402)
		(width 0.1651)
		(layer "In5.Cu")
		(net "PE_TX3_DR2_P")
	)
	(segment
		(start 223.139 -278.189944)
		(end 222.89135 -278.437594)
		(width 0.174752)
		(layer "F.Cu")
		(net "PE_TX3_DR2_N")
	)
	(segment
		(start 222.89135 -278.437594)
		(end 220.584014 -278.437594)
		(width 0.174752)
		(layer "F.Cu")
		(net "PE_TX3_DR2_N")
	)
	(segment
		(start 220.584014 -278.437594)
		(end 220.330014 -278.183594)
		(width 0.174752)
		(layer "F.Cu")
		(net "PE_TX3_DR2_N")
	)
	(segment
		(start 3.905504 -325.389494)
		(end 6.738874 -325.389494)
		(width 0.174752)
		(layer "F.Cu")
		(net "PE_TX3_DR2_N")
	)
	(segment
		(start 3.658108 -325.142098)
		(end 3.905504 -325.389494)
		(width 0.174752)
		(layer "F.Cu")
		(net "PE_TX3_DR2_N")
	)
	(segment
		(start 224.199958 -278.189944)
		(end 223.139 -278.189944)
		(width 0.174752)
		(layer "F.Cu")
		(net "PE_TX3_DR2_N")
	)
	(segment
		(start 2.249932 -325.142098)
		(end 3.658108 -325.142098)
		(width 0.174752)
		(layer "F.Cu")
		(net "PE_TX3_DR2_N")
	)
	(segment
		(start 6.738874 -325.389494)
		(end 6.992366 -325.136002)
		(width 0.174752)
		(layer "F.Cu")
		(net "PE_TX3_DR2_N")
	)
	(via
		(at 6.992366 -325.136002)
		(size 0.508)
		(drill 0.254)
		(layers "F.Cu" "B.Cu")
		(net "PE_TX3_DR2_N")
	)
	(via
		(at 220.330014 -278.183594)
		(size 0.508)
		(drill 0.254)
		(layers "F.Cu" "B.Cu")
		(net "PE_TX3_DR2_N")
	)
	(segment
		(start 10.8077 -323.628512)
		(end 10.806938 -323.62902)
		(width 0.1651)
		(layer "In5.Cu")
		(net "PE_TX3_DR2_N")
	)
	(segment
		(start 8.556498 -325.20509)
		(end 7.651242 -325.364602)
		(width 0.1651)
		(layer "In5.Cu")
		(net "PE_TX3_DR2_N")
	)
	(segment
		(start 23.244048 -302.82007)
		(end 20.686522 -303.27092)
		(width 0.1651)
		(layer "In5.Cu")
		(net "PE_TX3_DR2_N")
	)
	(segment
		(start 10.808208 -323.62775)
		(end 10.8077 -323.628512)
		(width 0.1651)
		(layer "In5.Cu")
		(net "PE_TX3_DR2_N")
	)
	(segment
		(start 67.411346 -289.26282)
		(end 45.720254 -304.44948)
		(width 0.1651)
		(layer "In5.Cu")
		(net "PE_TX3_DR2_N")
	)
	(segment
		(start 218.948 -278.412448)
		(end 173.964092 -270.480536)
		(width 0.1651)
		(layer "In5.Cu")
		(net "PE_TX3_DR2_N")
	)
	(segment
		(start 220.330014 -278.183594)
		(end 220.10116 -278.412448)
		(width 0.1651)
		(layer "In5.Cu")
		(net "PE_TX3_DR2_N")
	)
	(segment
		(start 13.064744 -320.404744)
		(end 10.808208 -323.62775)
		(width 0.1651)
		(layer "In5.Cu")
		(net "PE_TX3_DR2_N")
	)
	(segment
		(start 45.720254 -304.44948)
		(end 39.104824 -305.616102)
		(width 0.1651)
		(layer "In5.Cu")
		(net "PE_TX3_DR2_N")
	)
	(segment
		(start 10.806938 -323.62902)
		(end 8.556498 -325.20509)
		(width 0.1651)
		(layer "In5.Cu")
		(net "PE_TX3_DR2_N")
	)
	(segment
		(start 173.964092 -270.480536)
		(end 173.961044 -270.480028)
		(width 0.1651)
		(layer "In5.Cu")
		(net "PE_TX3_DR2_N")
	)
	(segment
		(start 7.220966 -325.364602)
		(end 6.992366 -325.136002)
		(width 0.1651)
		(layer "In5.Cu")
		(net "PE_TX3_DR2_N")
	)
	(segment
		(start 39.104824 -305.616102)
		(end 23.244048 -302.82007)
		(width 0.1651)
		(layer "In5.Cu")
		(net "PE_TX3_DR2_N")
	)
	(segment
		(start 7.651242 -325.364602)
		(end 7.220966 -325.364602)
		(width 0.1651)
		(layer "In5.Cu")
		(net "PE_TX3_DR2_N")
	)
	(segment
		(start 220.10116 -278.412448)
		(end 218.948 -278.412448)
		(width 0.1651)
		(layer "In5.Cu")
		(net "PE_TX3_DR2_N")
	)
	(segment
		(start 20.686522 -303.27092)
		(end 16.489426 -306.2097)
		(width 0.1651)
		(layer "In5.Cu")
		(net "PE_TX3_DR2_N")
	)
	(segment
		(start 16.489426 -306.2097)
		(end 15.260828 -307.964078)
		(width 0.1651)
		(layer "In5.Cu")
		(net "PE_TX3_DR2_N")
	)
	(segment
		(start 173.961044 -270.480028)
		(end 67.411346 -289.26282)
		(width 0.1651)
		(layer "In5.Cu")
		(net "PE_TX3_DR2_N")
	)
	(segment
		(start 15.260828 -307.964078)
		(end 13.064744 -320.404744)
		(width 0.1651)
		(layer "In5.Cu")
		(net "PE_TX3_DR2_N")
	)
	(segment
		(start 22.800056 -21.009864)
		(end 23.876 -21.009864)
		(width 0.174752)
		(layer "F.Cu")
		(net "PE_TX3_DR14_P")
	)
	(segment
		(start 24.123396 -21.25726)
		(end 26.416254 -21.25726)
		(width 0.174752)
		(layer "F.Cu")
		(net "PE_TX3_DR14_P")
	)
	(segment
		(start 3.85445 -159.745426)
		(end 6.738366 -159.745426)
		(width 0.174752)
		(layer "F.Cu")
		(net "PE_TX3_DR14_P")
	)
	(segment
		(start 6.738366 -159.745426)
		(end 6.992366 -159.999426)
		(width 0.174752)
		(layer "F.Cu")
		(net "PE_TX3_DR14_P")
	)
	(segment
		(start 26.416254 -21.25726)
		(end 26.67 -21.003514)
		(width 0.174752)
		(layer "F.Cu")
		(net "PE_TX3_DR14_P")
	)
	(segment
		(start 2.249932 -159.942022)
		(end 3.657854 -159.942022)
		(width 0.174752)
		(layer "F.Cu")
		(net "PE_TX3_DR14_P")
	)
	(segment
		(start 3.657854 -159.942022)
		(end 3.85445 -159.745426)
		(width 0.174752)
		(layer "F.Cu")
		(net "PE_TX3_DR14_P")
	)
	(segment
		(start 23.876 -21.009864)
		(end 24.123396 -21.25726)
		(width 0.174752)
		(layer "F.Cu")
		(net "PE_TX3_DR14_P")
	)
	(via
		(at 6.992366 -159.999426)
		(size 0.508)
		(drill 0.254)
		(layers "F.Cu" "B.Cu")
		(net "PE_TX3_DR14_P")
	)
	(via
		(at 26.67 -21.003514)
		(size 0.508)
		(drill 0.254)
		(layers "F.Cu" "B.Cu")
		(net "PE_TX3_DR14_P")
	)
	(segment
		(start 26.67 -21.003514)
		(end 26.898346 -21.23186)
		(width 0.1651)
		(layer "In5.Cu")
		(net "PE_TX3_DR14_P")
	)
	(segment
		(start 7.848854 -159.685228)
		(end 7.363206 -159.770826)
		(width 0.1651)
		(layer "In5.Cu")
		(net "PE_TX3_DR14_P")
	)
	(segment
		(start 7.220966 -159.770826)
		(end 6.992366 -159.999426)
		(width 0.1651)
		(layer "In5.Cu")
		(net "PE_TX3_DR14_P")
	)
	(segment
		(start 7.363206 -159.770826)
		(end 7.220966 -159.770826)
		(width 0.1651)
		(layer "In5.Cu")
		(net "PE_TX3_DR14_P")
	)
	(segment
		(start 34.695384 -30.941772)
		(end 28.679394 -65.050416)
		(width 0.1651)
		(layer "In5.Cu")
		(net "PE_TX3_DR14_P")
	)
	(segment
		(start 30.986222 -22.53361)
		(end 33.96234 -26.7843)
		(width 0.1651)
		(layer "In5.Cu")
		(net "PE_TX3_DR14_P")
	)
	(segment
		(start 28.679394 -65.050416)
		(end 16.531844 -82.3976)
		(width 0.1651)
		(layer "In5.Cu")
		(net "PE_TX3_DR14_P")
	)
	(segment
		(start 14.92504 -140.85316)
		(end 12.276328 -155.87218)
		(width 0.1651)
		(layer "In5.Cu")
		(net "PE_TX3_DR14_P")
	)
	(segment
		(start 11.295634 -157.27299)
		(end 7.848854 -159.685228)
		(width 0.1651)
		(layer "In5.Cu")
		(net "PE_TX3_DR14_P")
	)
	(segment
		(start 29.903166 -21.77542)
		(end 30.986222 -22.53361)
		(width 0.1651)
		(layer "In5.Cu")
		(net "PE_TX3_DR14_P")
	)
	(segment
		(start 28.970478 -21.388324)
		(end 29.903166 -21.77542)
		(width 0.1651)
		(layer "In5.Cu")
		(net "PE_TX3_DR14_P")
	)
	(segment
		(start 33.96234 -26.7843)
		(end 34.695384 -30.941772)
		(width 0.1651)
		(layer "In5.Cu")
		(net "PE_TX3_DR14_P")
	)
	(segment
		(start 16.531844 -82.3976)
		(end 10.574274 -116.183918)
		(width 0.1651)
		(layer "In5.Cu")
		(net "PE_TX3_DR14_P")
	)
	(segment
		(start 12.276328 -155.87218)
		(end 11.295634 -157.27299)
		(width 0.1651)
		(layer "In5.Cu")
		(net "PE_TX3_DR14_P")
	)
	(segment
		(start 28.083256 -21.23186)
		(end 28.970478 -21.388324)
		(width 0.1651)
		(layer "In5.Cu")
		(net "PE_TX3_DR14_P")
	)
	(segment
		(start 10.574274 -116.183918)
		(end 14.92504 -140.85316)
		(width 0.1651)
		(layer "In5.Cu")
		(net "PE_TX3_DR14_P")
	)
	(segment
		(start 26.898346 -21.23186)
		(end 28.083256 -21.23186)
		(width 0.1651)
		(layer "In5.Cu")
		(net "PE_TX3_DR14_P")
	)
	(segment
		(start 24.13 -21.562314)
		(end 26.416 -21.562314)
		(width 0.174752)
		(layer "F.Cu")
		(net "PE_TX3_DR14_N")
	)
	(segment
		(start 3.95605 -159.440372)
		(end 6.73862 -159.440372)
		(width 0.174752)
		(layer "F.Cu")
		(net "PE_TX3_DR14_N")
	)
	(segment
		(start 23.88235 -21.809964)
		(end 24.13 -21.562314)
		(width 0.174752)
		(layer "F.Cu")
		(net "PE_TX3_DR14_N")
	)
	(segment
		(start 3.657854 -159.142176)
		(end 3.95605 -159.440372)
		(width 0.174752)
		(layer "F.Cu")
		(net "PE_TX3_DR14_N")
	)
	(segment
		(start 22.800056 -21.809964)
		(end 23.88235 -21.809964)
		(width 0.174752)
		(layer "F.Cu")
		(net "PE_TX3_DR14_N")
	)
	(segment
		(start 2.249932 -159.142176)
		(end 3.657854 -159.142176)
		(width 0.174752)
		(layer "F.Cu")
		(net "PE_TX3_DR14_N")
	)
	(segment
		(start 26.416 -21.562314)
		(end 26.67 -21.816314)
		(width 0.174752)
		(layer "F.Cu")
		(net "PE_TX3_DR14_N")
	)
	(segment
		(start 6.73862 -159.440372)
		(end 6.992366 -159.186626)
		(width 0.174752)
		(layer "F.Cu")
		(net "PE_TX3_DR14_N")
	)
	(via
		(at 26.67 -21.816314)
		(size 0.508)
		(drill 0.254)
		(layers "F.Cu" "B.Cu")
		(net "PE_TX3_DR14_N")
	)
	(via
		(at 6.992366 -159.186626)
		(size 0.508)
		(drill 0.254)
		(layers "F.Cu" "B.Cu")
		(net "PE_TX3_DR14_N")
	)
	(segment
		(start 31.75254 -24.576024)
		(end 32.036512 -24.981662)
		(width 0.1651)
		(layer "In5.Cu")
		(net "PE_TX3_DR14_N")
	)
	(segment
		(start 34.030412 -31.582106)
		(end 33.944306 -32.069786)
		(width 0.1651)
		(layer "In5.Cu")
		(net "PE_TX3_DR14_N")
	)
	(segment
		(start 9.234678 -158.281116)
		(end 8.82904 -158.565088)
		(width 0.1651)
		(layer "In5.Cu")
		(net "PE_TX3_DR14_N")
	)
	(segment
		(start 32.582358 -25.433528)
		(end 32.53613 -25.695402)
		(width 0.1651)
		(layer "In5.Cu")
		(net "PE_TX3_DR14_N")
	)
	(segment
		(start 7.331964 -159.415226)
		(end 7.220966 -159.415226)
		(width 0.1651)
		(layer "In5.Cu")
		(net "PE_TX3_DR14_N")
	)
	(segment
		(start 26.67 -21.816314)
		(end 26.898854 -21.58746)
		(width 0.1651)
		(layer "In5.Cu")
		(net "PE_TX3_DR14_N")
	)
	(segment
		(start 34.096706 -32.287464)
		(end 34.010854 -32.775398)
		(width 0.1651)
		(layer "In5.Cu")
		(net "PE_TX3_DR14_N")
	)
	(segment
		(start 28.342844 -64.91097)
		(end 16.195294 -82.258154)
		(width 0.1651)
		(layer "In5.Cu")
		(net "PE_TX3_DR14_N")
	)
	(segment
		(start 33.944306 -32.069786)
		(end 34.096706 -32.287464)
		(width 0.1651)
		(layer "In5.Cu")
		(net "PE_TX3_DR14_N")
	)
	(segment
		(start 31.798514 -24.31415)
		(end 31.75254 -24.576024)
		(width 0.1651)
		(layer "In5.Cu")
		(net "PE_TX3_DR14_N")
	)
	(segment
		(start 33.85947 -33.633156)
		(end 28.342844 -64.91097)
		(width 0.1651)
		(layer "In5.Cu")
		(net "PE_TX3_DR14_N")
	)
	(segment
		(start 32.298386 -25.02789)
		(end 32.582358 -25.433528)
		(width 0.1651)
		(layer "In5.Cu")
		(net "PE_TX3_DR14_N")
	)
	(segment
		(start 34.010854 -32.775398)
		(end 33.792922 -32.927798)
		(width 0.1651)
		(layer "In5.Cu")
		(net "PE_TX3_DR14_N")
	)
	(segment
		(start 7.709408 -159.348678)
		(end 7.331964 -159.415226)
		(width 0.1651)
		(layer "In5.Cu")
		(net "PE_TX3_DR14_N")
	)
	(segment
		(start 9.686798 -157.73527)
		(end 9.280906 -158.019242)
		(width 0.1651)
		(layer "In5.Cu")
		(net "PE_TX3_DR14_N")
	)
	(segment
		(start 16.195294 -82.258154)
		(end 10.213086 -116.183918)
		(width 0.1651)
		(layer "In5.Cu")
		(net "PE_TX3_DR14_N")
	)
	(segment
		(start 9.948418 -157.781498)
		(end 9.686798 -157.73527)
		(width 0.1651)
		(layer "In5.Cu")
		(net "PE_TX3_DR14_N")
	)
	(segment
		(start 33.70707 -33.415478)
		(end 33.85947 -33.633156)
		(width 0.1651)
		(layer "In5.Cu")
		(net "PE_TX3_DR14_N")
	)
	(segment
		(start 8.567166 -158.51886)
		(end 8.161274 -158.802832)
		(width 0.1651)
		(layer "In5.Cu")
		(net "PE_TX3_DR14_N")
	)
	(segment
		(start 28.869894 -21.731732)
		(end 29.730954 -22.08911)
		(width 0.1651)
		(layer "In5.Cu")
		(net "PE_TX3_DR14_N")
	)
	(segment
		(start 8.161274 -158.802832)
		(end 8.1153 -159.064706)
		(width 0.1651)
		(layer "In5.Cu")
		(net "PE_TX3_DR14_N")
	)
	(segment
		(start 11.939778 -155.732734)
		(end 11.04011 -157.017466)
		(width 0.1651)
		(layer "In5.Cu")
		(net "PE_TX3_DR14_N")
	)
	(segment
		(start 30.730698 -22.789134)
		(end 31.01467 -23.194772)
		(width 0.1651)
		(layer "In5.Cu")
		(net "PE_TX3_DR14_N")
	)
	(segment
		(start 7.220966 -159.415226)
		(end 6.992366 -159.186626)
		(width 0.1651)
		(layer "In5.Cu")
		(net "PE_TX3_DR14_N")
	)
	(segment
		(start 26.898854 -21.58746)
		(end 28.052014 -21.58746)
		(width 0.1651)
		(layer "In5.Cu")
		(net "PE_TX3_DR14_N")
	)
	(segment
		(start 11.04011 -157.017466)
		(end 9.948418 -157.781498)
		(width 0.1651)
		(layer "In5.Cu")
		(net "PE_TX3_DR14_N")
	)
	(segment
		(start 34.334196 -30.941772)
		(end 34.24809 -31.429452)
		(width 0.1651)
		(layer "In5.Cu")
		(net "PE_TX3_DR14_N")
	)
	(segment
		(start 32.53613 -25.695402)
		(end 32.820356 -26.10104)
		(width 0.1651)
		(layer "In5.Cu")
		(net "PE_TX3_DR14_N")
	)
	(segment
		(start 29.730954 -22.08911)
		(end 30.730698 -22.789134)
		(width 0.1651)
		(layer "In5.Cu")
		(net "PE_TX3_DR14_N")
	)
	(segment
		(start 10.213086 -116.183918)
		(end 14.563852 -140.85316)
		(width 0.1651)
		(layer "In5.Cu")
		(net "PE_TX3_DR14_N")
	)
	(segment
		(start 34.24809 -31.429452)
		(end 34.030412 -31.582106)
		(width 0.1651)
		(layer "In5.Cu")
		(net "PE_TX3_DR14_N")
	)
	(segment
		(start 32.820356 -26.10104)
		(end 33.08223 -26.147268)
		(width 0.1651)
		(layer "In5.Cu")
		(net "PE_TX3_DR14_N")
	)
	(segment
		(start 8.1153 -159.064706)
		(end 7.709408 -159.348678)
		(width 0.1651)
		(layer "In5.Cu")
		(net "PE_TX3_DR14_N")
	)
	(segment
		(start 31.01467 -23.194772)
		(end 30.968696 -23.456646)
		(width 0.1651)
		(layer "In5.Cu")
		(net "PE_TX3_DR14_N")
	)
	(segment
		(start 30.968696 -23.456646)
		(end 31.252668 -23.862284)
		(width 0.1651)
		(layer "In5.Cu")
		(net "PE_TX3_DR14_N")
	)
	(segment
		(start 33.08223 -26.147268)
		(end 33.62579 -26.923746)
		(width 0.1651)
		(layer "In5.Cu")
		(net "PE_TX3_DR14_N")
	)
	(segment
		(start 32.036512 -24.981662)
		(end 32.298386 -25.02789)
		(width 0.1651)
		(layer "In5.Cu")
		(net "PE_TX3_DR14_N")
	)
	(segment
		(start 9.280906 -158.019242)
		(end 9.234678 -158.281116)
		(width 0.1651)
		(layer "In5.Cu")
		(net "PE_TX3_DR14_N")
	)
	(segment
		(start 31.252668 -23.862284)
		(end 31.514542 -23.908512)
		(width 0.1651)
		(layer "In5.Cu")
		(net "PE_TX3_DR14_N")
	)
	(segment
		(start 14.563852 -140.85316)
		(end 11.939778 -155.732734)
		(width 0.1651)
		(layer "In5.Cu")
		(net "PE_TX3_DR14_N")
	)
	(segment
		(start 33.792922 -32.927798)
		(end 33.70707 -33.415478)
		(width 0.1651)
		(layer "In5.Cu")
		(net "PE_TX3_DR14_N")
	)
	(segment
		(start 8.82904 -158.565088)
		(end 8.567166 -158.51886)
		(width 0.1651)
		(layer "In5.Cu")
		(net "PE_TX3_DR14_N")
	)
	(segment
		(start 31.514542 -23.908512)
		(end 31.798514 -24.31415)
		(width 0.1651)
		(layer "In5.Cu")
		(net "PE_TX3_DR14_N")
	)
	(segment
		(start 33.62579 -26.923746)
		(end 34.334196 -30.941772)
		(width 0.1651)
		(layer "In5.Cu")
		(net "PE_TX3_DR14_N")
	)
	(segment
		(start 28.052014 -21.58746)
		(end 28.869894 -21.731732)
		(width 0.1651)
		(layer "In5.Cu")
		(net "PE_TX3_DR14_N")
	)
	(segment
		(start 3.85445 -175.745394)
		(end 6.738366 -175.745394)
		(width 0.174752)
		(layer "F.Cu")
		(net "PE_TX3_DR13_P")
	)
	(segment
		(start 22.800056 -124.009912)
		(end 23.882604 -124.009912)
		(width 0.174752)
		(layer "F.Cu")
		(net "PE_TX3_DR13_P")
	)
	(segment
		(start 23.882604 -124.009912)
		(end 24.13 -124.257308)
		(width 0.174752)
		(layer "F.Cu")
		(net "PE_TX3_DR13_P")
	)
	(segment
		(start 26.416254 -124.257308)
		(end 26.67 -124.003562)
		(width 0.174752)
		(layer "F.Cu")
		(net "PE_TX3_DR13_P")
	)
	(segment
		(start 2.249932 -175.94199)
		(end 3.657854 -175.94199)
		(width 0.174752)
		(layer "F.Cu")
		(net "PE_TX3_DR13_P")
	)
	(segment
		(start 24.13 -124.257308)
		(end 26.416254 -124.257308)
		(width 0.174752)
		(layer "F.Cu")
		(net "PE_TX3_DR13_P")
	)
	(segment
		(start 3.657854 -175.94199)
		(end 3.85445 -175.745394)
		(width 0.174752)
		(layer "F.Cu")
		(net "PE_TX3_DR13_P")
	)
	(segment
		(start 6.738366 -175.745394)
		(end 6.992366 -175.999394)
		(width 0.174752)
		(layer "F.Cu")
		(net "PE_TX3_DR13_P")
	)
	(via
		(at 26.67 -124.003562)
		(size 0.508)
		(drill 0.254)
		(layers "F.Cu" "B.Cu")
		(net "PE_TX3_DR13_P")
	)
	(via
		(at 6.992366 -175.999394)
		(size 0.508)
		(drill 0.254)
		(layers "F.Cu" "B.Cu")
		(net "PE_TX3_DR13_P")
	)
	(segment
		(start 28.399232 -148.856192)
		(end 28.399232 -148.855938)
		(width 0.1651)
		(layer "In5.Cu")
		(net "PE_TX3_DR13_P")
	)
	(segment
		(start 24.996394 -168.148508)
		(end 23.741888 -169.940732)
		(width 0.1651)
		(layer "In5.Cu")
		(net "PE_TX3_DR13_P")
	)
	(segment
		(start 18.127218 -173.871382)
		(end 7.36346 -175.770794)
		(width 0.1651)
		(layer "In5.Cu")
		(net "PE_TX3_DR13_P")
	)
	(segment
		(start 31.274512 -144.748504)
		(end 28.399232 -148.856192)
		(width 0.1651)
		(layer "In5.Cu")
		(net "PE_TX3_DR13_P")
	)
	(segment
		(start 32.373316 -128.131316)
		(end 33.289494 -133.326378)
		(width 0.1651)
		(layer "In5.Cu")
		(net "PE_TX3_DR13_P")
	)
	(segment
		(start 33.289494 -133.326378)
		(end 31.274512 -144.748504)
		(width 0.1651)
		(layer "In5.Cu")
		(net "PE_TX3_DR13_P")
	)
	(segment
		(start 28.39339 -148.889212)
		(end 24.996394 -168.148508)
		(width 0.1651)
		(layer "In5.Cu")
		(net "PE_TX3_DR13_P")
	)
	(segment
		(start 7.220966 -175.770794)
		(end 6.992366 -175.999394)
		(width 0.1651)
		(layer "In5.Cu")
		(net "PE_TX3_DR13_P")
	)
	(segment
		(start 23.741888 -169.940732)
		(end 18.127218 -173.871382)
		(width 0.1651)
		(layer "In5.Cu")
		(net "PE_TX3_DR13_P")
	)
	(segment
		(start 28.399232 -148.855938)
		(end 28.39339 -148.889212)
		(width 0.1651)
		(layer "In5.Cu")
		(net "PE_TX3_DR13_P")
	)
	(segment
		(start 28.083256 -124.231908)
		(end 29.031692 -124.39904)
		(width 0.1651)
		(layer "In5.Cu")
		(net "PE_TX3_DR13_P")
	)
	(segment
		(start 26.67 -124.003562)
		(end 26.898346 -124.231908)
		(width 0.1651)
		(layer "In5.Cu")
		(net "PE_TX3_DR13_P")
	)
	(segment
		(start 7.36346 -175.770794)
		(end 7.220966 -175.770794)
		(width 0.1651)
		(layer "In5.Cu")
		(net "PE_TX3_DR13_P")
	)
	(segment
		(start 30.460442 -125.399038)
		(end 32.373316 -128.131316)
		(width 0.1651)
		(layer "In5.Cu")
		(net "PE_TX3_DR13_P")
	)
	(segment
		(start 26.898346 -124.231908)
		(end 28.083256 -124.231908)
		(width 0.1651)
		(layer "In5.Cu")
		(net "PE_TX3_DR13_P")
	)
	(segment
		(start 29.031692 -124.39904)
		(end 30.460442 -125.399038)
		(width 0.1651)
		(layer "In5.Cu")
		(net "PE_TX3_DR13_P")
	)
	(segment
		(start 2.249932 -175.142144)
		(end 3.657854 -175.142144)
		(width 0.174752)
		(layer "F.Cu")
		(net "PE_TX3_DR13_N")
	)
	(segment
		(start 24.154638 -124.562362)
		(end 26.416 -124.562362)
		(width 0.174752)
		(layer "F.Cu")
		(net "PE_TX3_DR13_N")
	)
	(segment
		(start 6.73862 -175.44034)
		(end 6.992366 -175.186594)
		(width 0.174752)
		(layer "F.Cu")
		(net "PE_TX3_DR13_N")
	)
	(segment
		(start 23.906988 -124.810012)
		(end 24.154638 -124.562362)
		(width 0.174752)
		(layer "F.Cu")
		(net "PE_TX3_DR13_N")
	)
	(segment
		(start 3.657854 -175.142144)
		(end 3.95605 -175.44034)
		(width 0.174752)
		(layer "F.Cu")
		(net "PE_TX3_DR13_N")
	)
	(segment
		(start 22.800056 -124.810012)
		(end 23.906988 -124.810012)
		(width 0.174752)
		(layer "F.Cu")
		(net "PE_TX3_DR13_N")
	)
	(segment
		(start 26.416 -124.562362)
		(end 26.67 -124.816362)
		(width 0.174752)
		(layer "F.Cu")
		(net "PE_TX3_DR13_N")
	)
	(segment
		(start 3.95605 -175.44034)
		(end 6.73862 -175.44034)
		(width 0.174752)
		(layer "F.Cu")
		(net "PE_TX3_DR13_N")
	)
	(via
		(at 6.992366 -175.186594)
		(size 0.508)
		(drill 0.254)
		(layers "F.Cu" "B.Cu")
		(net "PE_TX3_DR13_N")
	)
	(via
		(at 26.67 -124.816362)
		(size 0.508)
		(drill 0.254)
		(layers "F.Cu" "B.Cu")
		(net "PE_TX3_DR13_N")
	)
	(segment
		(start 32.928306 -133.326378)
		(end 30.937962 -144.609058)
		(width 0.1651)
		(layer "In5.Cu")
		(net "PE_TX3_DR13_N")
	)
	(segment
		(start 19.964908 -171.92117)
		(end 19.559016 -172.205142)
		(width 0.1651)
		(layer "In5.Cu")
		(net "PE_TX3_DR13_N")
	)
	(segment
		(start 9.318244 -174.87392)
		(end 9.16559 -175.091598)
		(width 0.1651)
		(layer "In5.Cu")
		(net "PE_TX3_DR13_N")
	)
	(segment
		(start 26.898854 -124.587508)
		(end 28.052014 -124.587508)
		(width 0.1651)
		(layer "In5.Cu")
		(net "PE_TX3_DR13_N")
	)
	(segment
		(start 20.678648 -171.421552)
		(end 20.63242 -171.683426)
		(width 0.1651)
		(layer "In5.Cu")
		(net "PE_TX3_DR13_N")
	)
	(segment
		(start 11.369294 -174.702724)
		(end 11.151616 -174.550324)
		(width 0.1651)
		(layer "In5.Cu")
		(net "PE_TX3_DR13_N")
	)
	(segment
		(start 7.972298 -175.11141)
		(end 7.819898 -175.329088)
		(width 0.1651)
		(layer "In5.Cu")
		(net "PE_TX3_DR13_N")
	)
	(segment
		(start 24.65959 -168.009062)
		(end 24.65959 -168.009316)
		(width 0.1651)
		(layer "In5.Cu")
		(net "PE_TX3_DR13_N")
	)
	(segment
		(start 30.48889 -126.0602)
		(end 30.442916 -126.322074)
		(width 0.1651)
		(layer "In5.Cu")
		(net "PE_TX3_DR13_N")
	)
	(segment
		(start 19.559016 -172.205142)
		(end 19.513042 -172.467016)
		(width 0.1651)
		(layer "In5.Cu")
		(net "PE_TX3_DR13_N")
	)
	(segment
		(start 10.511536 -174.854108)
		(end 10.023602 -174.940214)
		(width 0.1651)
		(layer "In5.Cu")
		(net "PE_TX3_DR13_N")
	)
	(segment
		(start 7.332218 -175.415194)
		(end 7.220966 -175.415194)
		(width 0.1651)
		(layer "In5.Cu")
		(net "PE_TX3_DR13_N")
	)
	(segment
		(start 10.023602 -174.940214)
		(end 9.805924 -174.787814)
		(width 0.1651)
		(layer "In5.Cu")
		(net "PE_TX3_DR13_N")
	)
	(segment
		(start 20.63242 -171.683426)
		(end 20.226782 -171.967398)
		(width 0.1651)
		(layer "In5.Cu")
		(net "PE_TX3_DR13_N")
	)
	(segment
		(start 24.65959 -168.009316)
		(end 23.486364 -169.685208)
		(width 0.1651)
		(layer "In5.Cu")
		(net "PE_TX3_DR13_N")
	)
	(segment
		(start 30.937962 -144.609058)
		(end 28.062428 -148.717)
		(width 0.1651)
		(layer "In5.Cu")
		(net "PE_TX3_DR13_N")
	)
	(segment
		(start 21.34616 -171.183554)
		(end 21.084286 -171.13758)
		(width 0.1651)
		(layer "In5.Cu")
		(net "PE_TX3_DR13_N")
	)
	(segment
		(start 32.036766 -128.270762)
		(end 32.928306 -133.326378)
		(width 0.1651)
		(layer "In5.Cu")
		(net "PE_TX3_DR13_N")
	)
	(segment
		(start 30.442916 -126.322074)
		(end 30.726888 -126.727712)
		(width 0.1651)
		(layer "In5.Cu")
		(net "PE_TX3_DR13_N")
	)
	(segment
		(start 10.663936 -174.63643)
		(end 10.511536 -174.854108)
		(width 0.1651)
		(layer "In5.Cu")
		(net "PE_TX3_DR13_N")
	)
	(segment
		(start 19.10715 -172.750988)
		(end 18.84553 -172.705014)
		(width 0.1651)
		(layer "In5.Cu")
		(net "PE_TX3_DR13_N")
	)
	(segment
		(start 30.204918 -125.654562)
		(end 30.48889 -126.0602)
		(width 0.1651)
		(layer "In5.Cu")
		(net "PE_TX3_DR13_N")
	)
	(segment
		(start 7.819898 -175.329088)
		(end 7.332218 -175.415194)
		(width 0.1651)
		(layer "In5.Cu")
		(net "PE_TX3_DR13_N")
	)
	(segment
		(start 30.726888 -126.727712)
		(end 30.988762 -126.77394)
		(width 0.1651)
		(layer "In5.Cu")
		(net "PE_TX3_DR13_N")
	)
	(segment
		(start 20.226782 -171.967398)
		(end 19.964908 -171.92117)
		(width 0.1651)
		(layer "In5.Cu")
		(net "PE_TX3_DR13_N")
	)
	(segment
		(start 11.151616 -174.550324)
		(end 10.663936 -174.63643)
		(width 0.1651)
		(layer "In5.Cu")
		(net "PE_TX3_DR13_N")
	)
	(segment
		(start 8.460232 -175.025304)
		(end 7.972298 -175.11141)
		(width 0.1651)
		(layer "In5.Cu")
		(net "PE_TX3_DR13_N")
	)
	(segment
		(start 9.16559 -175.091598)
		(end 8.67791 -175.177704)
		(width 0.1651)
		(layer "In5.Cu")
		(net "PE_TX3_DR13_N")
	)
	(segment
		(start 17.987772 -173.534832)
		(end 11.369294 -174.702724)
		(width 0.1651)
		(layer "In5.Cu")
		(net "PE_TX3_DR13_N")
	)
	(segment
		(start 26.67 -124.816362)
		(end 26.898854 -124.587508)
		(width 0.1651)
		(layer "In5.Cu")
		(net "PE_TX3_DR13_N")
	)
	(segment
		(start 28.062428 -148.717)
		(end 24.65959 -168.009062)
		(width 0.1651)
		(layer "In5.Cu")
		(net "PE_TX3_DR13_N")
	)
	(segment
		(start 18.39341 -173.25086)
		(end 17.987772 -173.534832)
		(width 0.1651)
		(layer "In5.Cu")
		(net "PE_TX3_DR13_N")
	)
	(segment
		(start 18.439638 -172.988986)
		(end 18.39341 -173.25086)
		(width 0.1651)
		(layer "In5.Cu")
		(net "PE_TX3_DR13_N")
	)
	(segment
		(start 23.486364 -169.685208)
		(end 21.34616 -171.183554)
		(width 0.1651)
		(layer "In5.Cu")
		(net "PE_TX3_DR13_N")
	)
	(segment
		(start 30.988762 -126.77394)
		(end 32.036766 -128.270762)
		(width 0.1651)
		(layer "In5.Cu")
		(net "PE_TX3_DR13_N")
	)
	(segment
		(start 21.084286 -171.13758)
		(end 20.678648 -171.421552)
		(width 0.1651)
		(layer "In5.Cu")
		(net "PE_TX3_DR13_N")
	)
	(segment
		(start 28.892754 -124.735844)
		(end 30.204918 -125.654562)
		(width 0.1651)
		(layer "In5.Cu")
		(net "PE_TX3_DR13_N")
	)
	(segment
		(start 7.220966 -175.415194)
		(end 6.992366 -175.186594)
		(width 0.1651)
		(layer "In5.Cu")
		(net "PE_TX3_DR13_N")
	)
	(segment
		(start 9.805924 -174.787814)
		(end 9.318244 -174.87392)
		(width 0.1651)
		(layer "In5.Cu")
		(net "PE_TX3_DR13_N")
	)
	(segment
		(start 18.84553 -172.705014)
		(end 18.439638 -172.988986)
		(width 0.1651)
		(layer "In5.Cu")
		(net "PE_TX3_DR13_N")
	)
	(segment
		(start 28.052014 -124.587508)
		(end 28.892754 -124.735844)
		(width 0.1651)
		(layer "In5.Cu")
		(net "PE_TX3_DR13_N")
	)
	(segment
		(start 8.67791 -175.177704)
		(end 8.460232 -175.025304)
		(width 0.1651)
		(layer "In5.Cu")
		(net "PE_TX3_DR13_N")
	)
	(segment
		(start 19.513042 -172.467016)
		(end 19.10715 -172.750988)
		(width 0.1651)
		(layer "In5.Cu")
		(net "PE_TX3_DR13_N")
	)
	(segment
		(start 26.416254 -227.257356)
		(end 26.67 -227.00361)
		(width 0.174752)
		(layer "F.Cu")
		(net "PE_TX3_DR12_P")
	)
	(segment
		(start 3.905504 -221.243652)
		(end 6.738112 -221.243652)
		(width 0.174752)
		(layer "F.Cu")
		(net "PE_TX3_DR12_P")
	)
	(segment
		(start 22.800056 -227.00996)
		(end 23.876 -227.00996)
		(width 0.174752)
		(layer "F.Cu")
		(net "PE_TX3_DR12_P")
	)
	(segment
		(start 2.249932 -221.542102)
		(end 3.607054 -221.542102)
		(width 0.174752)
		(layer "F.Cu")
		(net "PE_TX3_DR12_P")
	)
	(segment
		(start 23.876 -227.00996)
		(end 24.123396 -227.257356)
		(width 0.174752)
		(layer "F.Cu")
		(net "PE_TX3_DR12_P")
	)
	(segment
		(start 6.738112 -221.243652)
		(end 6.992366 -221.497906)
		(width 0.174752)
		(layer "F.Cu")
		(net "PE_TX3_DR12_P")
	)
	(segment
		(start 24.123396 -227.257356)
		(end 26.416254 -227.257356)
		(width 0.174752)
		(layer "F.Cu")
		(net "PE_TX3_DR12_P")
	)
	(segment
		(start 3.607054 -221.542102)
		(end 3.905504 -221.243652)
		(width 0.174752)
		(layer "F.Cu")
		(net "PE_TX3_DR12_P")
	)
	(via
		(at 26.67 -227.00361)
		(size 0.508)
		(drill 0.254)
		(layers "F.Cu" "B.Cu")
		(net "PE_TX3_DR12_P")
	)
	(via
		(at 6.992366 -221.497906)
		(size 0.508)
		(drill 0.254)
		(layers "F.Cu" "B.Cu")
		(net "PE_TX3_DR12_P")
	)
	(segment
		(start 40.406066 -204.741272)
		(end 40.811704 -205.025244)
		(width 0.1651)
		(layer "In5.Cu")
		(net "PE_TX3_DR12_P")
	)
	(segment
		(start 7.220966 -221.269306)
		(end 7.682484 -221.269306)
		(width 0.1651)
		(layer "In5.Cu")
		(net "PE_TX3_DR12_P")
	)
	(segment
		(start 43.045126 -209.254344)
		(end 42.720768 -211.093304)
		(width 0.1651)
		(layer "In5.Cu")
		(net "PE_TX3_DR12_P")
	)
	(segment
		(start 39.24046 -203.695554)
		(end 39.286688 -203.957428)
		(width 0.1651)
		(layer "In5.Cu")
		(net "PE_TX3_DR12_P")
	)
	(segment
		(start 9.737344 -220.907102)
		(end 10.12825 -220.63329)
		(width 0.1651)
		(layer "In5.Cu")
		(net "PE_TX3_DR12_P")
	)
	(segment
		(start 34.897314 -221.938088)
		(end 34.943542 -222.199962)
		(width 0.1651)
		(layer "In5.Cu")
		(net "PE_TX3_DR12_P")
	)
	(segment
		(start 29.171392 -226.448112)
		(end 28.909772 -226.402138)
		(width 0.1651)
		(layer "In5.Cu")
		(net "PE_TX3_DR12_P")
	)
	(segment
		(start 6.992366 -221.497906)
		(end 7.220966 -221.269306)
		(width 0.1651)
		(layer "In5.Cu")
		(net "PE_TX3_DR12_P")
	)
	(segment
		(start 18.811494 -202.811126)
		(end 20.145756 -201.87666)
		(width 0.1651)
		(layer "In5.Cu")
		(net "PE_TX3_DR12_P")
	)
	(segment
		(start 41.073578 -204.97927)
		(end 41.508426 -205.283562)
		(width 0.1651)
		(layer "In5.Cu")
		(net "PE_TX3_DR12_P")
	)
	(segment
		(start 35.727386 -221.080584)
		(end 35.44316 -221.486222)
		(width 0.1651)
		(layer "In5.Cu")
		(net "PE_TX3_DR12_P")
	)
	(segment
		(start 36.465002 -219.699332)
		(end 36.51123 -219.961206)
		(width 0.1651)
		(layer "In5.Cu")
		(net "PE_TX3_DR12_P")
	)
	(segment
		(start 37.010848 -219.247466)
		(end 36.748974 -219.293694)
		(width 0.1651)
		(layer "In5.Cu")
		(net "PE_TX3_DR12_P")
	)
	(segment
		(start 40.811704 -205.025244)
		(end 41.073578 -204.97927)
		(width 0.1651)
		(layer "In5.Cu")
		(net "PE_TX3_DR12_P")
	)
	(segment
		(start 39.286688 -203.957428)
		(end 39.692326 -204.2414)
		(width 0.1651)
		(layer "In5.Cu")
		(net "PE_TX3_DR12_P")
	)
	(segment
		(start 34.943542 -222.199962)
		(end 34.659316 -222.6056)
		(width 0.1651)
		(layer "In5.Cu")
		(net "PE_TX3_DR12_P")
	)
	(segment
		(start 7.682484 -221.269306)
		(end 9.737344 -220.907102)
		(width 0.1651)
		(layer "In5.Cu")
		(net "PE_TX3_DR12_P")
	)
	(segment
		(start 34.659316 -222.6056)
		(end 30.29077 -225.664522)
		(width 0.1651)
		(layer "In5.Cu")
		(net "PE_TX3_DR12_P")
	)
	(segment
		(start 13.443458 -216.981786)
		(end 14.975586 -208.291684)
		(width 0.1651)
		(layer "In5.Cu")
		(net "PE_TX3_DR12_P")
	)
	(segment
		(start 28.909772 -226.402138)
		(end 28.50388 -226.68611)
		(width 0.1651)
		(layer "In5.Cu")
		(net "PE_TX3_DR12_P")
	)
	(segment
		(start 36.748974 -219.293694)
		(end 36.465002 -219.699332)
		(width 0.1651)
		(layer "In5.Cu")
		(net "PE_TX3_DR12_P")
	)
	(segment
		(start 11.617706 -219.59062)
		(end 13.443458 -216.981786)
		(width 0.1651)
		(layer "In5.Cu")
		(net "PE_TX3_DR12_P")
	)
	(segment
		(start 10.12825 -220.63329)
		(end 11.617706 -219.59062)
		(width 0.1651)
		(layer "In5.Cu")
		(net "PE_TX3_DR12_P")
	)
	(segment
		(start 28.457652 -226.947984)
		(end 28.052014 -227.231956)
		(width 0.1651)
		(layer "In5.Cu")
		(net "PE_TX3_DR12_P")
	)
	(segment
		(start 20.145756 -201.87666)
		(end 25.539954 -200.92543)
		(width 0.1651)
		(layer "In5.Cu")
		(net "PE_TX3_DR12_P")
	)
	(segment
		(start 39.9542 -204.195426)
		(end 40.359838 -204.479398)
		(width 0.1651)
		(layer "In5.Cu")
		(net "PE_TX3_DR12_P")
	)
	(segment
		(start 25.539954 -200.92543)
		(end 25.65146 -200.92543)
		(width 0.1651)
		(layer "In5.Cu")
		(net "PE_TX3_DR12_P")
	)
	(segment
		(start 36.51123 -219.961206)
		(end 36.227004 -220.366844)
		(width 0.1651)
		(layer "In5.Cu")
		(net "PE_TX3_DR12_P")
	)
	(segment
		(start 25.65146 -200.92543)
		(end 38.537896 -203.203302)
		(width 0.1651)
		(layer "In5.Cu")
		(net "PE_TX3_DR12_P")
	)
	(segment
		(start 42.626026 -206.87919)
		(end 43.045126 -209.254344)
		(width 0.1651)
		(layer "In5.Cu")
		(net "PE_TX3_DR12_P")
	)
	(segment
		(start 35.181286 -221.53245)
		(end 34.897314 -221.938088)
		(width 0.1651)
		(layer "In5.Cu")
		(net "PE_TX3_DR12_P")
	)
	(segment
		(start 35.44316 -221.486222)
		(end 35.181286 -221.53245)
		(width 0.1651)
		(layer "In5.Cu")
		(net "PE_TX3_DR12_P")
	)
	(segment
		(start 28.50388 -226.68611)
		(end 28.457652 -226.947984)
		(width 0.1651)
		(layer "In5.Cu")
		(net "PE_TX3_DR12_P")
	)
	(segment
		(start 29.577284 -226.16414)
		(end 29.171392 -226.448112)
		(width 0.1651)
		(layer "In5.Cu")
		(net "PE_TX3_DR12_P")
	)
	(segment
		(start 42.720768 -211.093304)
		(end 37.010848 -219.247466)
		(width 0.1651)
		(layer "In5.Cu")
		(net "PE_TX3_DR12_P")
	)
	(segment
		(start 14.975586 -208.291684)
		(end 18.811494 -202.811126)
		(width 0.1651)
		(layer "In5.Cu")
		(net "PE_TX3_DR12_P")
	)
	(segment
		(start 40.359838 -204.479398)
		(end 40.406066 -204.741272)
		(width 0.1651)
		(layer "In5.Cu")
		(net "PE_TX3_DR12_P")
	)
	(segment
		(start 30.02915 -225.618294)
		(end 29.623258 -225.902266)
		(width 0.1651)
		(layer "In5.Cu")
		(net "PE_TX3_DR12_P")
	)
	(segment
		(start 30.29077 -225.664522)
		(end 30.02915 -225.618294)
		(width 0.1651)
		(layer "In5.Cu")
		(net "PE_TX3_DR12_P")
	)
	(segment
		(start 41.508426 -205.283562)
		(end 42.626026 -206.87919)
		(width 0.1651)
		(layer "In5.Cu")
		(net "PE_TX3_DR12_P")
	)
	(segment
		(start 29.623258 -225.902266)
		(end 29.577284 -226.16414)
		(width 0.1651)
		(layer "In5.Cu")
		(net "PE_TX3_DR12_P")
	)
	(segment
		(start 36.227004 -220.366844)
		(end 35.96513 -220.413072)
		(width 0.1651)
		(layer "In5.Cu")
		(net "PE_TX3_DR12_P")
	)
	(segment
		(start 35.96513 -220.413072)
		(end 35.681158 -220.81871)
		(width 0.1651)
		(layer "In5.Cu")
		(net "PE_TX3_DR12_P")
	)
	(segment
		(start 28.052014 -227.231956)
		(end 26.898346 -227.231956)
		(width 0.1651)
		(layer "In5.Cu")
		(net "PE_TX3_DR12_P")
	)
	(segment
		(start 26.898346 -227.231956)
		(end 26.67 -227.00361)
		(width 0.1651)
		(layer "In5.Cu")
		(net "PE_TX3_DR12_P")
	)
	(segment
		(start 38.537896 -203.203302)
		(end 39.24046 -203.695554)
		(width 0.1651)
		(layer "In5.Cu")
		(net "PE_TX3_DR12_P")
	)
	(segment
		(start 39.692326 -204.2414)
		(end 39.9542 -204.195426)
		(width 0.1651)
		(layer "In5.Cu")
		(net "PE_TX3_DR12_P")
	)
	(segment
		(start 35.681158 -220.81871)
		(end 35.727386 -221.080584)
		(width 0.1651)
		(layer "In5.Cu")
		(net "PE_TX3_DR12_P")
	)
	(segment
		(start 2.249932 -220.742002)
		(end 3.708908 -220.742002)
		(width 0.174752)
		(layer "F.Cu")
		(net "PE_TX3_DR12_N")
	)
	(segment
		(start 26.416 -227.56241)
		(end 26.67 -227.81641)
		(width 0.174752)
		(layer "F.Cu")
		(net "PE_TX3_DR12_N")
	)
	(segment
		(start 3.708908 -220.742002)
		(end 3.905504 -220.938598)
		(width 0.174752)
		(layer "F.Cu")
		(net "PE_TX3_DR12_N")
	)
	(segment
		(start 23.876 -227.81006)
		(end 24.12365 -227.56241)
		(width 0.174752)
		(layer "F.Cu")
		(net "PE_TX3_DR12_N")
	)
	(segment
		(start 24.12365 -227.56241)
		(end 26.416 -227.56241)
		(width 0.174752)
		(layer "F.Cu")
		(net "PE_TX3_DR12_N")
	)
	(segment
		(start 3.905504 -220.938598)
		(end 6.738874 -220.938598)
		(width 0.174752)
		(layer "F.Cu")
		(net "PE_TX3_DR12_N")
	)
	(segment
		(start 22.800056 -227.81006)
		(end 23.876 -227.81006)
		(width 0.174752)
		(layer "F.Cu")
		(net "PE_TX3_DR12_N")
	)
	(segment
		(start 6.738874 -220.938598)
		(end 6.992366 -220.685106)
		(width 0.174752)
		(layer "F.Cu")
		(net "PE_TX3_DR12_N")
	)
	(via
		(at 6.992366 -220.685106)
		(size 0.508)
		(drill 0.254)
		(layers "F.Cu" "B.Cu")
		(net "PE_TX3_DR12_N")
	)
	(via
		(at 26.67 -227.81641)
		(size 0.508)
		(drill 0.254)
		(layers "F.Cu" "B.Cu")
		(net "PE_TX3_DR12_N")
	)
	(segment
		(start 14.641068 -208.149444)
		(end 14.641068 -208.148682)
		(width 0.1651)
		(layer "In5.Cu")
		(net "PE_TX3_DR12_N")
	)
	(segment
		(start 11.362182 -219.335096)
		(end 13.106908 -216.84234)
		(width 0.1651)
		(layer "In5.Cu")
		(net "PE_TX3_DR12_N")
	)
	(segment
		(start 43.057318 -211.23275)
		(end 34.91484 -222.861124)
		(width 0.1651)
		(layer "In5.Cu")
		(net "PE_TX3_DR12_N")
	)
	(segment
		(start 20.00631 -201.54011)
		(end 25.508712 -200.56983)
		(width 0.1651)
		(layer "In5.Cu")
		(net "PE_TX3_DR12_N")
	)
	(segment
		(start 41.76395 -205.028038)
		(end 42.962576 -206.739744)
		(width 0.1651)
		(layer "In5.Cu")
		(net "PE_TX3_DR12_N")
	)
	(segment
		(start 18.55597 -202.555602)
		(end 20.00631 -201.54011)
		(width 0.1651)
		(layer "In5.Cu")
		(net "PE_TX3_DR12_N")
	)
	(segment
		(start 25.682702 -200.56983)
		(end 38.677342 -202.866752)
		(width 0.1651)
		(layer "In5.Cu")
		(net "PE_TX3_DR12_N")
	)
	(segment
		(start 14.638782 -208.152492)
		(end 14.641068 -208.149444)
		(width 0.1651)
		(layer "In5.Cu")
		(net "PE_TX3_DR12_N")
	)
	(segment
		(start 28.164282 -227.587556)
		(end 26.898854 -227.587556)
		(width 0.1651)
		(layer "In5.Cu")
		(net "PE_TX3_DR12_N")
	)
	(segment
		(start 43.406314 -209.254344)
		(end 43.057318 -211.23275)
		(width 0.1651)
		(layer "In5.Cu")
		(net "PE_TX3_DR12_N")
	)
	(segment
		(start 26.898854 -227.587556)
		(end 26.67 -227.81641)
		(width 0.1651)
		(layer "In5.Cu")
		(net "PE_TX3_DR12_N")
	)
	(segment
		(start 42.962576 -206.739744)
		(end 43.406314 -209.254344)
		(width 0.1651)
		(layer "In5.Cu")
		(net "PE_TX3_DR12_N")
	)
	(segment
		(start 38.677342 -202.866752)
		(end 41.277794 -204.687678)
		(width 0.1651)
		(layer "In5.Cu")
		(net "PE_TX3_DR12_N")
	)
	(segment
		(start 13.106908 -216.84234)
		(end 14.638782 -208.152492)
		(width 0.1651)
		(layer "In5.Cu")
		(net "PE_TX3_DR12_N")
	)
	(segment
		(start 34.91484 -222.861124)
		(end 28.164282 -227.587556)
		(width 0.1651)
		(layer "In5.Cu")
		(net "PE_TX3_DR12_N")
	)
	(segment
		(start 9.59739 -220.570552)
		(end 9.955784 -220.3196)
		(width 0.1651)
		(layer "In5.Cu")
		(net "PE_TX3_DR12_N")
	)
	(segment
		(start 25.508712 -200.56983)
		(end 25.682702 -200.56983)
		(width 0.1651)
		(layer "In5.Cu")
		(net "PE_TX3_DR12_N")
	)
	(segment
		(start 7.651242 -220.913706)
		(end 9.59739 -220.570552)
		(width 0.1651)
		(layer "In5.Cu")
		(net "PE_TX3_DR12_N")
	)
	(segment
		(start 41.277794 -204.687932)
		(end 41.76395 -205.028038)
		(width 0.1651)
		(layer "In5.Cu")
		(net "PE_TX3_DR12_N")
	)
	(segment
		(start 14.641068 -208.148682)
		(end 18.55597 -202.555602)
		(width 0.1651)
		(layer "In5.Cu")
		(net "PE_TX3_DR12_N")
	)
	(segment
		(start 9.955784 -220.3196)
		(end 11.362182 -219.335096)
		(width 0.1651)
		(layer "In5.Cu")
		(net "PE_TX3_DR12_N")
	)
	(segment
		(start 7.220966 -220.913706)
		(end 7.651242 -220.913706)
		(width 0.1651)
		(layer "In5.Cu")
		(net "PE_TX3_DR12_N")
	)
	(segment
		(start 41.277794 -204.687678)
		(end 41.277794 -204.687932)
		(width 0.1651)
		(layer "In5.Cu")
		(net "PE_TX3_DR12_N")
	)
	(segment
		(start 6.992366 -220.685106)
		(end 7.220966 -220.913706)
		(width 0.1651)
		(layer "In5.Cu")
		(net "PE_TX3_DR12_N")
	)
	(segment
		(start 23.876 -330.010008)
		(end 24.123396 -330.257404)
		(width 0.174752)
		(layer "F.Cu")
		(net "PE_TX3_DR11_P")
	)
	(segment
		(start 22.800056 -330.010008)
		(end 23.876 -330.010008)
		(width 0.174752)
		(layer "F.Cu")
		(net "PE_TX3_DR11_P")
	)
	(segment
		(start 26.416254 -330.257404)
		(end 26.67 -330.003658)
		(width 0.174752)
		(layer "F.Cu")
		(net "PE_TX3_DR11_P")
	)
	(segment
		(start 24.123396 -330.257404)
		(end 26.416254 -330.257404)
		(width 0.174752)
		(layer "F.Cu")
		(net "PE_TX3_DR11_P")
	)
	(segment
		(start 6.738366 -340.94547)
		(end 6.992366 -341.19947)
		(width 0.174752)
		(layer "F.Cu")
		(net "PE_TX3_DR11_P")
	)
	(segment
		(start 3.85445 -340.94547)
		(end 6.738366 -340.94547)
		(width 0.174752)
		(layer "F.Cu")
		(net "PE_TX3_DR11_P")
	)
	(segment
		(start 3.657854 -341.142066)
		(end 3.85445 -340.94547)
		(width 0.174752)
		(layer "F.Cu")
		(net "PE_TX3_DR11_P")
	)
	(segment
		(start 2.249932 -341.142066)
		(end 3.657854 -341.142066)
		(width 0.174752)
		(layer "F.Cu")
		(net "PE_TX3_DR11_P")
	)
	(via
		(at 6.992366 -341.19947)
		(size 0.508)
		(drill 0.254)
		(layers "F.Cu" "B.Cu")
		(net "PE_TX3_DR11_P")
	)
	(via
		(at 26.67 -330.003658)
		(size 0.508)
		(drill 0.254)
		(layers "F.Cu" "B.Cu")
		(net "PE_TX3_DR11_P")
	)
	(segment
		(start 6.992366 -341.19947)
		(end 7.220966 -340.97087)
		(width 0.1651)
		(layer "In5.Cu")
		(net "PE_TX3_DR11_P")
	)
	(segment
		(start 30.182058 -351.719134)
		(end 30.760924 -350.892364)
		(width 0.1651)
		(layer "In5.Cu")
		(net "PE_TX3_DR11_P")
	)
	(segment
		(start 15.920212 -350.620838)
		(end 16.094202 -351.607628)
		(width 0.1651)
		(layer "In5.Cu")
		(net "PE_TX3_DR11_P")
	)
	(segment
		(start 16.094202 -351.607628)
		(end 18.570956 -355.146102)
		(width 0.1651)
		(layer "In5.Cu")
		(net "PE_TX3_DR11_P")
	)
	(segment
		(start 21.71954 -356.622096)
		(end 23.672038 -356.277418)
		(width 0.1651)
		(layer "In5.Cu")
		(net "PE_TX3_DR11_P")
	)
	(segment
		(start 9.163812 -341.203026)
		(end 9.42213 -341.339424)
		(width 0.1651)
		(layer "In5.Cu")
		(net "PE_TX3_DR11_P")
	)
	(segment
		(start 30.745684 -330.858876)
		(end 30.530038 -330.55052)
		(width 0.1651)
		(layer "In5.Cu")
		(net "PE_TX3_DR11_P")
	)
	(segment
		(start 9.42213 -341.339424)
		(end 15.920212 -350.620838)
		(width 0.1651)
		(layer "In5.Cu")
		(net "PE_TX3_DR11_P")
	)
	(segment
		(start 31.293562 -333.96555)
		(end 30.745684 -330.858876)
		(width 0.1651)
		(layer "In5.Cu")
		(net "PE_TX3_DR11_P")
	)
	(segment
		(start 31.279338 -347.94952)
		(end 30.053534 -340.997032)
		(width 0.1651)
		(layer "In5.Cu")
		(net "PE_TX3_DR11_P")
	)
	(segment
		(start 28.870402 -330.232004)
		(end 26.898346 -330.232004)
		(width 0.1651)
		(layer "In5.Cu")
		(net "PE_TX3_DR11_P")
	)
	(segment
		(start 30.163262 -330.29398)
		(end 29.34081 -330.148946)
		(width 0.1651)
		(layer "In5.Cu")
		(net "PE_TX3_DR11_P")
	)
	(segment
		(start 30.053534 -340.997032)
		(end 31.293562 -333.96555)
		(width 0.1651)
		(layer "In5.Cu")
		(net "PE_TX3_DR11_P")
	)
	(segment
		(start 20.326858 -356.37597)
		(end 21.71954 -356.622096)
		(width 0.1651)
		(layer "In5.Cu")
		(net "PE_TX3_DR11_P")
	)
	(segment
		(start 29.34081 -330.148946)
		(end 28.870402 -330.232004)
		(width 0.1651)
		(layer "In5.Cu")
		(net "PE_TX3_DR11_P")
	)
	(segment
		(start 7.845806 -340.97087)
		(end 9.163812 -341.203026)
		(width 0.1651)
		(layer "In5.Cu")
		(net "PE_TX3_DR11_P")
	)
	(segment
		(start 30.760924 -350.892364)
		(end 31.279338 -347.94952)
		(width 0.1651)
		(layer "In5.Cu")
		(net "PE_TX3_DR11_P")
	)
	(segment
		(start 18.570956 -355.146102)
		(end 20.326858 -356.37597)
		(width 0.1651)
		(layer "In5.Cu")
		(net "PE_TX3_DR11_P")
	)
	(segment
		(start 30.530038 -330.55052)
		(end 30.163262 -330.29398)
		(width 0.1651)
		(layer "In5.Cu")
		(net "PE_TX3_DR11_P")
	)
	(segment
		(start 23.672038 -356.277418)
		(end 30.182058 -351.719134)
		(width 0.1651)
		(layer "In5.Cu")
		(net "PE_TX3_DR11_P")
	)
	(segment
		(start 7.220966 -340.97087)
		(end 7.845806 -340.97087)
		(width 0.1651)
		(layer "In5.Cu")
		(net "PE_TX3_DR11_P")
	)
	(segment
		(start 26.898346 -330.232004)
		(end 26.67 -330.003658)
		(width 0.1651)
		(layer "In5.Cu")
		(net "PE_TX3_DR11_P")
	)
	(segment
		(start 26.416 -330.562458)
		(end 26.67 -330.816458)
		(width 0.174752)
		(layer "F.Cu")
		(net "PE_TX3_DR11_N")
	)
	(segment
		(start 3.95605 -340.640416)
		(end 6.73862 -340.640416)
		(width 0.174752)
		(layer "F.Cu")
		(net "PE_TX3_DR11_N")
	)
	(segment
		(start 22.800056 -330.810108)
		(end 23.88235 -330.810108)
		(width 0.174752)
		(layer "F.Cu")
		(net "PE_TX3_DR11_N")
	)
	(segment
		(start 23.88235 -330.810108)
		(end 24.13 -330.562458)
		(width 0.174752)
		(layer "F.Cu")
		(net "PE_TX3_DR11_N")
	)
	(segment
		(start 3.657854 -340.34222)
		(end 3.95605 -340.640416)
		(width 0.174752)
		(layer "F.Cu")
		(net "PE_TX3_DR11_N")
	)
	(segment
		(start 2.249932 -340.34222)
		(end 3.657854 -340.34222)
		(width 0.174752)
		(layer "F.Cu")
		(net "PE_TX3_DR11_N")
	)
	(segment
		(start 6.73862 -340.640416)
		(end 6.992366 -340.38667)
		(width 0.174752)
		(layer "F.Cu")
		(net "PE_TX3_DR11_N")
	)
	(segment
		(start 24.13 -330.562458)
		(end 26.416 -330.562458)
		(width 0.174752)
		(layer "F.Cu")
		(net "PE_TX3_DR11_N")
	)
	(via
		(at 26.67 -330.816458)
		(size 0.508)
		(drill 0.254)
		(layers "F.Cu" "B.Cu")
		(net "PE_TX3_DR11_N")
	)
	(via
		(at 6.992366 -340.38667)
		(size 0.508)
		(drill 0.254)
		(layers "F.Cu" "B.Cu")
		(net "PE_TX3_DR11_N")
	)
	(segment
		(start 7.220966 -340.61527)
		(end 6.992366 -340.38667)
		(width 0.1651)
		(layer "In5.Cu")
		(net "PE_TX3_DR11_N")
	)
	(segment
		(start 16.256762 -350.481392)
		(end 12.01547 -344.423238)
		(width 0.1651)
		(layer "In5.Cu")
		(net "PE_TX3_DR11_N")
	)
	(segment
		(start 30.62859 -333.325216)
		(end 30.846268 -333.47787)
		(width 0.1651)
		(layer "In5.Cu")
		(net "PE_TX3_DR11_N")
	)
	(segment
		(start 9.664192 -341.065104)
		(end 9.280398 -340.862412)
		(width 0.1651)
		(layer "In5.Cu")
		(net "PE_TX3_DR11_N")
	)
	(segment
		(start 30.62859 -334.605884)
		(end 30.542484 -335.093564)
		(width 0.1651)
		(layer "In5.Cu")
		(net "PE_TX3_DR11_N")
	)
	(segment
		(start 10.448036 -342.184482)
		(end 10.49401 -341.922862)
		(width 0.1651)
		(layer "In5.Cu")
		(net "PE_TX3_DR11_N")
	)
	(segment
		(start 20.466304 -356.03942)
		(end 18.82648 -354.890578)
		(width 0.1651)
		(layer "In5.Cu")
		(net "PE_TX3_DR11_N")
	)
	(segment
		(start 10.993882 -342.636348)
		(end 10.732008 -342.59012)
		(width 0.1651)
		(layer "In5.Cu")
		(net "PE_TX3_DR11_N")
	)
	(segment
		(start 30.695138 -335.311242)
		(end 30.609032 -335.799176)
		(width 0.1651)
		(layer "In5.Cu")
		(net "PE_TX3_DR11_N")
	)
	(segment
		(start 17.902936 -353.243388)
		(end 17.641062 -353.19716)
		(width 0.1651)
		(layer "In5.Cu")
		(net "PE_TX3_DR11_N")
	)
	(segment
		(start 30.542484 -332.837536)
		(end 30.62859 -333.325216)
		(width 0.1651)
		(layer "In5.Cu")
		(net "PE_TX3_DR11_N")
	)
	(segment
		(start 10.732008 -342.59012)
		(end 10.448036 -342.184482)
		(width 0.1651)
		(layer "In5.Cu")
		(net "PE_TX3_DR11_N")
	)
	(segment
		(start 11.277854 -343.04224)
		(end 10.993882 -342.636348)
		(width 0.1651)
		(layer "In5.Cu")
		(net "PE_TX3_DR11_N")
	)
	(segment
		(start 18.82648 -354.890578)
		(end 18.14068 -353.9109)
		(width 0.1651)
		(layer "In5.Cu")
		(net "PE_TX3_DR11_N")
	)
	(segment
		(start 18.14068 -353.9109)
		(end 18.186908 -353.64928)
		(width 0.1651)
		(layer "In5.Cu")
		(net "PE_TX3_DR11_N")
	)
	(segment
		(start 10.210038 -341.51697)
		(end 9.948164 -341.470742)
		(width 0.1651)
		(layer "In5.Cu")
		(net "PE_TX3_DR11_N")
	)
	(segment
		(start 30.424374 -350.752918)
		(end 29.927042 -351.463102)
		(width 0.1651)
		(layer "In5.Cu")
		(net "PE_TX3_DR11_N")
	)
	(segment
		(start 11.515852 -343.709498)
		(end 11.23188 -343.30386)
		(width 0.1651)
		(layer "In5.Cu")
		(net "PE_TX3_DR11_N")
	)
	(segment
		(start 12.01547 -344.423238)
		(end 12.061698 -344.161618)
		(width 0.1651)
		(layer "In5.Cu")
		(net "PE_TX3_DR11_N")
	)
	(segment
		(start 9.948164 -341.470742)
		(end 9.664192 -341.065104)
		(width 0.1651)
		(layer "In5.Cu")
		(net "PE_TX3_DR11_N")
	)
	(segment
		(start 30.846268 -333.47787)
		(end 30.932374 -333.96555)
		(width 0.1651)
		(layer "In5.Cu")
		(net "PE_TX3_DR11_N")
	)
	(segment
		(start 30.409134 -330.998322)
		(end 30.695138 -332.619858)
		(width 0.1651)
		(layer "In5.Cu")
		(net "PE_TX3_DR11_N")
	)
	(segment
		(start 30.846268 -334.45323)
		(end 30.62859 -334.605884)
		(width 0.1651)
		(layer "In5.Cu")
		(net "PE_TX3_DR11_N")
	)
	(segment
		(start 23.532592 -355.940868)
		(end 21.71954 -356.260908)
		(width 0.1651)
		(layer "In5.Cu")
		(net "PE_TX3_DR11_N")
	)
	(segment
		(start 30.274514 -330.806044)
		(end 30.409134 -330.998322)
		(width 0.1651)
		(layer "In5.Cu")
		(net "PE_TX3_DR11_N")
	)
	(segment
		(start 29.34081 -330.510134)
		(end 30.023816 -330.63053)
		(width 0.1651)
		(layer "In5.Cu")
		(net "PE_TX3_DR11_N")
	)
	(segment
		(start 21.71954 -356.260908)
		(end 20.466304 -356.03942)
		(width 0.1651)
		(layer "In5.Cu")
		(net "PE_TX3_DR11_N")
	)
	(segment
		(start 30.542484 -335.093564)
		(end 30.695138 -335.311242)
		(width 0.1651)
		(layer "In5.Cu")
		(net "PE_TX3_DR11_N")
	)
	(segment
		(start 30.91815 -347.94952)
		(end 30.424374 -350.752918)
		(width 0.1651)
		(layer "In5.Cu")
		(net "PE_TX3_DR11_N")
	)
	(segment
		(start 7.877048 -340.61527)
		(end 7.220966 -340.61527)
		(width 0.1651)
		(layer "In5.Cu")
		(net "PE_TX3_DR11_N")
	)
	(segment
		(start 29.927042 -351.463102)
		(end 23.532592 -355.940868)
		(width 0.1651)
		(layer "In5.Cu")
		(net "PE_TX3_DR11_N")
	)
	(segment
		(start 30.305248 -336.439256)
		(end 30.457648 -336.656934)
		(width 0.1651)
		(layer "In5.Cu")
		(net "PE_TX3_DR11_N")
	)
	(segment
		(start 26.898854 -330.587604)
		(end 28.901644 -330.587604)
		(width 0.1651)
		(layer "In5.Cu")
		(net "PE_TX3_DR11_N")
	)
	(segment
		(start 30.695138 -332.619858)
		(end 30.542484 -332.837536)
		(width 0.1651)
		(layer "In5.Cu")
		(net "PE_TX3_DR11_N")
	)
	(segment
		(start 11.23188 -343.30386)
		(end 11.277854 -343.04224)
		(width 0.1651)
		(layer "In5.Cu")
		(net "PE_TX3_DR11_N")
	)
	(segment
		(start 18.186908 -353.64928)
		(end 17.902936 -353.243388)
		(width 0.1651)
		(layer "In5.Cu")
		(net "PE_TX3_DR11_N")
	)
	(segment
		(start 16.430752 -351.468182)
		(end 16.256762 -350.481392)
		(width 0.1651)
		(layer "In5.Cu")
		(net "PE_TX3_DR11_N")
	)
	(segment
		(start 30.932374 -333.96555)
		(end 30.846268 -334.45323)
		(width 0.1651)
		(layer "In5.Cu")
		(net "PE_TX3_DR11_N")
	)
	(segment
		(start 17.641062 -353.19716)
		(end 16.430752 -351.468182)
		(width 0.1651)
		(layer "In5.Cu")
		(net "PE_TX3_DR11_N")
	)
	(segment
		(start 29.692346 -340.997032)
		(end 30.91815 -347.94952)
		(width 0.1651)
		(layer "In5.Cu")
		(net "PE_TX3_DR11_N")
	)
	(segment
		(start 30.457648 -336.656934)
		(end 29.692346 -340.997032)
		(width 0.1651)
		(layer "In5.Cu")
		(net "PE_TX3_DR11_N")
	)
	(segment
		(start 30.023816 -330.63053)
		(end 30.274514 -330.806044)
		(width 0.1651)
		(layer "In5.Cu")
		(net "PE_TX3_DR11_N")
	)
	(segment
		(start 28.901644 -330.587604)
		(end 29.34081 -330.510134)
		(width 0.1651)
		(layer "In5.Cu")
		(net "PE_TX3_DR11_N")
	)
	(segment
		(start 11.777726 -343.755726)
		(end 11.515852 -343.709498)
		(width 0.1651)
		(layer "In5.Cu")
		(net "PE_TX3_DR11_N")
	)
	(segment
		(start 26.67 -330.816458)
		(end 26.898854 -330.587604)
		(width 0.1651)
		(layer "In5.Cu")
		(net "PE_TX3_DR11_N")
	)
	(segment
		(start 12.061698 -344.161618)
		(end 11.777726 -343.755726)
		(width 0.1651)
		(layer "In5.Cu")
		(net "PE_TX3_DR11_N")
	)
	(segment
		(start 9.280398 -340.862412)
		(end 7.877048 -340.61527)
		(width 0.1651)
		(layer "In5.Cu")
		(net "PE_TX3_DR11_N")
	)
	(segment
		(start 30.609032 -335.799176)
		(end 30.391354 -335.951576)
		(width 0.1651)
		(layer "In5.Cu")
		(net "PE_TX3_DR11_N")
	)
	(segment
		(start 10.49401 -341.922862)
		(end 10.210038 -341.51697)
		(width 0.1651)
		(layer "In5.Cu")
		(net "PE_TX3_DR11_N")
	)
	(segment
		(start 30.391354 -335.951576)
		(end 30.305248 -336.439256)
		(width 0.1651)
		(layer "In5.Cu")
		(net "PE_TX3_DR11_N")
	)
	(segment
		(start 26.67 -433.816506)
		(end 26.4414 -433.587906)
		(width 0.174752)
		(layer "F.Cu")
		(net "PE_TX3_DR10_P")
	)
	(segment
		(start 24.09825 -433.587906)
		(end 23.876 -433.810156)
		(width 0.174752)
		(layer "F.Cu")
		(net "PE_TX3_DR10_P")
	)
	(segment
		(start 3.658108 -408.74188)
		(end 3.905504 -408.989276)
		(width 0.174752)
		(layer "F.Cu")
		(net "PE_TX3_DR10_P")
	)
	(segment
		(start 3.905504 -408.989276)
		(end 6.738874 -408.989276)
		(width 0.174752)
		(layer "F.Cu")
		(net "PE_TX3_DR10_P")
	)
	(segment
		(start 26.4414 -433.587906)
		(end 24.09825 -433.587906)
		(width 0.174752)
		(layer "F.Cu")
		(net "PE_TX3_DR10_P")
	)
	(segment
		(start 6.738874 -408.989276)
		(end 6.992366 -408.735784)
		(width 0.174752)
		(layer "F.Cu")
		(net "PE_TX3_DR10_P")
	)
	(segment
		(start 23.876 -433.810156)
		(end 22.800056 -433.810156)
		(width 0.174752)
		(layer "F.Cu")
		(net "PE_TX3_DR10_P")
	)
	(segment
		(start 2.249932 -408.74188)
		(end 3.658108 -408.74188)
		(width 0.174752)
		(layer "F.Cu")
		(net "PE_TX3_DR10_P")
	)
	(via
		(at 6.992366 -408.735784)
		(size 0.508)
		(drill 0.254)
		(layers "F.Cu" "B.Cu")
		(net "PE_TX3_DR10_P")
	)
	(via
		(at 26.67 -433.816506)
		(size 0.508)
		(drill 0.254)
		(layers "F.Cu" "B.Cu")
		(net "PE_TX3_DR10_P")
	)
	(segment
		(start 43.249596 -415.162238)
		(end 42.472102 -419.570916)
		(width 0.1651)
		(layer "In5.Cu")
		(net "PE_TX3_DR10_P")
	)
	(segment
		(start 6.992366 -408.735784)
		(end 7.220966 -408.964384)
		(width 0.1651)
		(layer "In5.Cu")
		(net "PE_TX3_DR10_P")
	)
	(segment
		(start 11.41603 -409.63342)
		(end 20.805902 -407.977848)
		(width 0.1651)
		(layer "In5.Cu")
		(net "PE_TX3_DR10_P")
	)
	(segment
		(start 28.16606 -433.587652)
		(end 26.898854 -433.587652)
		(width 0.1651)
		(layer "In5.Cu")
		(net "PE_TX3_DR10_P")
	)
	(segment
		(start 36.706048 -427.742604)
		(end 28.515564 -433.477416)
		(width 0.1651)
		(layer "In5.Cu")
		(net "PE_TX3_DR10_P")
	)
	(segment
		(start 42.023538 -412.509462)
		(end 43.037252 -413.95777)
		(width 0.1651)
		(layer "In5.Cu")
		(net "PE_TX3_DR10_P")
	)
	(segment
		(start 7.62 -408.964384)
		(end 11.41603 -409.63342)
		(width 0.1651)
		(layer "In5.Cu")
		(net "PE_TX3_DR10_P")
	)
	(segment
		(start 40.51173 -411.451044)
		(end 42.023538 -412.509462)
		(width 0.1651)
		(layer "In5.Cu")
		(net "PE_TX3_DR10_P")
	)
	(segment
		(start 42.472102 -419.570916)
		(end 36.855654 -427.592998)
		(width 0.1651)
		(layer "In5.Cu")
		(net "PE_TX3_DR10_P")
	)
	(segment
		(start 20.805902 -407.977848)
		(end 40.51173 -411.451044)
		(width 0.1651)
		(layer "In5.Cu")
		(net "PE_TX3_DR10_P")
	)
	(segment
		(start 7.220966 -408.964384)
		(end 7.62 -408.964384)
		(width 0.1651)
		(layer "In5.Cu")
		(net "PE_TX3_DR10_P")
	)
	(segment
		(start 43.037252 -413.95777)
		(end 43.249596 -415.162238)
		(width 0.1651)
		(layer "In5.Cu")
		(net "PE_TX3_DR10_P")
	)
	(segment
		(start 26.898854 -433.587652)
		(end 26.67 -433.816506)
		(width 0.1651)
		(layer "In5.Cu")
		(net "PE_TX3_DR10_P")
	)
	(arc
		(start 28.515564 -433.477416)
		(mid 28.349287 -433.559383)
		(end 28.16606 -433.587652)
		(width 0.1651)
		(layer "In5.Cu")
		(net "PE_TX3_DR10_P")
	)
	(arc
		(start 36.855654 -427.592998)
		(mid 36.78739 -427.67434)
		(end 36.706048 -427.742604)
		(width 0.1651)
		(layer "In5.Cu")
		(net "PE_TX3_DR10_P")
	)
	(segment
		(start 26.390854 -433.282852)
		(end 24.148796 -433.282852)
		(width 0.174752)
		(layer "F.Cu")
		(net "PE_TX3_DR10_N")
	)
	(segment
		(start 3.905504 -409.29433)
		(end 6.738112 -409.29433)
		(width 0.174752)
		(layer "F.Cu")
		(net "PE_TX3_DR10_N")
	)
	(segment
		(start 24.148796 -433.282852)
		(end 23.876 -433.010056)
		(width 0.174752)
		(layer "F.Cu")
		(net "PE_TX3_DR10_N")
	)
	(segment
		(start 23.876 -433.010056)
		(end 22.800056 -433.010056)
		(width 0.174752)
		(layer "F.Cu")
		(net "PE_TX3_DR10_N")
	)
	(segment
		(start 3.657854 -409.54198)
		(end 3.905504 -409.29433)
		(width 0.174752)
		(layer "F.Cu")
		(net "PE_TX3_DR10_N")
	)
	(segment
		(start 26.67 -433.003706)
		(end 26.390854 -433.282852)
		(width 0.174752)
		(layer "F.Cu")
		(net "PE_TX3_DR10_N")
	)
	(segment
		(start 2.249932 -409.54198)
		(end 3.657854 -409.54198)
		(width 0.174752)
		(layer "F.Cu")
		(net "PE_TX3_DR10_N")
	)
	(segment
		(start 6.738112 -409.29433)
		(end 6.992366 -409.548584)
		(width 0.174752)
		(layer "F.Cu")
		(net "PE_TX3_DR10_N")
	)
	(via
		(at 6.992366 -409.548584)
		(size 0.508)
		(drill 0.254)
		(layers "F.Cu" "B.Cu")
		(net "PE_TX3_DR10_N")
	)
	(via
		(at 26.67 -433.003706)
		(size 0.508)
		(drill 0.254)
		(layers "F.Cu" "B.Cu")
		(net "PE_TX3_DR10_N")
	)
	(segment
		(start 34.746692 -428.45101)
		(end 35.008312 -428.496984)
		(width 0.1651)
		(layer "In5.Cu")
		(net "PE_TX3_DR10_N")
	)
	(segment
		(start 33.221422 -429.518826)
		(end 33.627314 -429.234854)
		(width 0.1651)
		(layer "In5.Cu")
		(net "PE_TX3_DR10_N")
	)
	(segment
		(start 40.37203 -411.787594)
		(end 20.805902 -408.339036)
		(width 0.1651)
		(layer "In5.Cu")
		(net "PE_TX3_DR10_N")
	)
	(segment
		(start 34.3408 -428.734982)
		(end 34.746692 -428.45101)
		(width 0.1651)
		(layer "In5.Cu")
		(net "PE_TX3_DR10_N")
	)
	(segment
		(start 11.41603 -409.994608)
		(end 7.588758 -409.319984)
		(width 0.1651)
		(layer "In5.Cu")
		(net "PE_TX3_DR10_N")
	)
	(segment
		(start 33.627314 -429.234854)
		(end 33.888934 -429.280828)
		(width 0.1651)
		(layer "In5.Cu")
		(net "PE_TX3_DR10_N")
	)
	(segment
		(start 42.135552 -419.431216)
		(end 42.888408 -415.162238)
		(width 0.1651)
		(layer "In5.Cu")
		(net "PE_TX3_DR10_N")
	)
	(segment
		(start 40.14724 -421.94353)
		(end 40.431466 -421.537892)
		(width 0.1651)
		(layer "In5.Cu")
		(net "PE_TX3_DR10_N")
	)
	(segment
		(start 40.193468 -422.205404)
		(end 40.14724 -421.94353)
		(width 0.1651)
		(layer "In5.Cu")
		(net "PE_TX3_DR10_N")
	)
	(segment
		(start 39.36365 -423.063162)
		(end 39.647622 -422.65727)
		(width 0.1651)
		(layer "In5.Cu")
		(net "PE_TX3_DR10_N")
	)
	(segment
		(start 35.008312 -428.496984)
		(end 36.502086 -427.451266)
		(width 0.1651)
		(layer "In5.Cu")
		(net "PE_TX3_DR10_N")
	)
	(segment
		(start 41.768014 -412.764986)
		(end 40.37203 -411.787594)
		(width 0.1651)
		(layer "In5.Cu")
		(net "PE_TX3_DR10_N")
	)
	(segment
		(start 39.909496 -422.611042)
		(end 40.193468 -422.205404)
		(width 0.1651)
		(layer "In5.Cu")
		(net "PE_TX3_DR10_N")
	)
	(segment
		(start 36.564316 -427.388782)
		(end 36.95954 -426.824394)
		(width 0.1651)
		(layer "In5.Cu")
		(net "PE_TX3_DR10_N")
	)
	(segment
		(start 7.588758 -409.319984)
		(end 7.220966 -409.319984)
		(width 0.1651)
		(layer "In5.Cu")
		(net "PE_TX3_DR10_N")
	)
	(segment
		(start 37.981128 -425.037504)
		(end 38.243002 -424.991276)
		(width 0.1651)
		(layer "In5.Cu")
		(net "PE_TX3_DR10_N")
	)
	(segment
		(start 26.67 -433.003706)
		(end 26.898346 -433.232052)
		(width 0.1651)
		(layer "In5.Cu")
		(net "PE_TX3_DR10_N")
	)
	(segment
		(start 28.311602 -433.186078)
		(end 33.175194 -429.7807)
		(width 0.1651)
		(layer "In5.Cu")
		(net "PE_TX3_DR10_N")
	)
	(segment
		(start 39.647622 -422.65727)
		(end 39.909496 -422.611042)
		(width 0.1651)
		(layer "In5.Cu")
		(net "PE_TX3_DR10_N")
	)
	(segment
		(start 42.135552 -419.43147)
		(end 42.135552 -419.431216)
		(width 0.1651)
		(layer "In5.Cu")
		(net "PE_TX3_DR10_N")
	)
	(segment
		(start 38.243002 -424.991276)
		(end 39.409624 -423.324782)
		(width 0.1651)
		(layer "In5.Cu")
		(net "PE_TX3_DR10_N")
	)
	(segment
		(start 40.431466 -421.537892)
		(end 40.693086 -421.491664)
		(width 0.1651)
		(layer "In5.Cu")
		(net "PE_TX3_DR10_N")
	)
	(segment
		(start 34.294572 -428.996856)
		(end 34.3408 -428.734982)
		(width 0.1651)
		(layer "In5.Cu")
		(net "PE_TX3_DR10_N")
	)
	(segment
		(start 33.888934 -429.280828)
		(end 34.294572 -428.996856)
		(width 0.1651)
		(layer "In5.Cu")
		(net "PE_TX3_DR10_N")
	)
	(segment
		(start 40.977058 -421.086026)
		(end 40.931084 -420.824152)
		(width 0.1651)
		(layer "In5.Cu")
		(net "PE_TX3_DR10_N")
	)
	(segment
		(start 26.898346 -433.232052)
		(end 28.16606 -433.232052)
		(width 0.1651)
		(layer "In5.Cu")
		(net "PE_TX3_DR10_N")
	)
	(segment
		(start 37.697156 -425.443142)
		(end 37.981128 -425.037504)
		(width 0.1651)
		(layer "In5.Cu")
		(net "PE_TX3_DR10_N")
	)
	(segment
		(start 42.700702 -414.097216)
		(end 41.768014 -412.764986)
		(width 0.1651)
		(layer "In5.Cu")
		(net "PE_TX3_DR10_N")
	)
	(segment
		(start 20.805902 -408.339036)
		(end 11.41603 -409.994608)
		(width 0.1651)
		(layer "In5.Cu")
		(net "PE_TX3_DR10_N")
	)
	(segment
		(start 37.197284 -426.156882)
		(end 37.459158 -426.110654)
		(width 0.1651)
		(layer "In5.Cu")
		(net "PE_TX3_DR10_N")
	)
	(segment
		(start 40.693086 -421.491664)
		(end 40.977058 -421.086026)
		(width 0.1651)
		(layer "In5.Cu")
		(net "PE_TX3_DR10_N")
	)
	(segment
		(start 39.409624 -423.324782)
		(end 39.36365 -423.063162)
		(width 0.1651)
		(layer "In5.Cu")
		(net "PE_TX3_DR10_N")
	)
	(segment
		(start 37.743384 -425.705016)
		(end 37.697156 -425.443142)
		(width 0.1651)
		(layer "In5.Cu")
		(net "PE_TX3_DR10_N")
	)
	(segment
		(start 7.220966 -409.319984)
		(end 6.992366 -409.548584)
		(width 0.1651)
		(layer "In5.Cu")
		(net "PE_TX3_DR10_N")
	)
	(segment
		(start 41.47693 -420.372286)
		(end 42.135552 -419.43147)
		(width 0.1651)
		(layer "In5.Cu")
		(net "PE_TX3_DR10_N")
	)
	(segment
		(start 36.95954 -426.824394)
		(end 36.913312 -426.56252)
		(width 0.1651)
		(layer "In5.Cu")
		(net "PE_TX3_DR10_N")
	)
	(segment
		(start 40.931084 -420.824152)
		(end 41.215056 -420.418514)
		(width 0.1651)
		(layer "In5.Cu")
		(net "PE_TX3_DR10_N")
	)
	(segment
		(start 42.888408 -415.162238)
		(end 42.700702 -414.097216)
		(width 0.1651)
		(layer "In5.Cu")
		(net "PE_TX3_DR10_N")
	)
	(segment
		(start 33.175194 -429.7807)
		(end 33.221422 -429.518826)
		(width 0.1651)
		(layer "In5.Cu")
		(net "PE_TX3_DR10_N")
	)
	(segment
		(start 37.459158 -426.110654)
		(end 37.743384 -425.705016)
		(width 0.1651)
		(layer "In5.Cu")
		(net "PE_TX3_DR10_N")
	)
	(segment
		(start 41.215056 -420.418514)
		(end 41.47693 -420.372286)
		(width 0.1651)
		(layer "In5.Cu")
		(net "PE_TX3_DR10_N")
	)
	(segment
		(start 36.913312 -426.56252)
		(end 37.197284 -426.156882)
		(width 0.1651)
		(layer "In5.Cu")
		(net "PE_TX3_DR10_N")
	)
	(arc
		(start 36.502086 -427.451266)
		(mid 36.535942 -427.422753)
		(end 36.564316 -427.388782)
		(width 0.1651)
		(layer "In5.Cu")
		(net "PE_TX3_DR10_N")
	)
	(arc
		(start 28.16606 -433.232052)
		(mid 28.242359 -433.220241)
		(end 28.311602 -433.186078)
		(width 0.1651)
		(layer "In5.Cu")
		(net "PE_TX3_DR10_N")
	)
	(segment
		(start 222.885 -381.742696)
		(end 220.58376 -381.742696)
		(width 0.174752)
		(layer "F.Cu")
		(net "PE_TX3_DR1_P")
	)
	(segment
		(start 3.657854 -394.341858)
		(end 3.90525 -394.094462)
		(width 0.174752)
		(layer "F.Cu")
		(net "PE_TX3_DR1_P")
	)
	(segment
		(start 6.738366 -394.094462)
		(end 6.992366 -394.348462)
		(width 0.174752)
		(layer "F.Cu")
		(net "PE_TX3_DR1_P")
	)
	(segment
		(start 3.90525 -394.094462)
		(end 6.738366 -394.094462)
		(width 0.174752)
		(layer "F.Cu")
		(net "PE_TX3_DR1_P")
	)
	(segment
		(start 2.249932 -394.341858)
		(end 3.657854 -394.341858)
		(width 0.174752)
		(layer "F.Cu")
		(net "PE_TX3_DR1_P")
	)
	(segment
		(start 224.199958 -381.990092)
		(end 223.132396 -381.990092)
		(width 0.174752)
		(layer "F.Cu")
		(net "PE_TX3_DR1_P")
	)
	(segment
		(start 223.132396 -381.990092)
		(end 222.885 -381.742696)
		(width 0.174752)
		(layer "F.Cu")
		(net "PE_TX3_DR1_P")
	)
	(segment
		(start 220.58376 -381.742696)
		(end 220.330014 -381.996442)
		(width 0.174752)
		(layer "F.Cu")
		(net "PE_TX3_DR1_P")
	)
	(via
		(at 220.330014 -381.996442)
		(size 0.508)
		(drill 0.254)
		(layers "F.Cu" "B.Cu")
		(net "PE_TX3_DR1_P")
	)
	(via
		(at 6.992366 -394.348462)
		(size 0.508)
		(drill 0.254)
		(layers "F.Cu" "B.Cu")
		(net "PE_TX3_DR1_P")
	)
	(segment
		(start 45.177202 -408.363674)
		(end 196.51853 -381.674878)
		(width 0.1651)
		(layer "In5.Cu")
		(net "PE_TX3_DR1_P")
	)
	(segment
		(start 6.992366 -394.348462)
		(end 7.220966 -394.119862)
		(width 0.1651)
		(layer "In5.Cu")
		(net "PE_TX3_DR1_P")
	)
	(segment
		(start 207.545686 -379.768862)
		(end 218.885516 -381.768096)
		(width 0.1651)
		(layer "In5.Cu")
		(net "PE_TX3_DR1_P")
	)
	(segment
		(start 196.51853 -381.674878)
		(end 196.51853 -381.674624)
		(width 0.1651)
		(layer "In5.Cu")
		(net "PE_TX3_DR1_P")
	)
	(segment
		(start 7.220966 -394.119862)
		(end 7.62 -394.119862)
		(width 0.1651)
		(layer "In5.Cu")
		(net "PE_TX3_DR1_P")
	)
	(segment
		(start 196.51853 -381.674624)
		(end 207.325214 -379.768862)
		(width 0.1651)
		(layer "In5.Cu")
		(net "PE_TX3_DR1_P")
	)
	(segment
		(start 7.62 -394.119862)
		(end 8.0264 -394.19149)
		(width 0.1651)
		(layer "In5.Cu")
		(net "PE_TX3_DR1_P")
	)
	(segment
		(start 220.101668 -381.768096)
		(end 220.330014 -381.996442)
		(width 0.1651)
		(layer "In5.Cu")
		(net "PE_TX3_DR1_P")
	)
	(segment
		(start 218.885516 -381.768096)
		(end 220.101668 -381.768096)
		(width 0.1651)
		(layer "In5.Cu")
		(net "PE_TX3_DR1_P")
	)
	(segment
		(start 8.0264 -394.19149)
		(end 22.694392 -404.461472)
		(width 0.1651)
		(layer "In5.Cu")
		(net "PE_TX3_DR1_P")
	)
	(segment
		(start 22.694392 -404.461472)
		(end 44.833286 -408.363674)
		(width 0.1651)
		(layer "In5.Cu")
		(net "PE_TX3_DR1_P")
	)
	(arc
		(start 44.833286 -408.363674)
		(mid 45.005244 -408.378712)
		(end 45.177202 -408.363674)
		(width 0.1651)
		(layer "In5.Cu")
		(net "PE_TX3_DR1_P")
	)
	(arc
		(start 207.325214 -379.768862)
		(mid 207.43545 -379.75922)
		(end 207.545686 -379.768862)
		(width 0.1651)
		(layer "In5.Cu")
		(net "PE_TX3_DR1_P")
	)
	(segment
		(start 2.249932 -393.542012)
		(end 3.657854 -393.542012)
		(width 0.174752)
		(layer "F.Cu")
		(net "PE_TX3_DR1_N")
	)
	(segment
		(start 3.657854 -393.542012)
		(end 3.90525 -393.789408)
		(width 0.174752)
		(layer "F.Cu")
		(net "PE_TX3_DR1_N")
	)
	(segment
		(start 224.199958 -381.189992)
		(end 223.139 -381.189992)
		(width 0.174752)
		(layer "F.Cu")
		(net "PE_TX3_DR1_N")
	)
	(segment
		(start 3.90525 -393.789408)
		(end 6.73862 -393.789408)
		(width 0.174752)
		(layer "F.Cu")
		(net "PE_TX3_DR1_N")
	)
	(segment
		(start 220.584014 -381.437642)
		(end 220.330014 -381.183642)
		(width 0.174752)
		(layer "F.Cu")
		(net "PE_TX3_DR1_N")
	)
	(segment
		(start 6.73862 -393.789408)
		(end 6.992366 -393.535662)
		(width 0.174752)
		(layer "F.Cu")
		(net "PE_TX3_DR1_N")
	)
	(segment
		(start 223.139 -381.189992)
		(end 222.89135 -381.437642)
		(width 0.174752)
		(layer "F.Cu")
		(net "PE_TX3_DR1_N")
	)
	(segment
		(start 222.89135 -381.437642)
		(end 220.584014 -381.437642)
		(width 0.174752)
		(layer "F.Cu")
		(net "PE_TX3_DR1_N")
	)
	(via
		(at 220.330014 -381.183642)
		(size 0.508)
		(drill 0.254)
		(layers "F.Cu" "B.Cu")
		(net "PE_TX3_DR1_N")
	)
	(via
		(at 6.992366 -393.535662)
		(size 0.508)
		(drill 0.254)
		(layers "F.Cu" "B.Cu")
		(net "PE_TX3_DR1_N")
	)
	(segment
		(start 207.607408 -379.418342)
		(end 218.916758 -381.412496)
		(width 0.1651)
		(layer "In5.Cu")
		(net "PE_TX3_DR1_N")
	)
	(segment
		(start 22.833838 -404.124922)
		(end 44.895008 -408.013154)
		(width 0.1651)
		(layer "In5.Cu")
		(net "PE_TX3_DR1_N")
	)
	(segment
		(start 220.10116 -381.412496)
		(end 220.330014 -381.183642)
		(width 0.1651)
		(layer "In5.Cu")
		(net "PE_TX3_DR1_N")
	)
	(segment
		(start 45.11548 -408.013154)
		(end 207.263492 -379.418342)
		(width 0.1651)
		(layer "In5.Cu")
		(net "PE_TX3_DR1_N")
	)
	(segment
		(start 7.651242 -393.764262)
		(end 8.165846 -393.85494)
		(width 0.1651)
		(layer "In5.Cu")
		(net "PE_TX3_DR1_N")
	)
	(segment
		(start 7.220966 -393.764262)
		(end 7.651242 -393.764262)
		(width 0.1651)
		(layer "In5.Cu")
		(net "PE_TX3_DR1_N")
	)
	(segment
		(start 8.165846 -393.85494)
		(end 22.833838 -404.124922)
		(width 0.1651)
		(layer "In5.Cu")
		(net "PE_TX3_DR1_N")
	)
	(segment
		(start 6.992366 -393.535662)
		(end 7.220966 -393.764262)
		(width 0.1651)
		(layer "In5.Cu")
		(net "PE_TX3_DR1_N")
	)
	(segment
		(start 218.916758 -381.412496)
		(end 220.10116 -381.412496)
		(width 0.1651)
		(layer "In5.Cu")
		(net "PE_TX3_DR1_N")
	)
	(arc
		(start 207.263492 -379.418342)
		(mid 207.43545 -379.403304)
		(end 207.607408 -379.418342)
		(width 0.1651)
		(layer "In5.Cu")
		(net "PE_TX3_DR1_N")
	)
	(arc
		(start 44.895008 -408.013154)
		(mid 45.005244 -408.022796)
		(end 45.11548 -408.013154)
		(width 0.1651)
		(layer "In5.Cu")
		(net "PE_TX3_DR1_N")
	)
	(segment
		(start 6.718808 -428.5234)
		(end 3.876294 -428.5234)
		(width 0.174752)
		(layer "F.Cu")
		(net "PE_TX3_DR0_P")
	)
	(segment
		(start 224.199958 -484.99014)
		(end 223.139 -484.99014)
		(width 0.174752)
		(layer "F.Cu")
		(net "PE_TX3_DR0_P")
	)
	(segment
		(start 223.139 -484.99014)
		(end 222.891604 -484.742744)
		(width 0.174752)
		(layer "F.Cu")
		(net "PE_TX3_DR0_P")
	)
	(segment
		(start 3.657854 -428.74184)
		(end 2.249932 -428.74184)
		(width 0.174752)
		(layer "F.Cu")
		(net "PE_TX3_DR0_P")
	)
	(segment
		(start 222.891604 -484.742744)
		(end 220.58376 -484.742744)
		(width 0.174752)
		(layer "F.Cu")
		(net "PE_TX3_DR0_P")
	)
	(segment
		(start 220.58376 -484.742744)
		(end 220.330014 -484.99649)
		(width 0.174752)
		(layer "F.Cu")
		(net "PE_TX3_DR0_P")
	)
	(segment
		(start 6.992366 -428.796958)
		(end 6.718808 -428.5234)
		(width 0.174752)
		(layer "F.Cu")
		(net "PE_TX3_DR0_P")
	)
	(segment
		(start 3.876294 -428.5234)
		(end 3.657854 -428.74184)
		(width 0.174752)
		(layer "F.Cu")
		(net "PE_TX3_DR0_P")
	)
	(via
		(at 6.992366 -428.796958)
		(size 0.508)
		(drill 0.254)
		(layers "F.Cu" "B.Cu")
		(net "PE_TX3_DR0_P")
	)
	(via
		(at 220.330014 -484.99649)
		(size 0.508)
		(drill 0.254)
		(layers "F.Cu" "B.Cu")
		(net "PE_TX3_DR0_P")
	)
	(segment
		(start 215.029542 -484.082852)
		(end 218.916758 -484.768144)
		(width 0.1651)
		(layer "In5.Cu")
		(net "PE_TX3_DR0_P")
	)
	(segment
		(start 20.273264 -459.316074)
		(end 21.971762 -459.615794)
		(width 0.1651)
		(layer "In5.Cu")
		(net "PE_TX3_DR0_P")
	)
	(segment
		(start 36.112958 -446.344802)
		(end 36.113466 -446.34404)
		(width 0.1651)
		(layer "In5.Cu")
		(net "PE_TX3_DR0_P")
	)
	(segment
		(start 7.240524 -428.5488)
		(end 7.78383 -428.5488)
		(width 0.1651)
		(layer "In5.Cu")
		(net "PE_TX3_DR0_P")
	)
	(segment
		(start 16.063214 -455.445368)
		(end 17.33042 -457.255626)
		(width 0.1651)
		(layer "In5.Cu")
		(net "PE_TX3_DR0_P")
	)
	(segment
		(start 24.020526 -459.196694)
		(end 27.008836 -457.103988)
		(width 0.1651)
		(layer "In5.Cu")
		(net "PE_TX3_DR0_P")
	)
	(segment
		(start 30.14726 -454.861168)
		(end 36.112958 -446.344802)
		(width 0.1651)
		(layer "In5.Cu")
		(net "PE_TX3_DR0_P")
	)
	(segment
		(start 14.831568 -453.686418)
		(end 16.063214 -455.445368)
		(width 0.1651)
		(layer "In5.Cu")
		(net "PE_TX3_DR0_P")
	)
	(segment
		(start 19.241516 -458.593698)
		(end 20.273264 -459.316074)
		(width 0.1651)
		(layer "In5.Cu")
		(net "PE_TX3_DR0_P")
	)
	(segment
		(start 14.786356 -453.621902)
		(end 14.831314 -453.686418)
		(width 0.1651)
		(layer "In5.Cu")
		(net "PE_TX3_DR0_P")
	)
	(segment
		(start 36.269422 -446.188338)
		(end 40.074088 -443.523878)
		(width 0.1651)
		(layer "In5.Cu")
		(net "PE_TX3_DR0_P")
	)
	(segment
		(start 220.101668 -484.768144)
		(end 220.330014 -484.99649)
		(width 0.1651)
		(layer "In5.Cu")
		(net "PE_TX3_DR0_P")
	)
	(segment
		(start 8.732774 -428.716186)
		(end 10.02538 -429.621188)
		(width 0.1651)
		(layer "In5.Cu")
		(net "PE_TX3_DR0_P")
	)
	(segment
		(start 17.33042 -457.255626)
		(end 19.241516 -458.593698)
		(width 0.1651)
		(layer "In5.Cu")
		(net "PE_TX3_DR0_P")
	)
	(segment
		(start 21.971762 -459.615794)
		(end 23.776686 -459.297786)
		(width 0.1651)
		(layer "In5.Cu")
		(net "PE_TX3_DR0_P")
	)
	(segment
		(start 41.892728 -443.203076)
		(end 195.25742 -470.235534)
		(width 0.1651)
		(layer "In5.Cu")
		(net "PE_TX3_DR0_P")
	)
	(segment
		(start 40.074088 -443.523878)
		(end 41.892728 -443.203076)
		(width 0.1651)
		(layer "In5.Cu")
		(net "PE_TX3_DR0_P")
	)
	(segment
		(start 7.78383 -428.5488)
		(end 8.732774 -428.716186)
		(width 0.1651)
		(layer "In5.Cu")
		(net "PE_TX3_DR0_P")
	)
	(segment
		(start 218.916758 -484.768144)
		(end 220.101668 -484.768144)
		(width 0.1651)
		(layer "In5.Cu")
		(net "PE_TX3_DR0_P")
	)
	(segment
		(start 195.25742 -470.235534)
		(end 215.029542 -484.082852)
		(width 0.1651)
		(layer "In5.Cu")
		(net "PE_TX3_DR0_P")
	)
	(segment
		(start 27.008836 -457.103988)
		(end 29.997146 -455.011536)
		(width 0.1651)
		(layer "In5.Cu")
		(net "PE_TX3_DR0_P")
	)
	(segment
		(start 14.831314 -453.686418)
		(end 14.831568 -453.686418)
		(width 0.1651)
		(layer "In5.Cu")
		(net "PE_TX3_DR0_P")
	)
	(segment
		(start 36.269422 -446.188084)
		(end 36.269422 -446.188338)
		(width 0.1651)
		(layer "In5.Cu")
		(net "PE_TX3_DR0_P")
	)
	(segment
		(start 10.02538 -429.621188)
		(end 10.731246 -430.629314)
		(width 0.1651)
		(layer "In5.Cu")
		(net "PE_TX3_DR0_P")
	)
	(segment
		(start 30.146752 -454.86193)
		(end 30.14726 -454.861168)
		(width 0.1651)
		(layer "In5.Cu")
		(net "PE_TX3_DR0_P")
	)
	(segment
		(start 10.731246 -430.629314)
		(end 14.786356 -453.621902)
		(width 0.1651)
		(layer "In5.Cu")
		(net "PE_TX3_DR0_P")
	)
	(segment
		(start 6.992366 -428.796958)
		(end 7.240524 -428.5488)
		(width 0.1651)
		(layer "In5.Cu")
		(net "PE_TX3_DR0_P")
	)
	(arc
		(start 29.997146 -455.011536)
		(mid 30.078488 -454.943272)
		(end 30.146752 -454.86193)
		(width 0.1651)
		(layer "In5.Cu")
		(net "PE_TX3_DR0_P")
	)
	(arc
		(start 36.113466 -446.34404)
		(mid 36.184621 -446.259239)
		(end 36.269422 -446.188084)
		(width 0.1651)
		(layer "In5.Cu")
		(net "PE_TX3_DR0_P")
	)
	(arc
		(start 23.776686 -459.297786)
		(mid 23.904157 -459.26062)
		(end 24.020526 -459.196694)
		(width 0.1651)
		(layer "In5.Cu")
		(net "PE_TX3_DR0_P")
	)
	(segment
		(start 3.657854 -427.941994)
		(end 2.249932 -427.941994)
		(width 0.174752)
		(layer "F.Cu")
		(net "PE_TX3_DR0_N")
	)
	(segment
		(start 224.199958 -484.19004)
		(end 223.13265 -484.19004)
		(width 0.174752)
		(layer "F.Cu")
		(net "PE_TX3_DR0_N")
	)
	(segment
		(start 220.584014 -484.43769)
		(end 220.330014 -484.18369)
		(width 0.174752)
		(layer "F.Cu")
		(net "PE_TX3_DR0_N")
	)
	(segment
		(start 6.758178 -428.218346)
		(end 3.934206 -428.218346)
		(width 0.174752)
		(layer "F.Cu")
		(net "PE_TX3_DR0_N")
	)
	(segment
		(start 6.992366 -427.984158)
		(end 6.758178 -428.218346)
		(width 0.174752)
		(layer "F.Cu")
		(net "PE_TX3_DR0_N")
	)
	(segment
		(start 3.934206 -428.218346)
		(end 3.657854 -427.941994)
		(width 0.174752)
		(layer "F.Cu")
		(net "PE_TX3_DR0_N")
	)
	(segment
		(start 222.885 -484.43769)
		(end 220.584014 -484.43769)
		(width 0.174752)
		(layer "F.Cu")
		(net "PE_TX3_DR0_N")
	)
	(segment
		(start 223.13265 -484.19004)
		(end 222.885 -484.43769)
		(width 0.174752)
		(layer "F.Cu")
		(net "PE_TX3_DR0_N")
	)
	(via
		(at 220.330014 -484.18369)
		(size 0.508)
		(drill 0.254)
		(layers "F.Cu" "B.Cu")
		(net "PE_TX3_DR0_N")
	)
	(via
		(at 6.992366 -427.984158)
		(size 0.508)
		(drill 0.254)
		(layers "F.Cu" "B.Cu")
		(net "PE_TX3_DR0_N")
	)
	(segment
		(start 36.06546 -445.896746)
		(end 39.934642 -443.187328)
		(width 0.1651)
		(layer "In5.Cu")
		(net "PE_TX3_DR0_N")
	)
	(segment
		(start 6.992366 -427.984158)
		(end 7.201408 -428.1932)
		(width 0.1651)
		(layer "In5.Cu")
		(net "PE_TX3_DR0_N")
	)
	(segment
		(start 36.064444 -445.897508)
		(end 36.06546 -445.896746)
		(width 0.1651)
		(layer "In5.Cu")
		(net "PE_TX3_DR0_N")
	)
	(segment
		(start 41.892728 -442.841888)
		(end 195.395342 -469.89873)
		(width 0.1651)
		(layer "In5.Cu")
		(net "PE_TX3_DR0_N")
	)
	(segment
		(start 11.067796 -430.489868)
		(end 15.122906 -453.482456)
		(width 0.1651)
		(layer "In5.Cu")
		(net "PE_TX3_DR0_N")
	)
	(segment
		(start 20.41271 -458.979524)
		(end 21.971762 -459.254606)
		(width 0.1651)
		(layer "In5.Cu")
		(net "PE_TX3_DR0_N")
	)
	(segment
		(start 195.395342 -469.89873)
		(end 195.396612 -469.89873)
		(width 0.1651)
		(layer "In5.Cu")
		(net "PE_TX3_DR0_N")
	)
	(segment
		(start 21.971762 -459.254606)
		(end 23.714964 -458.94752)
		(width 0.1651)
		(layer "In5.Cu")
		(net "PE_TX3_DR0_N")
	)
	(segment
		(start 195.396612 -469.89873)
		(end 215.168988 -483.746302)
		(width 0.1651)
		(layer "In5.Cu")
		(net "PE_TX3_DR0_N")
	)
	(segment
		(start 218.948 -484.412544)
		(end 220.10116 -484.412544)
		(width 0.1651)
		(layer "In5.Cu")
		(net "PE_TX3_DR0_N")
	)
	(segment
		(start 220.10116 -484.412544)
		(end 220.330014 -484.18369)
		(width 0.1651)
		(layer "In5.Cu")
		(net "PE_TX3_DR0_N")
	)
	(segment
		(start 19.445478 -458.30236)
		(end 20.41271 -458.979524)
		(width 0.1651)
		(layer "In5.Cu")
		(net "PE_TX3_DR0_N")
	)
	(segment
		(start 7.201408 -428.1932)
		(end 7.815072 -428.1932)
		(width 0.1651)
		(layer "In5.Cu")
		(net "PE_TX3_DR0_N")
	)
	(segment
		(start 215.168988 -483.746302)
		(end 218.948 -484.412544)
		(width 0.1651)
		(layer "In5.Cu")
		(net "PE_TX3_DR0_N")
	)
	(segment
		(start 39.934642 -443.187328)
		(end 41.892728 -442.841888)
		(width 0.1651)
		(layer "In5.Cu")
		(net "PE_TX3_DR0_N")
	)
	(segment
		(start 29.79293 -454.719944)
		(end 29.793692 -454.719436)
		(width 0.1651)
		(layer "In5.Cu")
		(net "PE_TX3_DR0_N")
	)
	(segment
		(start 10.280904 -429.365664)
		(end 11.067796 -430.489868)
		(width 0.1651)
		(layer "In5.Cu")
		(net "PE_TX3_DR0_N")
	)
	(segment
		(start 17.585944 -457.000102)
		(end 19.445478 -458.30236)
		(width 0.1651)
		(layer "In5.Cu")
		(net "PE_TX3_DR0_N")
	)
	(segment
		(start 29.855922 -454.657206)
		(end 35.821366 -446.140586)
		(width 0.1651)
		(layer "In5.Cu")
		(net "PE_TX3_DR0_N")
	)
	(segment
		(start 7.815072 -428.1932)
		(end 8.87222 -428.379636)
		(width 0.1651)
		(layer "In5.Cu")
		(net "PE_TX3_DR0_N")
	)
	(segment
		(start 15.122906 -453.482456)
		(end 17.585944 -457.000102)
		(width 0.1651)
		(layer "In5.Cu")
		(net "PE_TX3_DR0_N")
	)
	(segment
		(start 23.816564 -458.905356)
		(end 29.79293 -454.719944)
		(width 0.1651)
		(layer "In5.Cu")
		(net "PE_TX3_DR0_N")
	)
	(segment
		(start 8.87222 -428.379636)
		(end 10.280904 -429.365664)
		(width 0.1651)
		(layer "In5.Cu")
		(net "PE_TX3_DR0_N")
	)
	(arc
		(start 23.714964 -458.94752)
		(mid 23.768082 -458.932018)
		(end 23.816564 -458.905356)
		(width 0.1651)
		(layer "In5.Cu")
		(net "PE_TX3_DR0_N")
	)
	(arc
		(start 29.793692 -454.719436)
		(mid 29.827522 -454.691036)
		(end 29.855922 -454.657206)
		(width 0.1651)
		(layer "In5.Cu")
		(net "PE_TX3_DR0_N")
	)
	(arc
		(start 35.821366 -446.140586)
		(mid 35.932279 -446.008421)
		(end 36.064444 -445.897508)
		(width 0.1651)
		(layer "In5.Cu")
		(net "PE_TX3_DR0_N")
	)
	(segment
		(start 6.738112 -185.294524)
		(end 6.992366 -185.548778)
		(width 0.174752)
		(layer "F.Cu")
		(net "PE_TX2_DR9_P")
	)
	(segment
		(start 35.58413 -67.94246)
		(end 35.33013 -68.19646)
		(width 0.174752)
		(layer "F.Cu")
		(net "PE_TX2_DR9_P")
	)
	(segment
		(start 3.657854 -185.542174)
		(end 3.905504 -185.294524)
		(width 0.174752)
		(layer "F.Cu")
		(net "PE_TX2_DR9_P")
	)
	(segment
		(start 37.84346 -67.94246)
		(end 35.58413 -67.94246)
		(width 0.174752)
		(layer "F.Cu")
		(net "PE_TX2_DR9_P")
	)
	(segment
		(start 3.905504 -185.294524)
		(end 6.738112 -185.294524)
		(width 0.174752)
		(layer "F.Cu")
		(net "PE_TX2_DR9_P")
	)
	(segment
		(start 39.200074 -68.189856)
		(end 38.090856 -68.189856)
		(width 0.174752)
		(layer "F.Cu")
		(net "PE_TX2_DR9_P")
	)
	(segment
		(start 38.090856 -68.189856)
		(end 37.84346 -67.94246)
		(width 0.174752)
		(layer "F.Cu")
		(net "PE_TX2_DR9_P")
	)
	(segment
		(start 2.249932 -185.542174)
		(end 3.657854 -185.542174)
		(width 0.174752)
		(layer "F.Cu")
		(net "PE_TX2_DR9_P")
	)
	(via
		(at 6.992366 -185.548778)
		(size 0.508)
		(drill 0.254)
		(layers "F.Cu" "B.Cu")
		(net "PE_TX2_DR9_P")
	)
	(via
		(at 35.33013 -68.19646)
		(size 0.508)
		(drill 0.254)
		(layers "F.Cu" "B.Cu")
		(net "PE_TX2_DR9_P")
	)
	(segment
		(start 7.220966 -185.320178)
		(end 7.682484 -185.320178)
		(width 0.1651)
		(layer "In5.Cu")
		(net "PE_TX2_DR9_P")
	)
	(segment
		(start 43.946318 -106.160062)
		(end 43.494198 -103.595932)
		(width 0.1651)
		(layer "In5.Cu")
		(net "PE_TX2_DR9_P")
	)
	(segment
		(start 40.64762 -115.45316)
		(end 42.866564 -112.284764)
		(width 0.1651)
		(layer "In5.Cu")
		(net "PE_TX2_DR9_P")
	)
	(segment
		(start 27.723592 -171.122086)
		(end 31.075376 -152.110186)
		(width 0.1651)
		(layer "In5.Cu")
		(net "PE_TX2_DR9_P")
	)
	(segment
		(start 31.075376 -152.110186)
		(end 35.233102 -146.172936)
		(width 0.1651)
		(layer "In5.Cu")
		(net "PE_TX2_DR9_P")
	)
	(segment
		(start 35.233102 -146.172936)
		(end 40.64762 -115.45316)
		(width 0.1651)
		(layer "In5.Cu")
		(net "PE_TX2_DR9_P")
	)
	(segment
		(start 21.456396 -180.067712)
		(end 27.723592 -171.122086)
		(width 0.1651)
		(layer "In5.Cu")
		(net "PE_TX2_DR9_P")
	)
	(segment
		(start 42.70375 -102.466394)
		(end 39.974012 -100.554536)
		(width 0.1651)
		(layer "In5.Cu")
		(net "PE_TX2_DR9_P")
	)
	(segment
		(start 33.415732 -68.06184)
		(end 33.948116 -67.96786)
		(width 0.1651)
		(layer "In5.Cu")
		(net "PE_TX2_DR9_P")
	)
	(segment
		(start 42.866564 -112.284764)
		(end 43.946318 -106.160062)
		(width 0.1651)
		(layer "In5.Cu")
		(net "PE_TX2_DR9_P")
	)
	(segment
		(start 20.772882 -85.106764)
		(end 32.026098 -69.03466)
		(width 0.1651)
		(layer "In5.Cu")
		(net "PE_TX2_DR9_P")
	)
	(segment
		(start 32.026098 -69.03466)
		(end 33.415732 -68.06184)
		(width 0.1651)
		(layer "In5.Cu")
		(net "PE_TX2_DR9_P")
	)
	(segment
		(start 6.992366 -185.548778)
		(end 7.220966 -185.320178)
		(width 0.1651)
		(layer "In5.Cu")
		(net "PE_TX2_DR9_P")
	)
	(segment
		(start 25.120092 -97.93224)
		(end 22.733 -96.261428)
		(width 0.1651)
		(layer "In5.Cu")
		(net "PE_TX2_DR9_P")
	)
	(segment
		(start 39.974012 -100.554536)
		(end 25.120092 -97.93224)
		(width 0.1651)
		(layer "In5.Cu")
		(net "PE_TX2_DR9_P")
	)
	(segment
		(start 16.065246 -183.842406)
		(end 21.456396 -180.067712)
		(width 0.1651)
		(layer "In5.Cu")
		(net "PE_TX2_DR9_P")
	)
	(segment
		(start 20.055078 -89.177114)
		(end 20.772882 -85.106764)
		(width 0.1651)
		(layer "In5.Cu")
		(net "PE_TX2_DR9_P")
	)
	(segment
		(start 33.948116 -67.96786)
		(end 35.10153 -67.96786)
		(width 0.1651)
		(layer "In5.Cu")
		(net "PE_TX2_DR9_P")
	)
	(segment
		(start 20.865846 -93.59519)
		(end 20.863814 -93.592396)
		(width 0.1651)
		(layer "In5.Cu")
		(net "PE_TX2_DR9_P")
	)
	(segment
		(start 7.682484 -185.320178)
		(end 16.065246 -183.842406)
		(width 0.1651)
		(layer "In5.Cu")
		(net "PE_TX2_DR9_P")
	)
	(segment
		(start 35.10153 -67.96786)
		(end 35.33013 -68.19646)
		(width 0.1651)
		(layer "In5.Cu")
		(net "PE_TX2_DR9_P")
	)
	(segment
		(start 20.823428 -93.534738)
		(end 20.055078 -89.177114)
		(width 0.1651)
		(layer "In5.Cu")
		(net "PE_TX2_DR9_P")
	)
	(segment
		(start 43.494198 -103.595932)
		(end 42.70375 -102.466394)
		(width 0.1651)
		(layer "In5.Cu")
		(net "PE_TX2_DR9_P")
	)
	(segment
		(start 20.863814 -93.592396)
		(end 20.823428 -93.534738)
		(width 0.1651)
		(layer "In5.Cu")
		(net "PE_TX2_DR9_P")
	)
	(segment
		(start 22.733 -96.261428)
		(end 20.865846 -93.59519)
		(width 0.1651)
		(layer "In5.Cu")
		(net "PE_TX2_DR9_P")
	)
	(segment
		(start 37.846 -67.637406)
		(end 35.583876 -67.637406)
		(width 0.174752)
		(layer "F.Cu")
		(net "PE_TX2_DR9_N")
	)
	(segment
		(start 38.093396 -67.39001)
		(end 37.846 -67.637406)
		(width 0.174752)
		(layer "F.Cu")
		(net "PE_TX2_DR9_N")
	)
	(segment
		(start 6.738874 -184.98947)
		(end 6.992366 -184.735978)
		(width 0.174752)
		(layer "F.Cu")
		(net "PE_TX2_DR9_N")
	)
	(segment
		(start 39.200074 -67.39001)
		(end 38.093396 -67.39001)
		(width 0.174752)
		(layer "F.Cu")
		(net "PE_TX2_DR9_N")
	)
	(segment
		(start 35.583876 -67.637406)
		(end 35.33013 -67.38366)
		(width 0.174752)
		(layer "F.Cu")
		(net "PE_TX2_DR9_N")
	)
	(segment
		(start 3.658108 -184.742074)
		(end 3.905504 -184.98947)
		(width 0.174752)
		(layer "F.Cu")
		(net "PE_TX2_DR9_N")
	)
	(segment
		(start 2.249932 -184.742074)
		(end 3.658108 -184.742074)
		(width 0.174752)
		(layer "F.Cu")
		(net "PE_TX2_DR9_N")
	)
	(segment
		(start 3.905504 -184.98947)
		(end 6.738874 -184.98947)
		(width 0.174752)
		(layer "F.Cu")
		(net "PE_TX2_DR9_N")
	)
	(via
		(at 6.992366 -184.735978)
		(size 0.508)
		(drill 0.254)
		(layers "F.Cu" "B.Cu")
		(net "PE_TX2_DR9_N")
	)
	(via
		(at 35.33013 -67.38366)
		(size 0.508)
		(drill 0.254)
		(layers "F.Cu" "B.Cu")
		(net "PE_TX2_DR9_N")
	)
	(segment
		(start 30.738826 -151.97074)
		(end 27.387042 -170.98264)
		(width 0.1651)
		(layer "In5.Cu")
		(net "PE_TX2_DR9_N")
	)
	(segment
		(start 7.651242 -184.964578)
		(end 7.220966 -184.964578)
		(width 0.1651)
		(layer "In5.Cu")
		(net "PE_TX2_DR9_N")
	)
	(segment
		(start 42.530014 -112.145318)
		(end 40.31107 -115.313714)
		(width 0.1651)
		(layer "In5.Cu")
		(net "PE_TX2_DR9_N")
	)
	(segment
		(start 39.834566 -100.891086)
		(end 42.448226 -102.721918)
		(width 0.1651)
		(layer "In5.Cu")
		(net "PE_TX2_DR9_N")
	)
	(segment
		(start 33.916874 -67.61226)
		(end 33.276286 -67.72529)
		(width 0.1651)
		(layer "In5.Cu")
		(net "PE_TX2_DR9_N")
	)
	(segment
		(start 20.572476 -93.796612)
		(end 20.574508 -93.799406)
		(width 0.1651)
		(layer "In5.Cu")
		(net "PE_TX2_DR9_N")
	)
	(segment
		(start 19.69389 -89.177114)
		(end 20.486624 -93.67393)
		(width 0.1651)
		(layer "In5.Cu")
		(net "PE_TX2_DR9_N")
	)
	(segment
		(start 20.574508 -93.799406)
		(end 22.477476 -96.516952)
		(width 0.1651)
		(layer "In5.Cu")
		(net "PE_TX2_DR9_N")
	)
	(segment
		(start 7.220966 -184.964578)
		(end 6.992366 -184.735978)
		(width 0.1651)
		(layer "In5.Cu")
		(net "PE_TX2_DR9_N")
	)
	(segment
		(start 35.10153 -67.61226)
		(end 33.916874 -67.61226)
		(width 0.1651)
		(layer "In5.Cu")
		(net "PE_TX2_DR9_N")
	)
	(segment
		(start 35.33013 -67.38366)
		(end 35.10153 -67.61226)
		(width 0.1651)
		(layer "In5.Cu")
		(net "PE_TX2_DR9_N")
	)
	(segment
		(start 43.58513 -106.160062)
		(end 42.530014 -112.145318)
		(width 0.1651)
		(layer "In5.Cu")
		(net "PE_TX2_DR9_N")
	)
	(segment
		(start 22.477476 -96.516952)
		(end 24.980646 -98.26879)
		(width 0.1651)
		(layer "In5.Cu")
		(net "PE_TX2_DR9_N")
	)
	(segment
		(start 33.276286 -67.72529)
		(end 31.770574 -68.779136)
		(width 0.1651)
		(layer "In5.Cu")
		(net "PE_TX2_DR9_N")
	)
	(segment
		(start 40.31107 -115.313714)
		(end 34.896552 -146.03349)
		(width 0.1651)
		(layer "In5.Cu")
		(net "PE_TX2_DR9_N")
	)
	(segment
		(start 20.486624 -93.67393)
		(end 20.572222 -93.796612)
		(width 0.1651)
		(layer "In5.Cu")
		(net "PE_TX2_DR9_N")
	)
	(segment
		(start 21.201126 -179.811934)
		(end 15.9258 -183.505856)
		(width 0.1651)
		(layer "In5.Cu")
		(net "PE_TX2_DR9_N")
	)
	(segment
		(start 31.770574 -68.779136)
		(end 20.436332 -84.967318)
		(width 0.1651)
		(layer "In5.Cu")
		(net "PE_TX2_DR9_N")
	)
	(segment
		(start 42.448226 -102.721918)
		(end 43.157648 -103.735378)
		(width 0.1651)
		(layer "In5.Cu")
		(net "PE_TX2_DR9_N")
	)
	(segment
		(start 20.436332 -84.967318)
		(end 19.69389 -89.177114)
		(width 0.1651)
		(layer "In5.Cu")
		(net "PE_TX2_DR9_N")
	)
	(segment
		(start 21.200872 -179.811934)
		(end 21.201126 -179.811934)
		(width 0.1651)
		(layer "In5.Cu")
		(net "PE_TX2_DR9_N")
	)
	(segment
		(start 24.980646 -98.26879)
		(end 39.834566 -100.891086)
		(width 0.1651)
		(layer "In5.Cu")
		(net "PE_TX2_DR9_N")
	)
	(segment
		(start 34.896552 -146.03349)
		(end 30.738826 -151.97074)
		(width 0.1651)
		(layer "In5.Cu")
		(net "PE_TX2_DR9_N")
	)
	(segment
		(start 27.387042 -170.98264)
		(end 21.200872 -179.811934)
		(width 0.1651)
		(layer "In5.Cu")
		(net "PE_TX2_DR9_N")
	)
	(segment
		(start 15.9258 -183.505856)
		(end 7.651242 -184.964578)
		(width 0.1651)
		(layer "In5.Cu")
		(net "PE_TX2_DR9_N")
	)
	(segment
		(start 20.572222 -93.796612)
		(end 20.572476 -93.796612)
		(width 0.1651)
		(layer "In5.Cu")
		(net "PE_TX2_DR9_N")
	)
	(segment
		(start 43.157648 -103.735378)
		(end 43.58513 -106.160062)
		(width 0.1651)
		(layer "In5.Cu")
		(net "PE_TX2_DR9_N")
	)
	(segment
		(start 2.249932 -205.542134)
		(end 3.657854 -205.542134)
		(width 0.174752)
		(layer "F.Cu")
		(net "PE_TX2_DR8_P")
	)
	(segment
		(start 37.852604 -170.942508)
		(end 35.58413 -170.942508)
		(width 0.174752)
		(layer "F.Cu")
		(net "PE_TX2_DR8_P")
	)
	(segment
		(start 6.738112 -205.294484)
		(end 6.992366 -205.548738)
		(width 0.174752)
		(layer "F.Cu")
		(net "PE_TX2_DR8_P")
	)
	(segment
		(start 3.905504 -205.294484)
		(end 6.738112 -205.294484)
		(width 0.174752)
		(layer "F.Cu")
		(net "PE_TX2_DR8_P")
	)
	(segment
		(start 35.58413 -170.942508)
		(end 35.33013 -171.196508)
		(width 0.174752)
		(layer "F.Cu")
		(net "PE_TX2_DR8_P")
	)
	(segment
		(start 3.657854 -205.542134)
		(end 3.905504 -205.294484)
		(width 0.174752)
		(layer "F.Cu")
		(net "PE_TX2_DR8_P")
	)
	(segment
		(start 39.200074 -171.189904)
		(end 38.1 -171.189904)
		(width 0.174752)
		(layer "F.Cu")
		(net "PE_TX2_DR8_P")
	)
	(segment
		(start 38.1 -171.189904)
		(end 37.852604 -170.942508)
		(width 0.174752)
		(layer "F.Cu")
		(net "PE_TX2_DR8_P")
	)
	(via
		(at 35.33013 -171.196508)
		(size 0.508)
		(drill 0.254)
		(layers "F.Cu" "B.Cu")
		(net "PE_TX2_DR8_P")
	)
	(via
		(at 6.992366 -205.548738)
		(size 0.508)
		(drill 0.254)
		(layers "F.Cu" "B.Cu")
		(net "PE_TX2_DR8_P")
	)
	(segment
		(start 33.059624 -171.296584)
		(end 33.377378 -171.07408)
		(width 0.1651)
		(layer "In5.Cu")
		(net "PE_TX2_DR8_P")
	)
	(segment
		(start 7.220966 -205.320138)
		(end 7.682484 -205.320138)
		(width 0.1651)
		(layer "In5.Cu")
		(net "PE_TX2_DR8_P")
	)
	(segment
		(start 7.682484 -205.320138)
		(end 9.083548 -205.073504)
		(width 0.1651)
		(layer "In5.Cu")
		(net "PE_TX2_DR8_P")
	)
	(segment
		(start 6.992366 -205.548738)
		(end 7.220966 -205.320138)
		(width 0.1651)
		(layer "In5.Cu")
		(net "PE_TX2_DR8_P")
	)
	(segment
		(start 33.377378 -171.07408)
		(end 33.979358 -170.967908)
		(width 0.1651)
		(layer "In5.Cu")
		(net "PE_TX2_DR8_P")
	)
	(segment
		(start 9.72439 -204.625194)
		(end 33.059624 -171.296584)
		(width 0.1651)
		(layer "In5.Cu")
		(net "PE_TX2_DR8_P")
	)
	(segment
		(start 33.979358 -170.967908)
		(end 35.10153 -170.967908)
		(width 0.1651)
		(layer "In5.Cu")
		(net "PE_TX2_DR8_P")
	)
	(segment
		(start 9.083548 -205.073504)
		(end 9.72439 -204.625194)
		(width 0.1651)
		(layer "In5.Cu")
		(net "PE_TX2_DR8_P")
	)
	(segment
		(start 35.10153 -170.967908)
		(end 35.33013 -171.196508)
		(width 0.1651)
		(layer "In5.Cu")
		(net "PE_TX2_DR8_P")
	)
	(segment
		(start 3.658108 -204.742034)
		(end 3.905504 -204.98943)
		(width 0.174752)
		(layer "F.Cu")
		(net "PE_TX2_DR8_N")
	)
	(segment
		(start 3.905504 -204.98943)
		(end 6.738874 -204.98943)
		(width 0.174752)
		(layer "F.Cu")
		(net "PE_TX2_DR8_N")
	)
	(segment
		(start 38.093396 -170.390058)
		(end 37.846 -170.637454)
		(width 0.174752)
		(layer "F.Cu")
		(net "PE_TX2_DR8_N")
	)
	(segment
		(start 37.846 -170.637454)
		(end 35.583876 -170.637454)
		(width 0.174752)
		(layer "F.Cu")
		(net "PE_TX2_DR8_N")
	)
	(segment
		(start 6.738874 -204.98943)
		(end 6.992366 -204.735938)
		(width 0.174752)
		(layer "F.Cu")
		(net "PE_TX2_DR8_N")
	)
	(segment
		(start 39.200074 -170.390058)
		(end 38.093396 -170.390058)
		(width 0.174752)
		(layer "F.Cu")
		(net "PE_TX2_DR8_N")
	)
	(segment
		(start 2.249932 -204.742034)
		(end 3.658108 -204.742034)
		(width 0.174752)
		(layer "F.Cu")
		(net "PE_TX2_DR8_N")
	)
	(segment
		(start 35.583876 -170.637454)
		(end 35.33013 -170.383708)
		(width 0.174752)
		(layer "F.Cu")
		(net "PE_TX2_DR8_N")
	)
	(via
		(at 6.992366 -204.735938)
		(size 0.508)
		(drill 0.254)
		(layers "F.Cu" "B.Cu")
		(net "PE_TX2_DR8_N")
	)
	(via
		(at 35.33013 -170.383708)
		(size 0.508)
		(drill 0.254)
		(layers "F.Cu" "B.Cu")
		(net "PE_TX2_DR8_N")
	)
	(segment
		(start 8.944102 -204.736954)
		(end 7.651242 -204.964538)
		(width 0.1651)
		(layer "In5.Cu")
		(net "PE_TX2_DR8_N")
	)
	(segment
		(start 9.468866 -204.36967)
		(end 8.944102 -204.736954)
		(width 0.1651)
		(layer "In5.Cu")
		(net "PE_TX2_DR8_N")
	)
	(segment
		(start 33.237932 -170.73753)
		(end 32.8041 -171.04106)
		(width 0.1651)
		(layer "In5.Cu")
		(net "PE_TX2_DR8_N")
	)
	(segment
		(start 33.948116 -170.612308)
		(end 33.237932 -170.73753)
		(width 0.1651)
		(layer "In5.Cu")
		(net "PE_TX2_DR8_N")
	)
	(segment
		(start 7.220966 -204.964538)
		(end 6.992366 -204.735938)
		(width 0.1651)
		(layer "In5.Cu")
		(net "PE_TX2_DR8_N")
	)
	(segment
		(start 35.10153 -170.612308)
		(end 33.948116 -170.612308)
		(width 0.1651)
		(layer "In5.Cu")
		(net "PE_TX2_DR8_N")
	)
	(segment
		(start 35.33013 -170.383708)
		(end 35.10153 -170.612308)
		(width 0.1651)
		(layer "In5.Cu")
		(net "PE_TX2_DR8_N")
	)
	(segment
		(start 32.8041 -171.04106)
		(end 9.468866 -204.36967)
		(width 0.1651)
		(layer "In5.Cu")
		(net "PE_TX2_DR8_N")
	)
	(segment
		(start 7.651242 -204.964538)
		(end 7.220966 -204.964538)
		(width 0.1651)
		(layer "In5.Cu")
		(net "PE_TX2_DR8_N")
	)
	(segment
		(start 6.738112 -304.894488)
		(end 6.992366 -305.148742)
		(width 0.174752)
		(layer "F.Cu")
		(net "PE_TX2_DR7_P")
	)
	(segment
		(start 35.58413 -273.942556)
		(end 35.33013 -274.196556)
		(width 0.174752)
		(layer "F.Cu")
		(net "PE_TX2_DR7_P")
	)
	(segment
		(start 37.852604 -273.942556)
		(end 35.58413 -273.942556)
		(width 0.174752)
		(layer "F.Cu")
		(net "PE_TX2_DR7_P")
	)
	(segment
		(start 3.657854 -305.142138)
		(end 3.905504 -304.894488)
		(width 0.174752)
		(layer "F.Cu")
		(net "PE_TX2_DR7_P")
	)
	(segment
		(start 38.1 -274.189952)
		(end 37.852604 -273.942556)
		(width 0.174752)
		(layer "F.Cu")
		(net "PE_TX2_DR7_P")
	)
	(segment
		(start 39.200074 -274.189952)
		(end 38.1 -274.189952)
		(width 0.174752)
		(layer "F.Cu")
		(net "PE_TX2_DR7_P")
	)
	(segment
		(start 2.249932 -305.142138)
		(end 3.657854 -305.142138)
		(width 0.174752)
		(layer "F.Cu")
		(net "PE_TX2_DR7_P")
	)
	(segment
		(start 3.905504 -304.894488)
		(end 6.738112 -304.894488)
		(width 0.174752)
		(layer "F.Cu")
		(net "PE_TX2_DR7_P")
	)
	(via
		(at 6.992366 -305.148742)
		(size 0.508)
		(drill 0.254)
		(layers "F.Cu" "B.Cu")
		(net "PE_TX2_DR7_P")
	)
	(via
		(at 35.33013 -274.196556)
		(size 0.508)
		(drill 0.254)
		(layers "F.Cu" "B.Cu")
		(net "PE_TX2_DR7_P")
	)
	(segment
		(start 7.220966 -304.920142)
		(end 6.992366 -305.148742)
		(width 0.1651)
		(layer "In5.Cu")
		(net "PE_TX2_DR7_P")
	)
	(segment
		(start 33.168336 -274.209764)
		(end 31.819342 -275.154644)
		(width 0.1651)
		(layer "In5.Cu")
		(net "PE_TX2_DR7_P")
	)
	(segment
		(start 7.682484 -304.920142)
		(end 7.220966 -304.920142)
		(width 0.1651)
		(layer "In5.Cu")
		(net "PE_TX2_DR7_P")
	)
	(segment
		(start 35.10153 -273.967956)
		(end 33.979358 -273.967956)
		(width 0.1651)
		(layer "In5.Cu")
		(net "PE_TX2_DR7_P")
	)
	(segment
		(start 31.819342 -275.154644)
		(end 13.417804 -301.426372)
		(width 0.1651)
		(layer "In5.Cu")
		(net "PE_TX2_DR7_P")
	)
	(segment
		(start 33.979358 -273.967956)
		(end 33.356296 -274.077938)
		(width 0.1651)
		(layer "In5.Cu")
		(net "PE_TX2_DR7_P")
	)
	(segment
		(start 35.33013 -274.196556)
		(end 35.10153 -273.967956)
		(width 0.1651)
		(layer "In5.Cu")
		(net "PE_TX2_DR7_P")
	)
	(segment
		(start 13.41755 -301.426626)
		(end 8.678672 -304.744628)
		(width 0.1651)
		(layer "In5.Cu")
		(net "PE_TX2_DR7_P")
	)
	(segment
		(start 13.417804 -301.426372)
		(end 13.41755 -301.426626)
		(width 0.1651)
		(layer "In5.Cu")
		(net "PE_TX2_DR7_P")
	)
	(segment
		(start 8.678672 -304.744628)
		(end 7.682484 -304.920142)
		(width 0.1651)
		(layer "In5.Cu")
		(net "PE_TX2_DR7_P")
	)
	(segment
		(start 33.356296 -274.077938)
		(end 33.254696 -274.149312)
		(width 0.1651)
		(layer "In5.Cu")
		(net "PE_TX2_DR7_P")
	)
	(segment
		(start 33.254696 -274.149312)
		(end 33.168336 -274.209764)
		(width 0.1651)
		(layer "In5.Cu")
		(net "PE_TX2_DR7_P")
	)
	(segment
		(start 38.093396 -273.390106)
		(end 37.846 -273.637502)
		(width 0.174752)
		(layer "F.Cu")
		(net "PE_TX2_DR7_N")
	)
	(segment
		(start 3.905504 -304.589434)
		(end 6.738874 -304.589434)
		(width 0.174752)
		(layer "F.Cu")
		(net "PE_TX2_DR7_N")
	)
	(segment
		(start 35.583876 -273.637502)
		(end 35.33013 -273.383756)
		(width 0.174752)
		(layer "F.Cu")
		(net "PE_TX2_DR7_N")
	)
	(segment
		(start 39.200074 -273.390106)
		(end 38.093396 -273.390106)
		(width 0.174752)
		(layer "F.Cu")
		(net "PE_TX2_DR7_N")
	)
	(segment
		(start 37.846 -273.637502)
		(end 35.583876 -273.637502)
		(width 0.174752)
		(layer "F.Cu")
		(net "PE_TX2_DR7_N")
	)
	(segment
		(start 3.658108 -304.342038)
		(end 3.905504 -304.589434)
		(width 0.174752)
		(layer "F.Cu")
		(net "PE_TX2_DR7_N")
	)
	(segment
		(start 6.738874 -304.589434)
		(end 6.992366 -304.335942)
		(width 0.174752)
		(layer "F.Cu")
		(net "PE_TX2_DR7_N")
	)
	(segment
		(start 2.249932 -304.342038)
		(end 3.658108 -304.342038)
		(width 0.174752)
		(layer "F.Cu")
		(net "PE_TX2_DR7_N")
	)
	(via
		(at 35.33013 -273.383756)
		(size 0.508)
		(drill 0.254)
		(layers "F.Cu" "B.Cu")
		(net "PE_TX2_DR7_N")
	)
	(via
		(at 6.992366 -304.335942)
		(size 0.508)
		(drill 0.254)
		(layers "F.Cu" "B.Cu")
		(net "PE_TX2_DR7_N")
	)
	(segment
		(start 35.33013 -273.383756)
		(end 35.10153 -273.612356)
		(width 0.1651)
		(layer "In5.Cu")
		(net "PE_TX2_DR7_N")
	)
	(segment
		(start 31.563818 -274.89912)
		(end 13.16228 -301.170848)
		(width 0.1651)
		(layer "In5.Cu")
		(net "PE_TX2_DR7_N")
	)
	(segment
		(start 33.948116 -273.612356)
		(end 33.21685 -273.741388)
		(width 0.1651)
		(layer "In5.Cu")
		(net "PE_TX2_DR7_N")
	)
	(segment
		(start 35.10153 -273.612356)
		(end 33.948116 -273.612356)
		(width 0.1651)
		(layer "In5.Cu")
		(net "PE_TX2_DR7_N")
	)
	(segment
		(start 13.16228 -301.170848)
		(end 8.539226 -304.408078)
		(width 0.1651)
		(layer "In5.Cu")
		(net "PE_TX2_DR7_N")
	)
	(segment
		(start 33.21685 -273.741388)
		(end 33.216596 -273.741388)
		(width 0.1651)
		(layer "In5.Cu")
		(net "PE_TX2_DR7_N")
	)
	(segment
		(start 33.216596 -273.741388)
		(end 31.563818 -274.89912)
		(width 0.1651)
		(layer "In5.Cu")
		(net "PE_TX2_DR7_N")
	)
	(segment
		(start 8.539226 -304.408078)
		(end 7.651242 -304.564542)
		(width 0.1651)
		(layer "In5.Cu")
		(net "PE_TX2_DR7_N")
	)
	(segment
		(start 7.220966 -304.564542)
		(end 6.992366 -304.335942)
		(width 0.1651)
		(layer "In5.Cu")
		(net "PE_TX2_DR7_N")
	)
	(segment
		(start 7.651242 -304.564542)
		(end 7.220966 -304.564542)
		(width 0.1651)
		(layer "In5.Cu")
		(net "PE_TX2_DR7_N")
	)
	(segment
		(start 37.846 -376.942604)
		(end 35.58413 -376.942604)
		(width 0.174752)
		(layer "F.Cu")
		(net "PE_TX2_DR6_P")
	)
	(segment
		(start 38.093396 -377.19)
		(end 37.846 -376.942604)
		(width 0.174752)
		(layer "F.Cu")
		(net "PE_TX2_DR6_P")
	)
	(segment
		(start 2.249932 -350.741996)
		(end 3.657854 -350.741996)
		(width 0.174752)
		(layer "F.Cu")
		(net "PE_TX2_DR6_P")
	)
	(segment
		(start 3.657854 -350.741996)
		(end 3.905504 -350.494346)
		(width 0.174752)
		(layer "F.Cu")
		(net "PE_TX2_DR6_P")
	)
	(segment
		(start 3.905504 -350.494346)
		(end 6.738112 -350.494346)
		(width 0.174752)
		(layer "F.Cu")
		(net "PE_TX2_DR6_P")
	)
	(segment
		(start 6.738112 -350.494346)
		(end 6.992366 -350.7486)
		(width 0.174752)
		(layer "F.Cu")
		(net "PE_TX2_DR6_P")
	)
	(segment
		(start 39.200074 -377.19)
		(end 38.093396 -377.19)
		(width 0.174752)
		(layer "F.Cu")
		(net "PE_TX2_DR6_P")
	)
	(segment
		(start 35.58413 -376.942604)
		(end 35.33013 -377.196604)
		(width 0.174752)
		(layer "F.Cu")
		(net "PE_TX2_DR6_P")
	)
	(via
		(at 35.33013 -377.196604)
		(size 0.508)
		(drill 0.254)
		(layers "F.Cu" "B.Cu")
		(net "PE_TX2_DR6_P")
	)
	(via
		(at 6.992366 -350.7486)
		(size 0.508)
		(drill 0.254)
		(layers "F.Cu" "B.Cu")
		(net "PE_TX2_DR6_P")
	)
	(segment
		(start 10.246106 -351.647252)
		(end 8.967724 -350.751902)
		(width 0.1651)
		(layer "In5.Cu")
		(net "PE_TX2_DR6_P")
	)
	(segment
		(start 18.077942 -379.62332)
		(end 16.6878 -377.637294)
		(width 0.1651)
		(layer "In5.Cu")
		(net "PE_TX2_DR6_P")
	)
	(segment
		(start 7.651242 -350.52)
		(end 7.220966 -350.52)
		(width 0.1651)
		(layer "In5.Cu")
		(net "PE_TX2_DR6_P")
	)
	(segment
		(start 33.947608 -376.968258)
		(end 30.844744 -377.520708)
		(width 0.1651)
		(layer "In5.Cu")
		(net "PE_TX2_DR6_P")
	)
	(segment
		(start 22.783038 -381.794004)
		(end 20.638008 -381.415544)
		(width 0.1651)
		(layer "In5.Cu")
		(net "PE_TX2_DR6_P")
	)
	(segment
		(start 35.10153 -376.968004)
		(end 33.948878 -376.968004)
		(width 0.1651)
		(layer "In5.Cu")
		(net "PE_TX2_DR6_P")
	)
	(segment
		(start 30.844744 -377.520708)
		(end 25.401524 -381.331978)
		(width 0.1651)
		(layer "In5.Cu")
		(net "PE_TX2_DR6_P")
	)
	(segment
		(start 8.967724 -350.751902)
		(end 7.651242 -350.52)
		(width 0.1651)
		(layer "In5.Cu")
		(net "PE_TX2_DR6_P")
	)
	(segment
		(start 12.732004 -355.19741)
		(end 10.246106 -351.647252)
		(width 0.1651)
		(layer "In5.Cu")
		(net "PE_TX2_DR6_P")
	)
	(segment
		(start 20.638008 -381.415544)
		(end 18.077942 -379.62332)
		(width 0.1651)
		(layer "In5.Cu")
		(net "PE_TX2_DR6_P")
	)
	(segment
		(start 7.220966 -350.52)
		(end 6.992366 -350.7486)
		(width 0.1651)
		(layer "In5.Cu")
		(net "PE_TX2_DR6_P")
	)
	(segment
		(start 16.6878 -377.637294)
		(end 12.732004 -355.19741)
		(width 0.1651)
		(layer "In5.Cu")
		(net "PE_TX2_DR6_P")
	)
	(segment
		(start 33.948878 -376.968004)
		(end 33.947608 -376.968258)
		(width 0.1651)
		(layer "In5.Cu")
		(net "PE_TX2_DR6_P")
	)
	(segment
		(start 35.33013 -377.196604)
		(end 35.10153 -376.968004)
		(width 0.1651)
		(layer "In5.Cu")
		(net "PE_TX2_DR6_P")
	)
	(segment
		(start 25.401524 -381.331978)
		(end 22.783038 -381.794004)
		(width 0.1651)
		(layer "In5.Cu")
		(net "PE_TX2_DR6_P")
	)
	(segment
		(start 3.905504 -350.189292)
		(end 6.738874 -350.189292)
		(width 0.174752)
		(layer "F.Cu")
		(net "PE_TX2_DR6_N")
	)
	(segment
		(start 6.738874 -350.189292)
		(end 6.992366 -349.9358)
		(width 0.174752)
		(layer "F.Cu")
		(net "PE_TX2_DR6_N")
	)
	(segment
		(start 38.1 -376.390154)
		(end 37.852604 -376.63755)
		(width 0.174752)
		(layer "F.Cu")
		(net "PE_TX2_DR6_N")
	)
	(segment
		(start 39.200074 -376.390154)
		(end 38.1 -376.390154)
		(width 0.174752)
		(layer "F.Cu")
		(net "PE_TX2_DR6_N")
	)
	(segment
		(start 3.658362 -349.94215)
		(end 3.905504 -350.189292)
		(width 0.174752)
		(layer "F.Cu")
		(net "PE_TX2_DR6_N")
	)
	(segment
		(start 35.583876 -376.63755)
		(end 35.33013 -376.383804)
		(width 0.174752)
		(layer "F.Cu")
		(net "PE_TX2_DR6_N")
	)
	(segment
		(start 37.852604 -376.63755)
		(end 35.583876 -376.63755)
		(width 0.174752)
		(layer "F.Cu")
		(net "PE_TX2_DR6_N")
	)
	(segment
		(start 2.249932 -349.94215)
		(end 3.658362 -349.94215)
		(width 0.174752)
		(layer "F.Cu")
		(net "PE_TX2_DR6_N")
	)
	(via
		(at 35.33013 -376.383804)
		(size 0.508)
		(drill 0.254)
		(layers "F.Cu" "B.Cu")
		(net "PE_TX2_DR6_N")
	)
	(via
		(at 6.992366 -349.9358)
		(size 0.508)
		(drill 0.254)
		(layers "F.Cu" "B.Cu")
		(net "PE_TX2_DR6_N")
	)
	(segment
		(start 17.02435 -377.497848)
		(end 13.068554 -355.057964)
		(width 0.1651)
		(layer "In5.Cu")
		(net "PE_TX2_DR6_N")
	)
	(segment
		(start 9.10717 -350.415352)
		(end 7.682484 -350.1644)
		(width 0.1651)
		(layer "In5.Cu")
		(net "PE_TX2_DR6_N")
	)
	(segment
		(start 25.262078 -380.995428)
		(end 22.783038 -381.432816)
		(width 0.1651)
		(layer "In5.Cu")
		(net "PE_TX2_DR6_N")
	)
	(segment
		(start 33.885886 -376.617738)
		(end 33.885124 -376.617992)
		(width 0.1651)
		(layer "In5.Cu")
		(net "PE_TX2_DR6_N")
	)
	(segment
		(start 7.220966 -350.1644)
		(end 6.992366 -349.9358)
		(width 0.1651)
		(layer "In5.Cu")
		(net "PE_TX2_DR6_N")
	)
	(segment
		(start 10.50163 -351.391728)
		(end 9.10717 -350.415352)
		(width 0.1651)
		(layer "In5.Cu")
		(net "PE_TX2_DR6_N")
	)
	(segment
		(start 20.777454 -381.078994)
		(end 18.333466 -379.367796)
		(width 0.1651)
		(layer "In5.Cu")
		(net "PE_TX2_DR6_N")
	)
	(segment
		(start 35.10153 -376.612404)
		(end 33.91662 -376.612404)
		(width 0.1651)
		(layer "In5.Cu")
		(net "PE_TX2_DR6_N")
	)
	(segment
		(start 30.705044 -377.184158)
		(end 25.262078 -380.995428)
		(width 0.1651)
		(layer "In5.Cu")
		(net "PE_TX2_DR6_N")
	)
	(segment
		(start 13.068554 -355.057964)
		(end 10.50163 -351.391728)
		(width 0.1651)
		(layer "In5.Cu")
		(net "PE_TX2_DR6_N")
	)
	(segment
		(start 18.333466 -379.367796)
		(end 17.02435 -377.497848)
		(width 0.1651)
		(layer "In5.Cu")
		(net "PE_TX2_DR6_N")
	)
	(segment
		(start 35.33013 -376.383804)
		(end 35.10153 -376.612404)
		(width 0.1651)
		(layer "In5.Cu")
		(net "PE_TX2_DR6_N")
	)
	(segment
		(start 33.91662 -376.612404)
		(end 33.885886 -376.617738)
		(width 0.1651)
		(layer "In5.Cu")
		(net "PE_TX2_DR6_N")
	)
	(segment
		(start 33.885124 -376.617992)
		(end 30.705044 -377.184158)
		(width 0.1651)
		(layer "In5.Cu")
		(net "PE_TX2_DR6_N")
	)
	(segment
		(start 7.682484 -350.1644)
		(end 7.220966 -350.1644)
		(width 0.1651)
		(layer "In5.Cu")
		(net "PE_TX2_DR6_N")
	)
	(segment
		(start 22.783038 -381.432816)
		(end 20.777454 -381.078994)
		(width 0.1651)
		(layer "In5.Cu")
		(net "PE_TX2_DR6_N")
	)
	(segment
		(start 35.571176 -479.624898)
		(end 35.33013 -479.383852)
		(width 0.174752)
		(layer "F.Cu")
		(net "PE_TX2_DR5_P")
	)
	(segment
		(start 3.953764 -440.23788)
		(end 6.73862 -440.23788)
		(width 0.174752)
		(layer "F.Cu")
		(net "PE_TX2_DR5_P")
	)
	(segment
		(start 6.73862 -440.23788)
		(end 6.992366 -439.984134)
		(width 0.174752)
		(layer "F.Cu")
		(net "PE_TX2_DR5_P")
	)
	(segment
		(start 3.657854 -439.94197)
		(end 3.953764 -440.23788)
		(width 0.174752)
		(layer "F.Cu")
		(net "PE_TX2_DR5_P")
	)
	(segment
		(start 37.7317 -479.624898)
		(end 35.571176 -479.624898)
		(width 0.174752)
		(layer "F.Cu")
		(net "PE_TX2_DR5_P")
	)
	(segment
		(start 2.249932 -439.94197)
		(end 3.657854 -439.94197)
		(width 0.174752)
		(layer "F.Cu")
		(net "PE_TX2_DR5_P")
	)
	(segment
		(start 39.200074 -479.390202)
		(end 37.966396 -479.390202)
		(width 0.174752)
		(layer "F.Cu")
		(net "PE_TX2_DR5_P")
	)
	(segment
		(start 37.966396 -479.390202)
		(end 37.7317 -479.624898)
		(width 0.174752)
		(layer "F.Cu")
		(net "PE_TX2_DR5_P")
	)
	(via
		(at 6.992366 -439.984134)
		(size 0.508)
		(drill 0.254)
		(layers "F.Cu" "B.Cu")
		(net "PE_TX2_DR5_P")
	)
	(via
		(at 35.33013 -479.383852)
		(size 0.508)
		(drill 0.254)
		(layers "F.Cu" "B.Cu")
		(net "PE_TX2_DR5_P")
	)
	(segment
		(start 7.220966 -440.212734)
		(end 6.992366 -439.984134)
		(width 0.1651)
		(layer "In5.Cu")
		(net "PE_TX2_DR5_P")
	)
	(segment
		(start 18.414746 -475.487492)
		(end 14.931898 -470.51341)
		(width 0.1651)
		(layer "In5.Cu")
		(net "PE_TX2_DR5_P")
	)
	(segment
		(start 7.926578 -440.212734)
		(end 7.220966 -440.212734)
		(width 0.1651)
		(layer "In5.Cu")
		(net "PE_TX2_DR5_P")
	)
	(segment
		(start 14.931898 -470.51341)
		(end 9.977374 -442.41593)
		(width 0.1651)
		(layer "In5.Cu")
		(net "PE_TX2_DR5_P")
	)
	(segment
		(start 8.034782 -440.231784)
		(end 7.926578 -440.212734)
		(width 0.1651)
		(layer "In5.Cu")
		(net "PE_TX2_DR5_P")
	)
	(segment
		(start 24.736298 -479.913442)
		(end 18.414746 -475.487492)
		(width 0.1651)
		(layer "In5.Cu")
		(net "PE_TX2_DR5_P")
	)
	(segment
		(start 8.845042 -440.798712)
		(end 8.034782 -440.231784)
		(width 0.1651)
		(layer "In5.Cu")
		(net "PE_TX2_DR5_P")
	)
	(segment
		(start 35.10153 -479.612452)
		(end 33.916874 -479.612452)
		(width 0.1651)
		(layer "In5.Cu")
		(net "PE_TX2_DR5_P")
	)
	(segment
		(start 9.977374 -442.41593)
		(end 8.845042 -440.798712)
		(width 0.1651)
		(layer "In5.Cu")
		(net "PE_TX2_DR5_P")
	)
	(segment
		(start 28.51658 -480.564444)
		(end 24.736298 -479.913442)
		(width 0.1651)
		(layer "In5.Cu")
		(net "PE_TX2_DR5_P")
	)
	(segment
		(start 35.33013 -479.383852)
		(end 35.10153 -479.612452)
		(width 0.1651)
		(layer "In5.Cu")
		(net "PE_TX2_DR5_P")
	)
	(segment
		(start 33.916874 -479.612452)
		(end 28.51658 -480.564444)
		(width 0.1651)
		(layer "In5.Cu")
		(net "PE_TX2_DR5_P")
	)
	(segment
		(start 39.200074 -480.190048)
		(end 37.966396 -480.190048)
		(width 0.174752)
		(layer "F.Cu")
		(net "PE_TX2_DR5_N")
	)
	(segment
		(start 37.966396 -480.190048)
		(end 37.7063 -479.929952)
		(width 0.174752)
		(layer "F.Cu")
		(net "PE_TX2_DR5_N")
	)
	(segment
		(start 37.7063 -479.929952)
		(end 35.59683 -479.929952)
		(width 0.174752)
		(layer "F.Cu")
		(net "PE_TX2_DR5_N")
	)
	(segment
		(start 3.856736 -440.542934)
		(end 6.738366 -440.542934)
		(width 0.174752)
		(layer "F.Cu")
		(net "PE_TX2_DR5_N")
	)
	(segment
		(start 6.738366 -440.542934)
		(end 6.992366 -440.796934)
		(width 0.174752)
		(layer "F.Cu")
		(net "PE_TX2_DR5_N")
	)
	(segment
		(start 3.657854 -440.741816)
		(end 3.856736 -440.542934)
		(width 0.174752)
		(layer "F.Cu")
		(net "PE_TX2_DR5_N")
	)
	(segment
		(start 2.249932 -440.741816)
		(end 3.657854 -440.741816)
		(width 0.174752)
		(layer "F.Cu")
		(net "PE_TX2_DR5_N")
	)
	(segment
		(start 35.59683 -479.929952)
		(end 35.33013 -480.196652)
		(width 0.174752)
		(layer "F.Cu")
		(net "PE_TX2_DR5_N")
	)
	(via
		(at 6.992366 -440.796934)
		(size 0.508)
		(drill 0.254)
		(layers "F.Cu" "B.Cu")
		(net "PE_TX2_DR5_N")
	)
	(via
		(at 35.33013 -480.196652)
		(size 0.508)
		(drill 0.254)
		(layers "F.Cu" "B.Cu")
		(net "PE_TX2_DR5_N")
	)
	(segment
		(start 35.33013 -480.196652)
		(end 35.10153 -479.968052)
		(width 0.1651)
		(layer "In5.Cu")
		(net "PE_TX2_DR5_N")
	)
	(segment
		(start 35.10153 -479.968052)
		(end 33.948116 -479.968052)
		(width 0.1651)
		(layer "In5.Cu")
		(net "PE_TX2_DR5_N")
	)
	(segment
		(start 24.597614 -480.2505)
		(end 18.159222 -475.743016)
		(width 0.1651)
		(layer "In5.Cu")
		(net "PE_TX2_DR5_N")
	)
	(segment
		(start 28.517342 -480.925632)
		(end 24.597614 -480.2505)
		(width 0.1651)
		(layer "In5.Cu")
		(net "PE_TX2_DR5_N")
	)
	(segment
		(start 9.640824 -442.555376)
		(end 8.589518 -441.054236)
		(width 0.1651)
		(layer "In5.Cu")
		(net "PE_TX2_DR5_N")
	)
	(segment
		(start 7.895336 -440.568334)
		(end 7.220966 -440.568334)
		(width 0.1651)
		(layer "In5.Cu")
		(net "PE_TX2_DR5_N")
	)
	(segment
		(start 14.595348 -470.652856)
		(end 9.640824 -442.555376)
		(width 0.1651)
		(layer "In5.Cu")
		(net "PE_TX2_DR5_N")
	)
	(segment
		(start 8.589518 -441.054236)
		(end 7.895336 -440.568334)
		(width 0.1651)
		(layer "In5.Cu")
		(net "PE_TX2_DR5_N")
	)
	(segment
		(start 7.220966 -440.568334)
		(end 6.992366 -440.796934)
		(width 0.1651)
		(layer "In5.Cu")
		(net "PE_TX2_DR5_N")
	)
	(segment
		(start 18.159222 -475.743016)
		(end 14.595348 -470.652856)
		(width 0.1651)
		(layer "In5.Cu")
		(net "PE_TX2_DR5_N")
	)
	(segment
		(start 33.948116 -479.968052)
		(end 28.517342 -480.925632)
		(width 0.1651)
		(layer "In5.Cu")
		(net "PE_TX2_DR5_N")
	)
	(segment
		(start 224.199958 -68.189856)
		(end 223.139 -68.189856)
		(width 0.174752)
		(layer "F.Cu")
		(net "PE_TX2_DR4_P")
	)
	(segment
		(start 6.738112 -230.894382)
		(end 6.992366 -231.148636)
		(width 0.174752)
		(layer "F.Cu")
		(net "PE_TX2_DR4_P")
	)
	(segment
		(start 222.891604 -67.94246)
		(end 220.584014 -67.94246)
		(width 0.174752)
		(layer "F.Cu")
		(net "PE_TX2_DR4_P")
	)
	(segment
		(start 3.657854 -231.142032)
		(end 3.905504 -230.894382)
		(width 0.174752)
		(layer "F.Cu")
		(net "PE_TX2_DR4_P")
	)
	(segment
		(start 223.139 -68.189856)
		(end 222.891604 -67.94246)
		(width 0.174752)
		(layer "F.Cu")
		(net "PE_TX2_DR4_P")
	)
	(segment
		(start 220.584014 -67.94246)
		(end 220.330014 -68.19646)
		(width 0.174752)
		(layer "F.Cu")
		(net "PE_TX2_DR4_P")
	)
	(segment
		(start 3.905504 -230.894382)
		(end 6.738112 -230.894382)
		(width 0.174752)
		(layer "F.Cu")
		(net "PE_TX2_DR4_P")
	)
	(segment
		(start 2.249932 -231.142032)
		(end 3.657854 -231.142032)
		(width 0.174752)
		(layer "F.Cu")
		(net "PE_TX2_DR4_P")
	)
	(via
		(at 220.330014 -68.19646)
		(size 0.508)
		(drill 0.254)
		(layers "F.Cu" "B.Cu")
		(net "PE_TX2_DR4_P")
	)
	(via
		(at 6.992366 -231.148636)
		(size 0.508)
		(drill 0.254)
		(layers "F.Cu" "B.Cu")
		(net "PE_TX2_DR4_P")
	)
	(segment
		(start 218.916758 -67.96786)
		(end 220.101414 -67.96786)
		(width 0.1651)
		(layer "In5.Cu")
		(net "PE_TX2_DR4_P")
	)
	(segment
		(start 18.161508 -256.48666)
		(end 19.097244 -256.48666)
		(width 0.1651)
		(layer "In5.Cu")
		(net "PE_TX2_DR4_P")
	)
	(segment
		(start 30.023562 -249.517408)
		(end 31.335726 -247.643396)
		(width 0.1651)
		(layer "In5.Cu")
		(net "PE_TX2_DR4_P")
	)
	(segment
		(start 20.394422 -256.25933)
		(end 30.023562 -249.517408)
		(width 0.1651)
		(layer "In5.Cu")
		(net "PE_TX2_DR4_P")
	)
	(segment
		(start 9.476994 -231.860852)
		(end 11.63193 -234.938316)
		(width 0.1651)
		(layer "In5.Cu")
		(net "PE_TX2_DR4_P")
	)
	(segment
		(start 11.63193 -234.938316)
		(end 15.031466 -254.21971)
		(width 0.1651)
		(layer "In5.Cu")
		(net "PE_TX2_DR4_P")
	)
	(segment
		(start 220.101414 -67.96786)
		(end 220.330014 -68.19646)
		(width 0.1651)
		(layer "In5.Cu")
		(net "PE_TX2_DR4_P")
	)
	(segment
		(start 6.992366 -231.148636)
		(end 7.220966 -230.920036)
		(width 0.1651)
		(layer "In5.Cu")
		(net "PE_TX2_DR4_P")
	)
	(segment
		(start 32.933894 -238.578136)
		(end 88.94318 -158.617158)
		(width 0.1651)
		(layer "In5.Cu")
		(net "PE_TX2_DR4_P")
	)
	(segment
		(start 16.143986 -255.78943)
		(end 16.795496 -256.24536)
		(width 0.1651)
		(layer "In5.Cu")
		(net "PE_TX2_DR4_P")
	)
	(segment
		(start 7.651242 -230.920036)
		(end 8.296148 -231.033828)
		(width 0.1651)
		(layer "In5.Cu")
		(net "PE_TX2_DR4_P")
	)
	(segment
		(start 16.795496 -256.24536)
		(end 18.161508 -256.48666)
		(width 0.1651)
		(layer "In5.Cu")
		(net "PE_TX2_DR4_P")
	)
	(segment
		(start 16.099536 -255.74498)
		(end 16.143986 -255.78943)
		(width 0.1651)
		(layer "In5.Cu")
		(net "PE_TX2_DR4_P")
	)
	(segment
		(start 88.94318 -158.617158)
		(end 218.23299 -68.08851)
		(width 0.1651)
		(layer "In5.Cu")
		(net "PE_TX2_DR4_P")
	)
	(segment
		(start 7.220966 -230.920036)
		(end 7.651242 -230.920036)
		(width 0.1651)
		(layer "In5.Cu")
		(net "PE_TX2_DR4_P")
	)
	(segment
		(start 31.335726 -247.643396)
		(end 32.933894 -238.578136)
		(width 0.1651)
		(layer "In5.Cu")
		(net "PE_TX2_DR4_P")
	)
	(segment
		(start 218.23299 -68.08851)
		(end 218.916758 -67.96786)
		(width 0.1651)
		(layer "In5.Cu")
		(net "PE_TX2_DR4_P")
	)
	(segment
		(start 15.031466 -254.21971)
		(end 16.099536 -255.74498)
		(width 0.1651)
		(layer "In5.Cu")
		(net "PE_TX2_DR4_P")
	)
	(segment
		(start 8.296148 -231.033828)
		(end 9.476994 -231.860852)
		(width 0.1651)
		(layer "In5.Cu")
		(net "PE_TX2_DR4_P")
	)
	(segment
		(start 19.097244 -256.48666)
		(end 20.394422 -256.25933)
		(width 0.1651)
		(layer "In5.Cu")
		(net "PE_TX2_DR4_P")
	)
	(segment
		(start 224.199958 -67.39001)
		(end 223.132396 -67.39001)
		(width 0.174752)
		(layer "F.Cu")
		(net "PE_TX2_DR4_N")
	)
	(segment
		(start 2.249932 -230.342186)
		(end 3.658362 -230.342186)
		(width 0.174752)
		(layer "F.Cu")
		(net "PE_TX2_DR4_N")
	)
	(segment
		(start 220.58376 -67.637406)
		(end 220.330014 -67.38366)
		(width 0.174752)
		(layer "F.Cu")
		(net "PE_TX2_DR4_N")
	)
	(segment
		(start 3.905504 -230.589328)
		(end 6.738874 -230.589328)
		(width 0.174752)
		(layer "F.Cu")
		(net "PE_TX2_DR4_N")
	)
	(segment
		(start 6.738874 -230.589328)
		(end 6.992366 -230.335836)
		(width 0.174752)
		(layer "F.Cu")
		(net "PE_TX2_DR4_N")
	)
	(segment
		(start 223.132396 -67.39001)
		(end 222.885 -67.637406)
		(width 0.174752)
		(layer "F.Cu")
		(net "PE_TX2_DR4_N")
	)
	(segment
		(start 3.658362 -230.342186)
		(end 3.905504 -230.589328)
		(width 0.174752)
		(layer "F.Cu")
		(net "PE_TX2_DR4_N")
	)
	(segment
		(start 222.885 -67.637406)
		(end 220.58376 -67.637406)
		(width 0.174752)
		(layer "F.Cu")
		(net "PE_TX2_DR4_N")
	)
	(via
		(at 220.330014 -67.38366)
		(size 0.508)
		(drill 0.254)
		(layers "F.Cu" "B.Cu")
		(net "PE_TX2_DR4_N")
	)
	(via
		(at 6.992366 -230.335836)
		(size 0.508)
		(drill 0.254)
		(layers "F.Cu" "B.Cu")
		(net "PE_TX2_DR4_N")
	)
	(segment
		(start 6.992366 -230.335836)
		(end 7.220966 -230.564436)
		(width 0.1651)
		(layer "In5.Cu")
		(net "PE_TX2_DR4_N")
	)
	(segment
		(start 9.731756 -231.604566)
		(end 9.732518 -231.605328)
		(width 0.1651)
		(layer "In5.Cu")
		(net "PE_TX2_DR4_N")
	)
	(segment
		(start 19.066256 -256.13106)
		(end 20.254976 -255.922526)
		(width 0.1651)
		(layer "In5.Cu")
		(net "PE_TX2_DR4_N")
	)
	(segment
		(start 20.25523 -255.922526)
		(end 29.768038 -249.261884)
		(width 0.1651)
		(layer "In5.Cu")
		(net "PE_TX2_DR4_N")
	)
	(segment
		(start 29.768038 -249.261884)
		(end 30.999176 -247.50395)
		(width 0.1651)
		(layer "In5.Cu")
		(net "PE_TX2_DR4_N")
	)
	(segment
		(start 8.435594 -230.697278)
		(end 9.731756 -231.604566)
		(width 0.1651)
		(layer "In5.Cu")
		(net "PE_TX2_DR4_N")
	)
	(segment
		(start 30.999176 -247.50395)
		(end 32.597344 -238.43869)
		(width 0.1651)
		(layer "In5.Cu")
		(net "PE_TX2_DR4_N")
	)
	(segment
		(start 88.68791 -158.36138)
		(end 218.093544 -67.75196)
		(width 0.1651)
		(layer "In5.Cu")
		(net "PE_TX2_DR4_N")
	)
	(segment
		(start 16.373348 -255.515872)
		(end 16.934942 -255.90881)
		(width 0.1651)
		(layer "In5.Cu")
		(net "PE_TX2_DR4_N")
	)
	(segment
		(start 20.254976 -255.922526)
		(end 20.25523 -255.922526)
		(width 0.1651)
		(layer "In5.Cu")
		(net "PE_TX2_DR4_N")
	)
	(segment
		(start 16.373094 -255.515618)
		(end 16.373348 -255.515872)
		(width 0.1651)
		(layer "In5.Cu")
		(net "PE_TX2_DR4_N")
	)
	(segment
		(start 16.934942 -255.90881)
		(end 18.19275 -256.13106)
		(width 0.1651)
		(layer "In5.Cu")
		(net "PE_TX2_DR4_N")
	)
	(segment
		(start 218.093544 -67.75196)
		(end 218.885516 -67.61226)
		(width 0.1651)
		(layer "In5.Cu")
		(net "PE_TX2_DR4_N")
	)
	(segment
		(start 7.682484 -230.564436)
		(end 8.435594 -230.697278)
		(width 0.1651)
		(layer "In5.Cu")
		(net "PE_TX2_DR4_N")
	)
	(segment
		(start 32.597344 -238.43869)
		(end 88.68791 -158.36138)
		(width 0.1651)
		(layer "In5.Cu")
		(net "PE_TX2_DR4_N")
	)
	(segment
		(start 18.19275 -256.13106)
		(end 19.066256 -256.13106)
		(width 0.1651)
		(layer "In5.Cu")
		(net "PE_TX2_DR4_N")
	)
	(segment
		(start 9.732518 -231.605328)
		(end 11.96848 -234.79887)
		(width 0.1651)
		(layer "In5.Cu")
		(net "PE_TX2_DR4_N")
	)
	(segment
		(start 220.101414 -67.61226)
		(end 220.330014 -67.38366)
		(width 0.1651)
		(layer "In5.Cu")
		(net "PE_TX2_DR4_N")
	)
	(segment
		(start 7.220966 -230.564436)
		(end 7.682484 -230.564436)
		(width 0.1651)
		(layer "In5.Cu")
		(net "PE_TX2_DR4_N")
	)
	(segment
		(start 15.368016 -254.080264)
		(end 16.373094 -255.515618)
		(width 0.1651)
		(layer "In5.Cu")
		(net "PE_TX2_DR4_N")
	)
	(segment
		(start 218.885516 -67.61226)
		(end 220.101414 -67.61226)
		(width 0.1651)
		(layer "In5.Cu")
		(net "PE_TX2_DR4_N")
	)
	(segment
		(start 11.96848 -234.79887)
		(end 15.368016 -254.080264)
		(width 0.1651)
		(layer "In5.Cu")
		(net "PE_TX2_DR4_N")
	)
	(segment
		(start 220.584014 -170.942508)
		(end 220.330014 -171.196508)
		(width 0.174752)
		(layer "F.Cu")
		(net "PE_TX2_DR3_P")
	)
	(segment
		(start 222.891604 -170.942508)
		(end 220.584014 -170.942508)
		(width 0.174752)
		(layer "F.Cu")
		(net "PE_TX2_DR3_P")
	)
	(segment
		(start 224.199958 -171.189904)
		(end 223.139 -171.189904)
		(width 0.174752)
		(layer "F.Cu")
		(net "PE_TX2_DR3_P")
	)
	(segment
		(start 223.139 -171.189904)
		(end 222.891604 -170.942508)
		(width 0.174752)
		(layer "F.Cu")
		(net "PE_TX2_DR3_P")
	)
	(segment
		(start 3.905504 -292.094412)
		(end 6.738112 -292.094412)
		(width 0.174752)
		(layer "F.Cu")
		(net "PE_TX2_DR3_P")
	)
	(segment
		(start 6.738112 -292.094412)
		(end 6.992366 -292.348666)
		(width 0.174752)
		(layer "F.Cu")
		(net "PE_TX2_DR3_P")
	)
	(segment
		(start 2.249932 -292.342062)
		(end 3.657854 -292.342062)
		(width 0.174752)
		(layer "F.Cu")
		(net "PE_TX2_DR3_P")
	)
	(segment
		(start 3.657854 -292.342062)
		(end 3.905504 -292.094412)
		(width 0.174752)
		(layer "F.Cu")
		(net "PE_TX2_DR3_P")
	)
	(via
		(at 6.992366 -292.348666)
		(size 0.508)
		(drill 0.254)
		(layers "F.Cu" "B.Cu")
		(net "PE_TX2_DR3_P")
	)
	(via
		(at 220.330014 -171.196508)
		(size 0.508)
		(drill 0.254)
		(layers "F.Cu" "B.Cu")
		(net "PE_TX2_DR3_P")
	)
	(segment
		(start 220.101414 -170.967908)
		(end 220.330014 -171.196508)
		(width 0.1651)
		(layer "In5.Cu")
		(net "PE_TX2_DR3_P")
	)
	(segment
		(start 32.581342 -252.931422)
		(end 35.228022 -249.151902)
		(width 0.1651)
		(layer "In5.Cu")
		(net "PE_TX2_DR3_P")
	)
	(segment
		(start 12.849352 -292.308534)
		(end 15.015718 -290.790884)
		(width 0.1651)
		(layer "In5.Cu")
		(net "PE_TX2_DR3_P")
	)
	(segment
		(start 6.992366 -292.348666)
		(end 7.220966 -292.120066)
		(width 0.1651)
		(layer "In5.Cu")
		(net "PE_TX2_DR3_P")
	)
	(segment
		(start 27.014678 -273.654012)
		(end 30.024832 -256.582164)
		(width 0.1651)
		(layer "In5.Cu")
		(net "PE_TX2_DR3_P")
	)
	(segment
		(start 218.746832 -170.967908)
		(end 220.101414 -170.967908)
		(width 0.1651)
		(layer "In5.Cu")
		(net "PE_TX2_DR3_P")
	)
	(segment
		(start 35.228022 -249.151902)
		(end 36.82746 -240.083594)
		(width 0.1651)
		(layer "In5.Cu")
		(net "PE_TX2_DR3_P")
	)
	(segment
		(start 81.98358 -194.36207)
		(end 203.66482 -172.906436)
		(width 0.1651)
		(layer "In5.Cu")
		(net "PE_TX2_DR3_P")
	)
	(segment
		(start 56.20512 -212.412326)
		(end 56.206136 -212.411564)
		(width 0.1651)
		(layer "In5.Cu")
		(net "PE_TX2_DR3_P")
	)
	(segment
		(start 56.204612 -212.41258)
		(end 56.20512 -212.412326)
		(width 0.1651)
		(layer "In5.Cu")
		(net "PE_TX2_DR3_P")
	)
	(segment
		(start 30.024832 -256.582164)
		(end 32.581342 -252.931422)
		(width 0.1651)
		(layer "In5.Cu")
		(net "PE_TX2_DR3_P")
	)
	(segment
		(start 36.82746 -240.083594)
		(end 56.204612 -212.41258)
		(width 0.1651)
		(layer "In5.Cu")
		(net "PE_TX2_DR3_P")
	)
	(segment
		(start 10.752328 -292.75405)
		(end 12.849352 -292.308534)
		(width 0.1651)
		(layer "In5.Cu")
		(net "PE_TX2_DR3_P")
	)
	(segment
		(start 15.015718 -290.790884)
		(end 27.014678 -273.654012)
		(width 0.1651)
		(layer "In5.Cu")
		(net "PE_TX2_DR3_P")
	)
	(segment
		(start 203.66482 -172.906436)
		(end 206.73822 -170.91152)
		(width 0.1651)
		(layer "In5.Cu")
		(net "PE_TX2_DR3_P")
	)
	(segment
		(start 7.768844 -292.120066)
		(end 10.752328 -292.75405)
		(width 0.1651)
		(layer "In5.Cu")
		(net "PE_TX2_DR3_P")
	)
	(segment
		(start 212.609176 -169.663364)
		(end 218.746832 -170.967908)
		(width 0.1651)
		(layer "In5.Cu")
		(net "PE_TX2_DR3_P")
	)
	(segment
		(start 7.220966 -292.120066)
		(end 7.768844 -292.120066)
		(width 0.1651)
		(layer "In5.Cu")
		(net "PE_TX2_DR3_P")
	)
	(segment
		(start 206.73822 -170.91152)
		(end 212.609176 -169.663364)
		(width 0.1651)
		(layer "In5.Cu")
		(net "PE_TX2_DR3_P")
	)
	(segment
		(start 56.206136 -212.411564)
		(end 81.98358 -194.36207)
		(width 0.1651)
		(layer "In5.Cu")
		(net "PE_TX2_DR3_P")
	)
	(segment
		(start 223.132396 -170.390058)
		(end 222.885 -170.637454)
		(width 0.174752)
		(layer "F.Cu")
		(net "PE_TX2_DR3_N")
	)
	(segment
		(start 3.658362 -291.542216)
		(end 3.905504 -291.789358)
		(width 0.174752)
		(layer "F.Cu")
		(net "PE_TX2_DR3_N")
	)
	(segment
		(start 2.249932 -291.542216)
		(end 3.658362 -291.542216)
		(width 0.174752)
		(layer "F.Cu")
		(net "PE_TX2_DR3_N")
	)
	(segment
		(start 6.738874 -291.789358)
		(end 6.992366 -291.535866)
		(width 0.174752)
		(layer "F.Cu")
		(net "PE_TX2_DR3_N")
	)
	(segment
		(start 224.199958 -170.390058)
		(end 223.132396 -170.390058)
		(width 0.174752)
		(layer "F.Cu")
		(net "PE_TX2_DR3_N")
	)
	(segment
		(start 222.885 -170.637454)
		(end 220.58376 -170.637454)
		(width 0.174752)
		(layer "F.Cu")
		(net "PE_TX2_DR3_N")
	)
	(segment
		(start 220.58376 -170.637454)
		(end 220.330014 -170.383708)
		(width 0.174752)
		(layer "F.Cu")
		(net "PE_TX2_DR3_N")
	)
	(segment
		(start 3.905504 -291.789358)
		(end 6.738874 -291.789358)
		(width 0.174752)
		(layer "F.Cu")
		(net "PE_TX2_DR3_N")
	)
	(via
		(at 6.992366 -291.535866)
		(size 0.508)
		(drill 0.254)
		(layers "F.Cu" "B.Cu")
		(net "PE_TX2_DR3_N")
	)
	(via
		(at 220.330014 -170.383708)
		(size 0.508)
		(drill 0.254)
		(layers "F.Cu" "B.Cu")
		(net "PE_TX2_DR3_N")
	)
	(segment
		(start 56.000904 -212.120988)
		(end 56.001666 -212.12048)
		(width 0.1651)
		(layer "In5.Cu")
		(net "PE_TX2_DR3_N")
	)
	(segment
		(start 212.609176 -169.299636)
		(end 218.026996 -170.451272)
		(width 0.1651)
		(layer "In5.Cu")
		(net "PE_TX2_DR3_N")
	)
	(segment
		(start 220.101414 -170.612308)
		(end 220.330014 -170.383708)
		(width 0.1651)
		(layer "In5.Cu")
		(net "PE_TX2_DR3_N")
	)
	(segment
		(start 36.49091 -239.944148)
		(end 55.949596 -212.156802)
		(width 0.1651)
		(layer "In5.Cu")
		(net "PE_TX2_DR3_N")
	)
	(segment
		(start 56.001666 -212.12048)
		(end 56.041798 -212.092286)
		(width 0.1651)
		(layer "In5.Cu")
		(net "PE_TX2_DR3_N")
	)
	(segment
		(start 6.992366 -291.535866)
		(end 7.220966 -291.764466)
		(width 0.1651)
		(layer "In5.Cu")
		(net "PE_TX2_DR3_N")
	)
	(segment
		(start 7.220966 -291.764466)
		(end 7.806436 -291.764466)
		(width 0.1651)
		(layer "In5.Cu")
		(net "PE_TX2_DR3_N")
	)
	(segment
		(start 206.59979 -170.577256)
		(end 212.609176 -169.299636)
		(width 0.1651)
		(layer "In5.Cu")
		(net "PE_TX2_DR3_N")
	)
	(segment
		(start 55.949596 -212.156802)
		(end 56.000904 -212.120988)
		(width 0.1651)
		(layer "In5.Cu")
		(net "PE_TX2_DR3_N")
	)
	(segment
		(start 81.844134 -194.02552)
		(end 203.531724 -172.568616)
		(width 0.1651)
		(layer "In5.Cu")
		(net "PE_TX2_DR3_N")
	)
	(segment
		(start 26.678128 -273.514566)
		(end 29.688282 -256.442718)
		(width 0.1651)
		(layer "In5.Cu")
		(net "PE_TX2_DR3_N")
	)
	(segment
		(start 29.688282 -256.442718)
		(end 34.891472 -249.012456)
		(width 0.1651)
		(layer "In5.Cu")
		(net "PE_TX2_DR3_N")
	)
	(segment
		(start 10.752328 -292.390322)
		(end 12.704572 -291.97554)
		(width 0.1651)
		(layer "In5.Cu")
		(net "PE_TX2_DR3_N")
	)
	(segment
		(start 7.806436 -291.764466)
		(end 10.752328 -292.390322)
		(width 0.1651)
		(layer "In5.Cu")
		(net "PE_TX2_DR3_N")
	)
	(segment
		(start 12.704572 -291.97554)
		(end 14.760194 -290.53536)
		(width 0.1651)
		(layer "In5.Cu")
		(net "PE_TX2_DR3_N")
	)
	(segment
		(start 34.891472 -249.012456)
		(end 36.49091 -239.944148)
		(width 0.1651)
		(layer "In5.Cu")
		(net "PE_TX2_DR3_N")
	)
	(segment
		(start 218.026996 -170.451272)
		(end 218.785186 -170.612308)
		(width 0.1651)
		(layer "In5.Cu")
		(net "PE_TX2_DR3_N")
	)
	(segment
		(start 56.041798 -212.092286)
		(end 81.844134 -194.02552)
		(width 0.1651)
		(layer "In5.Cu")
		(net "PE_TX2_DR3_N")
	)
	(segment
		(start 203.531724 -172.568616)
		(end 206.59979 -170.577256)
		(width 0.1651)
		(layer "In5.Cu")
		(net "PE_TX2_DR3_N")
	)
	(segment
		(start 218.785186 -170.612308)
		(end 220.101414 -170.612308)
		(width 0.1651)
		(layer "In5.Cu")
		(net "PE_TX2_DR3_N")
	)
	(segment
		(start 14.760194 -290.53536)
		(end 26.678128 -273.514566)
		(width 0.1651)
		(layer "In5.Cu")
		(net "PE_TX2_DR3_N")
	)
	(segment
		(start 222.891604 -273.942556)
		(end 220.584014 -273.942556)
		(width 0.174752)
		(layer "F.Cu")
		(net "PE_TX2_DR2_P")
	)
	(segment
		(start 224.199958 -274.189952)
		(end 223.139 -274.189952)
		(width 0.174752)
		(layer "F.Cu")
		(net "PE_TX2_DR2_P")
	)
	(segment
		(start 3.905504 -322.494402)
		(end 6.738112 -322.494402)
		(width 0.174752)
		(layer "F.Cu")
		(net "PE_TX2_DR2_P")
	)
	(segment
		(start 2.249932 -322.742052)
		(end 3.657854 -322.742052)
		(width 0.174752)
		(layer "F.Cu")
		(net "PE_TX2_DR2_P")
	)
	(segment
		(start 3.657854 -322.742052)
		(end 3.905504 -322.494402)
		(width 0.174752)
		(layer "F.Cu")
		(net "PE_TX2_DR2_P")
	)
	(segment
		(start 220.584014 -273.942556)
		(end 220.330014 -274.196556)
		(width 0.174752)
		(layer "F.Cu")
		(net "PE_TX2_DR2_P")
	)
	(segment
		(start 6.738112 -322.494402)
		(end 6.992366 -322.748656)
		(width 0.174752)
		(layer "F.Cu")
		(net "PE_TX2_DR2_P")
	)
	(segment
		(start 223.139 -274.189952)
		(end 222.891604 -273.942556)
		(width 0.174752)
		(layer "F.Cu")
		(net "PE_TX2_DR2_P")
	)
	(via
		(at 6.992366 -322.748656)
		(size 0.508)
		(drill 0.254)
		(layers "F.Cu" "B.Cu")
		(net "PE_TX2_DR2_P")
	)
	(via
		(at 220.330014 -274.196556)
		(size 0.508)
		(drill 0.254)
		(layers "F.Cu" "B.Cu")
		(net "PE_TX2_DR2_P")
	)
	(segment
		(start 220.101414 -273.967956)
		(end 218.916758 -273.967956)
		(width 0.1651)
		(layer "In5.Cu")
		(net "PE_TX2_DR2_P")
	)
	(segment
		(start 8.423148 -322.389754)
		(end 7.682484 -322.520056)
		(width 0.1651)
		(layer "In5.Cu")
		(net "PE_TX2_DR2_P")
	)
	(segment
		(start 218.916758 -273.967956)
		(end 184.770522 -267.94714)
		(width 0.1651)
		(layer "In5.Cu")
		(net "PE_TX2_DR2_P")
	)
	(segment
		(start 23.175976 -302.242474)
		(end 20.5232 -302.710596)
		(width 0.1651)
		(layer "In5.Cu")
		(net "PE_TX2_DR2_P")
	)
	(segment
		(start 20.5232 -302.710596)
		(end 16.068802 -305.829716)
		(width 0.1651)
		(layer "In5.Cu")
		(net "PE_TX2_DR2_P")
	)
	(segment
		(start 10.495788 -320.938652)
		(end 10.49528 -320.93916)
		(width 0.1651)
		(layer "In5.Cu")
		(net "PE_TX2_DR2_P")
	)
	(segment
		(start 12.98448 -317.384684)
		(end 10.495788 -320.938652)
		(width 0.1651)
		(layer "In5.Cu")
		(net "PE_TX2_DR2_P")
	)
	(segment
		(start 7.682484 -322.520056)
		(end 7.220966 -322.520056)
		(width 0.1651)
		(layer "In5.Cu")
		(net "PE_TX2_DR2_P")
	)
	(segment
		(start 220.330014 -274.196556)
		(end 220.101414 -273.967956)
		(width 0.1651)
		(layer "In5.Cu")
		(net "PE_TX2_DR2_P")
	)
	(segment
		(start 7.220966 -322.520056)
		(end 6.992366 -322.748656)
		(width 0.1651)
		(layer "In5.Cu")
		(net "PE_TX2_DR2_P")
	)
	(segment
		(start 39.10965 -305.051968)
		(end 23.175976 -302.242474)
		(width 0.1651)
		(layer "In5.Cu")
		(net "PE_TX2_DR2_P")
	)
	(segment
		(start 14.669516 -307.827172)
		(end 12.98448 -317.384684)
		(width 0.1651)
		(layer "In5.Cu")
		(net "PE_TX2_DR2_P")
	)
	(segment
		(start 67.31254 -288.655506)
		(end 45.507656 -303.923446)
		(width 0.1651)
		(layer "In5.Cu")
		(net "PE_TX2_DR2_P")
	)
	(segment
		(start 45.507656 -303.923446)
		(end 39.10965 -305.051968)
		(width 0.1651)
		(layer "In5.Cu")
		(net "PE_TX2_DR2_P")
	)
	(segment
		(start 184.770522 -267.94714)
		(end 67.31254 -288.655506)
		(width 0.1651)
		(layer "In5.Cu")
		(net "PE_TX2_DR2_P")
	)
	(segment
		(start 16.068802 -305.829716)
		(end 14.669516 -307.827172)
		(width 0.1651)
		(layer "In5.Cu")
		(net "PE_TX2_DR2_P")
	)
	(segment
		(start 10.49528 -320.93916)
		(end 8.423148 -322.389754)
		(width 0.1651)
		(layer "In5.Cu")
		(net "PE_TX2_DR2_P")
	)
	(segment
		(start 222.885 -273.637502)
		(end 220.58376 -273.637502)
		(width 0.174752)
		(layer "F.Cu")
		(net "PE_TX2_DR2_N")
	)
	(segment
		(start 220.58376 -273.637502)
		(end 220.330014 -273.383756)
		(width 0.174752)
		(layer "F.Cu")
		(net "PE_TX2_DR2_N")
	)
	(segment
		(start 3.905504 -322.189348)
		(end 6.738874 -322.189348)
		(width 0.174752)
		(layer "F.Cu")
		(net "PE_TX2_DR2_N")
	)
	(segment
		(start 2.249932 -321.942206)
		(end 3.658362 -321.942206)
		(width 0.174752)
		(layer "F.Cu")
		(net "PE_TX2_DR2_N")
	)
	(segment
		(start 6.738874 -322.189348)
		(end 6.992366 -321.935856)
		(width 0.174752)
		(layer "F.Cu")
		(net "PE_TX2_DR2_N")
	)
	(segment
		(start 3.658362 -321.942206)
		(end 3.905504 -322.189348)
		(width 0.174752)
		(layer "F.Cu")
		(net "PE_TX2_DR2_N")
	)
	(segment
		(start 224.199958 -273.390106)
		(end 223.132396 -273.390106)
		(width 0.174752)
		(layer "F.Cu")
		(net "PE_TX2_DR2_N")
	)
	(segment
		(start 223.132396 -273.390106)
		(end 222.885 -273.637502)
		(width 0.174752)
		(layer "F.Cu")
		(net "PE_TX2_DR2_N")
	)
	(via
		(at 220.330014 -273.383756)
		(size 0.508)
		(drill 0.254)
		(layers "F.Cu" "B.Cu")
		(net "PE_TX2_DR2_N")
	)
	(via
		(at 6.992366 -321.935856)
		(size 0.508)
		(drill 0.254)
		(layers "F.Cu" "B.Cu")
		(net "PE_TX2_DR2_N")
	)
	(segment
		(start 220.101414 -273.612356)
		(end 218.948 -273.612356)
		(width 0.1651)
		(layer "In5.Cu")
		(net "PE_TX2_DR2_N")
	)
	(segment
		(start 12.64793 -317.245238)
		(end 10.24001 -320.683382)
		(width 0.1651)
		(layer "In5.Cu")
		(net "PE_TX2_DR2_N")
	)
	(segment
		(start 67.173094 -288.318956)
		(end 45.36821 -303.586896)
		(width 0.1651)
		(layer "In5.Cu")
		(net "PE_TX2_DR2_N")
	)
	(segment
		(start 39.10965 -304.69078)
		(end 23.175976 -301.881286)
		(width 0.1651)
		(layer "In5.Cu")
		(net "PE_TX2_DR2_N")
	)
	(segment
		(start 20.384008 -302.373792)
		(end 15.813278 -305.574192)
		(width 0.1651)
		(layer "In5.Cu")
		(net "PE_TX2_DR2_N")
	)
	(segment
		(start 10.24001 -320.683382)
		(end 8.283702 -322.053204)
		(width 0.1651)
		(layer "In5.Cu")
		(net "PE_TX2_DR2_N")
	)
	(segment
		(start 7.651242 -322.164456)
		(end 7.220966 -322.164456)
		(width 0.1651)
		(layer "In5.Cu")
		(net "PE_TX2_DR2_N")
	)
	(segment
		(start 8.283702 -322.053204)
		(end 7.651242 -322.164456)
		(width 0.1651)
		(layer "In5.Cu")
		(net "PE_TX2_DR2_N")
	)
	(segment
		(start 15.813278 -305.574192)
		(end 14.332966 -307.687726)
		(width 0.1651)
		(layer "In5.Cu")
		(net "PE_TX2_DR2_N")
	)
	(segment
		(start 23.175976 -301.881286)
		(end 20.384008 -302.373792)
		(width 0.1651)
		(layer "In5.Cu")
		(net "PE_TX2_DR2_N")
	)
	(segment
		(start 220.330014 -273.383756)
		(end 220.101414 -273.612356)
		(width 0.1651)
		(layer "In5.Cu")
		(net "PE_TX2_DR2_N")
	)
	(segment
		(start 14.332966 -307.687726)
		(end 12.64793 -317.245238)
		(width 0.1651)
		(layer "In5.Cu")
		(net "PE_TX2_DR2_N")
	)
	(segment
		(start 184.770522 -267.585952)
		(end 67.173094 -288.318956)
		(width 0.1651)
		(layer "In5.Cu")
		(net "PE_TX2_DR2_N")
	)
	(segment
		(start 7.220966 -322.164456)
		(end 6.992366 -321.935856)
		(width 0.1651)
		(layer "In5.Cu")
		(net "PE_TX2_DR2_N")
	)
	(segment
		(start 45.36821 -303.586896)
		(end 39.10965 -304.69078)
		(width 0.1651)
		(layer "In5.Cu")
		(net "PE_TX2_DR2_N")
	)
	(segment
		(start 218.948 -273.612356)
		(end 184.770522 -267.585952)
		(width 0.1651)
		(layer "In5.Cu")
		(net "PE_TX2_DR2_N")
	)
	(segment
		(start 23.876 -25.809956)
		(end 24.123396 -26.057352)
		(width 0.174752)
		(layer "F.Cu")
		(net "PE_TX2_DR14_P")
	)
	(segment
		(start 22.800056 -25.809956)
		(end 23.876 -25.809956)
		(width 0.174752)
		(layer "F.Cu")
		(net "PE_TX2_DR14_P")
	)
	(segment
		(start 3.905504 -156.53258)
		(end 6.738112 -156.53258)
		(width 0.174752)
		(layer "F.Cu")
		(net "PE_TX2_DR14_P")
	)
	(segment
		(start 6.738112 -156.53258)
		(end 6.992366 -156.786834)
		(width 0.174752)
		(layer "F.Cu")
		(net "PE_TX2_DR14_P")
	)
	(segment
		(start 26.416 -26.057352)
		(end 26.67 -25.803352)
		(width 0.174752)
		(layer "F.Cu")
		(net "PE_TX2_DR14_P")
	)
	(segment
		(start 24.123396 -26.057352)
		(end 26.416 -26.057352)
		(width 0.174752)
		(layer "F.Cu")
		(net "PE_TX2_DR14_P")
	)
	(segment
		(start 2.249932 -156.74213)
		(end 3.695954 -156.74213)
		(width 0.174752)
		(layer "F.Cu")
		(net "PE_TX2_DR14_P")
	)
	(segment
		(start 3.695954 -156.74213)
		(end 3.905504 -156.53258)
		(width 0.174752)
		(layer "F.Cu")
		(net "PE_TX2_DR14_P")
	)
	(via
		(at 6.992366 -156.786834)
		(size 0.508)
		(drill 0.254)
		(layers "F.Cu" "B.Cu")
		(net "PE_TX2_DR14_P")
	)
	(via
		(at 26.67 -25.803352)
		(size 0.508)
		(drill 0.254)
		(layers "F.Cu" "B.Cu")
		(net "PE_TX2_DR14_P")
	)
	(segment
		(start 11.763756 -87.270082)
		(end 8.160258 -107.691428)
		(width 0.1651)
		(layer "In5.Cu")
		(net "PE_TX2_DR14_P")
	)
	(segment
		(start 13.96111 -140.58011)
		(end 11.882374 -152.372568)
		(width 0.1651)
		(layer "In5.Cu")
		(net "PE_TX2_DR14_P")
	)
	(segment
		(start 28.083256 -26.031952)
		(end 29.71038 -26.318718)
		(width 0.1651)
		(layer "In5.Cu")
		(net "PE_TX2_DR14_P")
	)
	(segment
		(start 26.67 -25.803352)
		(end 26.8986 -26.031952)
		(width 0.1651)
		(layer "In5.Cu")
		(net "PE_TX2_DR14_P")
	)
	(segment
		(start 9.371076 -155.958794)
		(end 8.794496 -156.362654)
		(width 0.1651)
		(layer "In5.Cu")
		(net "PE_TX2_DR14_P")
	)
	(segment
		(start 32.867092 -30.57017)
		(end 33.13938 -32.114236)
		(width 0.1651)
		(layer "In5.Cu")
		(net "PE_TX2_DR14_P")
	)
	(segment
		(start 27.330908 -65.04305)
		(end 11.763756 -87.270082)
		(width 0.1651)
		(layer "In5.Cu")
		(net "PE_TX2_DR14_P")
	)
	(segment
		(start 8.160258 -107.691428)
		(end 13.96111 -140.58011)
		(width 0.1651)
		(layer "In5.Cu")
		(net "PE_TX2_DR14_P")
	)
	(segment
		(start 29.71038 -26.318718)
		(end 30.0609 -26.564082)
		(width 0.1651)
		(layer "In5.Cu")
		(net "PE_TX2_DR14_P")
	)
	(segment
		(start 26.8986 -26.031952)
		(end 28.083256 -26.031952)
		(width 0.1651)
		(layer "In5.Cu")
		(net "PE_TX2_DR14_P")
	)
	(segment
		(start 33.13938 -32.114236)
		(end 27.330908 -65.04305)
		(width 0.1651)
		(layer "In5.Cu")
		(net "PE_TX2_DR14_P")
	)
	(segment
		(start 11.882374 -152.372568)
		(end 9.371076 -155.958794)
		(width 0.1651)
		(layer "In5.Cu")
		(net "PE_TX2_DR14_P")
	)
	(segment
		(start 7.220966 -156.558234)
		(end 6.992366 -156.786834)
		(width 0.1651)
		(layer "In5.Cu")
		(net "PE_TX2_DR14_P")
	)
	(segment
		(start 30.0609 -26.564082)
		(end 32.867092 -30.57017)
		(width 0.1651)
		(layer "In5.Cu")
		(net "PE_TX2_DR14_P")
	)
	(segment
		(start 8.794496 -156.362654)
		(end 7.682484 -156.558234)
		(width 0.1651)
		(layer "In5.Cu")
		(net "PE_TX2_DR14_P")
	)
	(segment
		(start 7.682484 -156.558234)
		(end 7.220966 -156.558234)
		(width 0.1651)
		(layer "In5.Cu")
		(net "PE_TX2_DR14_P")
	)
	(segment
		(start 26.416254 -26.362406)
		(end 26.67 -26.616152)
		(width 0.174752)
		(layer "F.Cu")
		(net "PE_TX2_DR14_N")
	)
	(segment
		(start 23.882604 -26.609802)
		(end 24.13 -26.362406)
		(width 0.174752)
		(layer "F.Cu")
		(net "PE_TX2_DR14_N")
	)
	(segment
		(start 24.13 -26.362406)
		(end 26.416254 -26.362406)
		(width 0.174752)
		(layer "F.Cu")
		(net "PE_TX2_DR14_N")
	)
	(segment
		(start 3.905504 -156.227526)
		(end 6.738874 -156.227526)
		(width 0.174752)
		(layer "F.Cu")
		(net "PE_TX2_DR14_N")
	)
	(segment
		(start 22.800056 -26.609802)
		(end 23.882604 -26.609802)
		(width 0.174752)
		(layer "F.Cu")
		(net "PE_TX2_DR14_N")
	)
	(segment
		(start 2.249932 -155.94203)
		(end 3.620008 -155.94203)
		(width 0.174752)
		(layer "F.Cu")
		(net "PE_TX2_DR14_N")
	)
	(segment
		(start 6.738874 -156.227526)
		(end 6.992366 -155.974034)
		(width 0.174752)
		(layer "F.Cu")
		(net "PE_TX2_DR14_N")
	)
	(segment
		(start 3.620008 -155.94203)
		(end 3.905504 -156.227526)
		(width 0.174752)
		(layer "F.Cu")
		(net "PE_TX2_DR14_N")
	)
	(via
		(at 6.992366 -155.974034)
		(size 0.508)
		(drill 0.254)
		(layers "F.Cu" "B.Cu")
		(net "PE_TX2_DR14_N")
	)
	(via
		(at 26.67 -26.616152)
		(size 0.508)
		(drill 0.254)
		(layers "F.Cu" "B.Cu")
		(net "PE_TX2_DR14_N")
	)
	(segment
		(start 26.994358 -64.903604)
		(end 11.427206 -87.130636)
		(width 0.1651)
		(layer "In5.Cu")
		(net "PE_TX2_DR14_N")
	)
	(segment
		(start 32.778192 -32.11449)
		(end 26.994358 -64.903604)
		(width 0.1651)
		(layer "In5.Cu")
		(net "PE_TX2_DR14_N")
	)
	(segment
		(start 10.42162 -153.510742)
		(end 10.137394 -153.91638)
		(width 0.1651)
		(layer "In5.Cu")
		(net "PE_TX2_DR14_N")
	)
	(segment
		(start 30.962346 -28.471114)
		(end 30.916372 -28.732988)
		(width 0.1651)
		(layer "In5.Cu")
		(net "PE_TX2_DR14_N")
	)
	(segment
		(start 7.220966 -156.202634)
		(end 6.992366 -155.974034)
		(width 0.1651)
		(layer "In5.Cu")
		(net "PE_TX2_DR14_N")
	)
	(segment
		(start 9.899396 -154.583892)
		(end 9.637776 -154.63012)
		(width 0.1651)
		(layer "In5.Cu")
		(net "PE_TX2_DR14_N")
	)
	(segment
		(start 13.599922 -140.58011)
		(end 13.323062 -142.150338)
		(width 0.1651)
		(layer "In5.Cu")
		(net "PE_TX2_DR14_N")
	)
	(segment
		(start 7.79907 -107.691428)
		(end 13.599922 -140.58011)
		(width 0.1651)
		(layer "In5.Cu")
		(net "PE_TX2_DR14_N")
	)
	(segment
		(start 10.68324 -153.464514)
		(end 10.42162 -153.510742)
		(width 0.1651)
		(layer "In5.Cu")
		(net "PE_TX2_DR14_N")
	)
	(segment
		(start 30.916372 -28.732988)
		(end 31.200598 -29.138626)
		(width 0.1651)
		(layer "In5.Cu")
		(net "PE_TX2_DR14_N")
	)
	(segment
		(start 30.178248 -27.35199)
		(end 30.132274 -27.613864)
		(width 0.1651)
		(layer "In5.Cu")
		(net "PE_TX2_DR14_N")
	)
	(segment
		(start 12.868148 -143.64843)
		(end 12.782296 -144.13611)
		(width 0.1651)
		(layer "In5.Cu")
		(net "PE_TX2_DR14_N")
	)
	(segment
		(start 31.200598 -29.138626)
		(end 31.462218 -29.184854)
		(width 0.1651)
		(layer "In5.Cu")
		(net "PE_TX2_DR14_N")
	)
	(segment
		(start 8.65505 -156.02585)
		(end 7.651242 -156.202634)
		(width 0.1651)
		(layer "In5.Cu")
		(net "PE_TX2_DR14_N")
	)
	(segment
		(start 9.35355 -155.035758)
		(end 9.399778 -155.297632)
		(width 0.1651)
		(layer "In5.Cu")
		(net "PE_TX2_DR14_N")
	)
	(segment
		(start 9.115552 -155.70327)
		(end 8.65505 -156.02585)
		(width 0.1651)
		(layer "In5.Cu")
		(net "PE_TX2_DR14_N")
	)
	(segment
		(start 13.105384 -142.302738)
		(end 13.019278 -142.790418)
		(width 0.1651)
		(layer "In5.Cu")
		(net "PE_TX2_DR14_N")
	)
	(segment
		(start 10.183622 -154.178254)
		(end 9.899396 -154.583892)
		(width 0.1651)
		(layer "In5.Cu")
		(net "PE_TX2_DR14_N")
	)
	(segment
		(start 32.530542 -30.709616)
		(end 32.778192 -32.11449)
		(width 0.1651)
		(layer "In5.Cu")
		(net "PE_TX2_DR14_N")
	)
	(segment
		(start 31.984696 -30.25775)
		(end 32.246316 -30.303978)
		(width 0.1651)
		(layer "In5.Cu")
		(net "PE_TX2_DR14_N")
	)
	(segment
		(start 30.132274 -27.613864)
		(end 30.4165 -28.019502)
		(width 0.1651)
		(layer "In5.Cu")
		(net "PE_TX2_DR14_N")
	)
	(segment
		(start 26.8986 -26.387552)
		(end 28.052014 -26.387552)
		(width 0.1651)
		(layer "In5.Cu")
		(net "PE_TX2_DR14_N")
	)
	(segment
		(start 28.052014 -26.387552)
		(end 29.570934 -26.655268)
		(width 0.1651)
		(layer "In5.Cu")
		(net "PE_TX2_DR14_N")
	)
	(segment
		(start 26.67 -26.616152)
		(end 26.8986 -26.387552)
		(width 0.1651)
		(layer "In5.Cu")
		(net "PE_TX2_DR14_N")
	)
	(segment
		(start 10.137394 -153.91638)
		(end 10.183622 -154.178254)
		(width 0.1651)
		(layer "In5.Cu")
		(net "PE_TX2_DR14_N")
	)
	(segment
		(start 12.934696 -144.354042)
		(end 11.545824 -152.233122)
		(width 0.1651)
		(layer "In5.Cu")
		(net "PE_TX2_DR14_N")
	)
	(segment
		(start 29.570934 -26.655268)
		(end 29.805376 -26.819606)
		(width 0.1651)
		(layer "In5.Cu")
		(net "PE_TX2_DR14_N")
	)
	(segment
		(start 13.019278 -142.790418)
		(end 13.171932 -143.00835)
		(width 0.1651)
		(layer "In5.Cu")
		(net "PE_TX2_DR14_N")
	)
	(segment
		(start 31.746444 -29.590492)
		(end 31.70047 -29.852112)
		(width 0.1651)
		(layer "In5.Cu")
		(net "PE_TX2_DR14_N")
	)
	(segment
		(start 9.399778 -155.297632)
		(end 9.115552 -155.70327)
		(width 0.1651)
		(layer "In5.Cu")
		(net "PE_TX2_DR14_N")
	)
	(segment
		(start 12.782296 -144.13611)
		(end 12.934696 -144.354042)
		(width 0.1651)
		(layer "In5.Cu")
		(net "PE_TX2_DR14_N")
	)
	(segment
		(start 13.323062 -142.150338)
		(end 13.105384 -142.302738)
		(width 0.1651)
		(layer "In5.Cu")
		(net "PE_TX2_DR14_N")
	)
	(segment
		(start 29.805376 -26.819606)
		(end 30.178248 -27.35199)
		(width 0.1651)
		(layer "In5.Cu")
		(net "PE_TX2_DR14_N")
	)
	(segment
		(start 31.70047 -29.852112)
		(end 31.984696 -30.25775)
		(width 0.1651)
		(layer "In5.Cu")
		(net "PE_TX2_DR14_N")
	)
	(segment
		(start 13.085826 -143.49603)
		(end 12.868148 -143.64843)
		(width 0.1651)
		(layer "In5.Cu")
		(net "PE_TX2_DR14_N")
	)
	(segment
		(start 9.637776 -154.63012)
		(end 9.35355 -155.035758)
		(width 0.1651)
		(layer "In5.Cu")
		(net "PE_TX2_DR14_N")
	)
	(segment
		(start 11.545824 -152.233122)
		(end 10.68324 -153.464514)
		(width 0.1651)
		(layer "In5.Cu")
		(net "PE_TX2_DR14_N")
	)
	(segment
		(start 31.462218 -29.184854)
		(end 31.746444 -29.590492)
		(width 0.1651)
		(layer "In5.Cu")
		(net "PE_TX2_DR14_N")
	)
	(segment
		(start 13.171932 -143.00835)
		(end 13.085826 -143.49603)
		(width 0.1651)
		(layer "In5.Cu")
		(net "PE_TX2_DR14_N")
	)
	(segment
		(start 30.4165 -28.019502)
		(end 30.67812 -28.065476)
		(width 0.1651)
		(layer "In5.Cu")
		(net "PE_TX2_DR14_N")
	)
	(segment
		(start 30.67812 -28.065476)
		(end 30.962346 -28.471114)
		(width 0.1651)
		(layer "In5.Cu")
		(net "PE_TX2_DR14_N")
	)
	(segment
		(start 11.427206 -87.130636)
		(end 7.79907 -107.691428)
		(width 0.1651)
		(layer "In5.Cu")
		(net "PE_TX2_DR14_N")
	)
	(segment
		(start 7.651242 -156.202634)
		(end 7.220966 -156.202634)
		(width 0.1651)
		(layer "In5.Cu")
		(net "PE_TX2_DR14_N")
	)
	(segment
		(start 32.246316 -30.303978)
		(end 32.530542 -30.709616)
		(width 0.1651)
		(layer "In5.Cu")
		(net "PE_TX2_DR14_N")
	)
	(segment
		(start 2.249932 -172.742098)
		(end 3.6576 -172.742098)
		(width 0.174752)
		(layer "F.Cu")
		(net "PE_TX2_DR13_P")
	)
	(segment
		(start 23.876 -128.810004)
		(end 24.123396 -129.0574)
		(width 0.174752)
		(layer "F.Cu")
		(net "PE_TX2_DR13_P")
	)
	(segment
		(start 22.800056 -128.810004)
		(end 23.876 -128.810004)
		(width 0.174752)
		(layer "F.Cu")
		(net "PE_TX2_DR13_P")
	)
	(segment
		(start 3.6576 -172.742098)
		(end 3.85445 -172.545248)
		(width 0.174752)
		(layer "F.Cu")
		(net "PE_TX2_DR13_P")
	)
	(segment
		(start 24.123396 -129.0574)
		(end 26.416 -129.0574)
		(width 0.174752)
		(layer "F.Cu")
		(net "PE_TX2_DR13_P")
	)
	(segment
		(start 26.416 -129.0574)
		(end 26.67 -128.8034)
		(width 0.174752)
		(layer "F.Cu")
		(net "PE_TX2_DR13_P")
	)
	(segment
		(start 3.85445 -172.545248)
		(end 6.738112 -172.545248)
		(width 0.174752)
		(layer "F.Cu")
		(net "PE_TX2_DR13_P")
	)
	(segment
		(start 6.738112 -172.545248)
		(end 6.992366 -172.799502)
		(width 0.174752)
		(layer "F.Cu")
		(net "PE_TX2_DR13_P")
	)
	(via
		(at 6.992366 -172.799502)
		(size 0.508)
		(drill 0.254)
		(layers "F.Cu" "B.Cu")
		(net "PE_TX2_DR13_P")
	)
	(via
		(at 26.67 -128.8034)
		(size 0.508)
		(drill 0.254)
		(layers "F.Cu" "B.Cu")
		(net "PE_TX2_DR13_P")
	)
	(segment
		(start 19.976338 -170.347386)
		(end 7.362952 -172.570902)
		(width 0.1651)
		(layer "In5.Cu")
		(net "PE_TX2_DR13_P")
	)
	(segment
		(start 29.66974 -145.25371)
		(end 27.487372 -148.37029)
		(width 0.1651)
		(layer "In5.Cu")
		(net "PE_TX2_DR13_P")
	)
	(segment
		(start 28.083256 -129.032)
		(end 28.521914 -129.109216)
		(width 0.1651)
		(layer "In5.Cu")
		(net "PE_TX2_DR13_P")
	)
	(segment
		(start 29.527246 -130.036316)
		(end 29.8704 -131.98221)
		(width 0.1651)
		(layer "In5.Cu")
		(net "PE_TX2_DR13_P")
	)
	(segment
		(start 30.492954 -140.575284)
		(end 29.66974 -145.25371)
		(width 0.1651)
		(layer "In5.Cu")
		(net "PE_TX2_DR13_P")
	)
	(segment
		(start 29.220668 -129.598166)
		(end 29.527246 -130.036316)
		(width 0.1651)
		(layer "In5.Cu")
		(net "PE_TX2_DR13_P")
	)
	(segment
		(start 26.67 -128.8034)
		(end 26.8986 -129.032)
		(width 0.1651)
		(layer "In5.Cu")
		(net "PE_TX2_DR13_P")
	)
	(segment
		(start 24.291036 -166.471092)
		(end 23.115524 -168.149524)
		(width 0.1651)
		(layer "In5.Cu")
		(net "PE_TX2_DR13_P")
	)
	(segment
		(start 24.312372 -166.367714)
		(end 24.309832 -166.386256)
		(width 0.1651)
		(layer "In5.Cu")
		(net "PE_TX2_DR13_P")
	)
	(segment
		(start 29.867606 -132.881878)
		(end 29.5021 -134.954518)
		(width 0.1651)
		(layer "In5.Cu")
		(net "PE_TX2_DR13_P")
	)
	(segment
		(start 24.309832 -166.386256)
		(end 24.291036 -166.471092)
		(width 0.1651)
		(layer "In5.Cu")
		(net "PE_TX2_DR13_P")
	)
	(segment
		(start 7.362952 -172.570902)
		(end 7.220966 -172.570902)
		(width 0.1651)
		(layer "In5.Cu")
		(net "PE_TX2_DR13_P")
	)
	(segment
		(start 29.867606 -131.982718)
		(end 29.867606 -132.881878)
		(width 0.1651)
		(layer "In5.Cu")
		(net "PE_TX2_DR13_P")
	)
	(segment
		(start 26.8986 -129.032)
		(end 28.083256 -129.032)
		(width 0.1651)
		(layer "In5.Cu")
		(net "PE_TX2_DR13_P")
	)
	(segment
		(start 27.487372 -148.37029)
		(end 24.312372 -166.367714)
		(width 0.1651)
		(layer "In5.Cu")
		(net "PE_TX2_DR13_P")
	)
	(segment
		(start 29.5021 -134.954518)
		(end 30.492954 -140.575284)
		(width 0.1651)
		(layer "In5.Cu")
		(net "PE_TX2_DR13_P")
	)
	(segment
		(start 7.220966 -172.570902)
		(end 6.992366 -172.799502)
		(width 0.1651)
		(layer "In5.Cu")
		(net "PE_TX2_DR13_P")
	)
	(segment
		(start 29.8704 -131.98221)
		(end 29.867606 -131.982718)
		(width 0.1651)
		(layer "In5.Cu")
		(net "PE_TX2_DR13_P")
	)
	(segment
		(start 23.115524 -168.149524)
		(end 19.976338 -170.347386)
		(width 0.1651)
		(layer "In5.Cu")
		(net "PE_TX2_DR13_P")
	)
	(segment
		(start 28.521914 -129.109216)
		(end 29.220668 -129.598166)
		(width 0.1651)
		(layer "In5.Cu")
		(net "PE_TX2_DR13_P")
	)
	(segment
		(start 23.882604 -129.60985)
		(end 24.13 -129.362454)
		(width 0.174752)
		(layer "F.Cu")
		(net "PE_TX2_DR13_N")
	)
	(segment
		(start 6.738874 -172.240194)
		(end 6.992366 -171.986702)
		(width 0.174752)
		(layer "F.Cu")
		(net "PE_TX2_DR13_N")
	)
	(segment
		(start 2.249932 -171.941998)
		(end 3.657854 -171.941998)
		(width 0.174752)
		(layer "F.Cu")
		(net "PE_TX2_DR13_N")
	)
	(segment
		(start 26.416254 -129.362454)
		(end 26.67 -129.6162)
		(width 0.174752)
		(layer "F.Cu")
		(net "PE_TX2_DR13_N")
	)
	(segment
		(start 3.657854 -171.941998)
		(end 3.95605 -172.240194)
		(width 0.174752)
		(layer "F.Cu")
		(net "PE_TX2_DR13_N")
	)
	(segment
		(start 24.13 -129.362454)
		(end 26.416254 -129.362454)
		(width 0.174752)
		(layer "F.Cu")
		(net "PE_TX2_DR13_N")
	)
	(segment
		(start 22.800056 -129.60985)
		(end 23.882604 -129.60985)
		(width 0.174752)
		(layer "F.Cu")
		(net "PE_TX2_DR13_N")
	)
	(segment
		(start 3.95605 -172.240194)
		(end 6.738874 -172.240194)
		(width 0.174752)
		(layer "F.Cu")
		(net "PE_TX2_DR13_N")
	)
	(via
		(at 26.67 -129.6162)
		(size 0.508)
		(drill 0.254)
		(layers "F.Cu" "B.Cu")
		(net "PE_TX2_DR13_N")
	)
	(via
		(at 6.992366 -171.986702)
		(size 0.508)
		(drill 0.254)
		(layers "F.Cu" "B.Cu")
		(net "PE_TX2_DR13_N")
	)
	(segment
		(start 10.663428 -171.437046)
		(end 10.511028 -171.654724)
		(width 0.1651)
		(layer "In5.Cu")
		(net "PE_TX2_DR13_N")
	)
	(segment
		(start 29.512006 -131.998212)
		(end 29.512006 -132.850636)
		(width 0.1651)
		(layer "In5.Cu")
		(net "PE_TX2_DR13_N")
	)
	(segment
		(start 11.151362 -171.351194)
		(end 10.663428 -171.437046)
		(width 0.1651)
		(layer "In5.Cu")
		(net "PE_TX2_DR13_N")
	)
	(segment
		(start 29.613098 -137.632948)
		(end 29.460444 -137.850626)
		(width 0.1651)
		(layer "In5.Cu")
		(net "PE_TX2_DR13_N")
	)
	(segment
		(start 17.229836 -170.470322)
		(end 17.012158 -170.317922)
		(width 0.1651)
		(layer "In5.Cu")
		(net "PE_TX2_DR13_N")
	)
	(segment
		(start 22.86 -167.894)
		(end 19.836892 -170.010836)
		(width 0.1651)
		(layer "In5.Cu")
		(net "PE_TX2_DR13_N")
	)
	(segment
		(start 17.012158 -170.317922)
		(end 16.524224 -170.403774)
		(width 0.1651)
		(layer "In5.Cu")
		(net "PE_TX2_DR13_N")
	)
	(segment
		(start 16.524224 -170.403774)
		(end 16.371824 -170.621706)
		(width 0.1651)
		(layer "In5.Cu")
		(net "PE_TX2_DR13_N")
	)
	(segment
		(start 23.960074 -166.318946)
		(end 23.959566 -166.322502)
		(width 0.1651)
		(layer "In5.Cu")
		(net "PE_TX2_DR13_N")
	)
	(segment
		(start 7.33171 -172.215302)
		(end 7.220966 -172.215302)
		(width 0.1651)
		(layer "In5.Cu")
		(net "PE_TX2_DR13_N")
	)
	(segment
		(start 7.972044 -171.911518)
		(end 7.81939 -172.129196)
		(width 0.1651)
		(layer "In5.Cu")
		(net "PE_TX2_DR13_N")
	)
	(segment
		(start 27.150822 -148.230844)
		(end 23.960836 -166.312596)
		(width 0.1651)
		(layer "In5.Cu")
		(net "PE_TX2_DR13_N")
	)
	(segment
		(start 23.960582 -166.313104)
		(end 23.96109 -166.313104)
		(width 0.1651)
		(layer "In5.Cu")
		(net "PE_TX2_DR13_N")
	)
	(segment
		(start 23.96109 -166.313104)
		(end 23.960074 -166.318946)
		(width 0.1651)
		(layer "In5.Cu")
		(net "PE_TX2_DR13_N")
	)
	(segment
		(start 29.223462 -136.504934)
		(end 29.309314 -136.992614)
		(width 0.1651)
		(layer "In5.Cu")
		(net "PE_TX2_DR13_N")
	)
	(segment
		(start 17.87017 -170.166538)
		(end 17.717516 -170.38447)
		(width 0.1651)
		(layer "In5.Cu")
		(net "PE_TX2_DR13_N")
	)
	(segment
		(start 29.309314 -136.992614)
		(end 29.526992 -137.145268)
		(width 0.1651)
		(layer "In5.Cu")
		(net "PE_TX2_DR13_N")
	)
	(segment
		(start 10.023348 -171.74083)
		(end 9.805416 -171.58843)
		(width 0.1651)
		(layer "In5.Cu")
		(net "PE_TX2_DR13_N")
	)
	(segment
		(start 29.375862 -136.287256)
		(end 29.223462 -136.504934)
		(width 0.1651)
		(layer "In5.Cu")
		(net "PE_TX2_DR13_N")
	)
	(segment
		(start 17.717516 -170.38447)
		(end 17.229836 -170.470322)
		(width 0.1651)
		(layer "In5.Cu")
		(net "PE_TX2_DR13_N")
	)
	(segment
		(start 29.33319 -145.114264)
		(end 27.150822 -148.230844)
		(width 0.1651)
		(layer "In5.Cu")
		(net "PE_TX2_DR13_N")
	)
	(segment
		(start 29.460444 -137.850626)
		(end 29.54655 -138.338306)
		(width 0.1651)
		(layer "In5.Cu")
		(net "PE_TX2_DR13_N")
	)
	(segment
		(start 29.764228 -138.490706)
		(end 30.131766 -140.575284)
		(width 0.1651)
		(layer "In5.Cu")
		(net "PE_TX2_DR13_N")
	)
	(segment
		(start 18.575528 -170.233086)
		(end 18.35785 -170.080686)
		(width 0.1651)
		(layer "In5.Cu")
		(net "PE_TX2_DR13_N")
	)
	(segment
		(start 19.836892 -170.010836)
		(end 18.575528 -170.233086)
		(width 0.1651)
		(layer "In5.Cu")
		(net "PE_TX2_DR13_N")
	)
	(segment
		(start 10.511028 -171.654724)
		(end 10.023348 -171.74083)
		(width 0.1651)
		(layer "In5.Cu")
		(net "PE_TX2_DR13_N")
	)
	(segment
		(start 11.36904 -171.503594)
		(end 11.151362 -171.351194)
		(width 0.1651)
		(layer "In5.Cu")
		(net "PE_TX2_DR13_N")
	)
	(segment
		(start 26.8986 -129.3876)
		(end 28.052014 -129.3876)
		(width 0.1651)
		(layer "In5.Cu")
		(net "PE_TX2_DR13_N")
	)
	(segment
		(start 8.677402 -171.978066)
		(end 8.459724 -171.825666)
		(width 0.1651)
		(layer "In5.Cu")
		(net "PE_TX2_DR13_N")
	)
	(segment
		(start 7.81939 -172.129196)
		(end 7.33171 -172.215302)
		(width 0.1651)
		(layer "In5.Cu")
		(net "PE_TX2_DR13_N")
	)
	(segment
		(start 28.052014 -129.3876)
		(end 28.382468 -129.445766)
		(width 0.1651)
		(layer "In5.Cu")
		(net "PE_TX2_DR13_N")
	)
	(segment
		(start 9.317736 -171.674282)
		(end 9.165336 -171.89196)
		(width 0.1651)
		(layer "In5.Cu")
		(net "PE_TX2_DR13_N")
	)
	(segment
		(start 28.965144 -129.85369)
		(end 29.190696 -130.175762)
		(width 0.1651)
		(layer "In5.Cu")
		(net "PE_TX2_DR13_N")
	)
	(segment
		(start 7.220966 -172.215302)
		(end 6.992366 -171.986702)
		(width 0.1651)
		(layer "In5.Cu")
		(net "PE_TX2_DR13_N")
	)
	(segment
		(start 9.165336 -171.89196)
		(end 8.677402 -171.978066)
		(width 0.1651)
		(layer "In5.Cu")
		(net "PE_TX2_DR13_N")
	)
	(segment
		(start 29.54655 -138.338306)
		(end 29.764228 -138.490706)
		(width 0.1651)
		(layer "In5.Cu")
		(net "PE_TX2_DR13_N")
	)
	(segment
		(start 9.805416 -171.58843)
		(end 9.317736 -171.674282)
		(width 0.1651)
		(layer "In5.Cu")
		(net "PE_TX2_DR13_N")
	)
	(segment
		(start 26.67 -129.6162)
		(end 26.8986 -129.3876)
		(width 0.1651)
		(layer "In5.Cu")
		(net "PE_TX2_DR13_N")
	)
	(segment
		(start 30.131766 -140.575284)
		(end 29.33319 -145.114264)
		(width 0.1651)
		(layer "In5.Cu")
		(net "PE_TX2_DR13_N")
	)
	(segment
		(start 28.382468 -129.445766)
		(end 28.965144 -129.85369)
		(width 0.1651)
		(layer "In5.Cu")
		(net "PE_TX2_DR13_N")
	)
	(segment
		(start 16.371824 -170.621706)
		(end 11.36904 -171.503594)
		(width 0.1651)
		(layer "In5.Cu")
		(net "PE_TX2_DR13_N")
	)
	(segment
		(start 23.959058 -166.324788)
		(end 22.86 -167.894)
		(width 0.1651)
		(layer "In5.Cu")
		(net "PE_TX2_DR13_N")
	)
	(segment
		(start 29.190696 -130.175762)
		(end 29.512006 -131.998212)
		(width 0.1651)
		(layer "In5.Cu")
		(net "PE_TX2_DR13_N")
	)
	(segment
		(start 29.526992 -137.145268)
		(end 29.613098 -137.632948)
		(width 0.1651)
		(layer "In5.Cu")
		(net "PE_TX2_DR13_N")
	)
	(segment
		(start 23.959566 -166.322502)
		(end 23.959058 -166.324788)
		(width 0.1651)
		(layer "In5.Cu")
		(net "PE_TX2_DR13_N")
	)
	(segment
		(start 29.512006 -132.850636)
		(end 29.140912 -134.954518)
		(width 0.1651)
		(layer "In5.Cu")
		(net "PE_TX2_DR13_N")
	)
	(segment
		(start 8.459724 -171.825666)
		(end 7.972044 -171.911518)
		(width 0.1651)
		(layer "In5.Cu")
		(net "PE_TX2_DR13_N")
	)
	(segment
		(start 23.960836 -166.312596)
		(end 23.960582 -166.313104)
		(width 0.1651)
		(layer "In5.Cu")
		(net "PE_TX2_DR13_N")
	)
	(segment
		(start 29.140912 -134.954518)
		(end 29.375862 -136.287256)
		(width 0.1651)
		(layer "In5.Cu")
		(net "PE_TX2_DR13_N")
	)
	(segment
		(start 18.35785 -170.080686)
		(end 17.87017 -170.166538)
		(width 0.1651)
		(layer "In5.Cu")
		(net "PE_TX2_DR13_N")
	)
	(segment
		(start 23.876 -231.810052)
		(end 24.123396 -232.057448)
		(width 0.174752)
		(layer "F.Cu")
		(net "PE_TX2_DR12_P")
	)
	(segment
		(start 24.123396 -232.057448)
		(end 26.416 -232.057448)
		(width 0.174752)
		(layer "F.Cu")
		(net "PE_TX2_DR12_P")
	)
	(segment
		(start 3.607054 -218.34221)
		(end 3.905504 -218.04376)
		(width 0.174752)
		(layer "F.Cu")
		(net "PE_TX2_DR12_P")
	)
	(segment
		(start 2.249932 -218.34221)
		(end 3.607054 -218.34221)
		(width 0.174752)
		(layer "F.Cu")
		(net "PE_TX2_DR12_P")
	)
	(segment
		(start 6.738112 -218.04376)
		(end 6.992366 -218.298014)
		(width 0.174752)
		(layer "F.Cu")
		(net "PE_TX2_DR12_P")
	)
	(segment
		(start 26.416 -232.057448)
		(end 26.67 -231.803448)
		(width 0.174752)
		(layer "F.Cu")
		(net "PE_TX2_DR12_P")
	)
	(segment
		(start 22.800056 -231.810052)
		(end 23.876 -231.810052)
		(width 0.174752)
		(layer "F.Cu")
		(net "PE_TX2_DR12_P")
	)
	(segment
		(start 3.905504 -218.04376)
		(end 6.738112 -218.04376)
		(width 0.174752)
		(layer "F.Cu")
		(net "PE_TX2_DR12_P")
	)
	(via
		(at 6.992366 -218.298014)
		(size 0.508)
		(drill 0.254)
		(layers "F.Cu" "B.Cu")
		(net "PE_TX2_DR12_P")
	)
	(via
		(at 26.67 -231.803448)
		(size 0.508)
		(drill 0.254)
		(layers "F.Cu" "B.Cu")
		(net "PE_TX2_DR12_P")
	)
	(segment
		(start 32.208724 -227.773484)
		(end 32.162496 -227.511864)
		(width 0.1651)
		(layer "In5.Cu")
		(net "PE_TX2_DR12_P")
	)
	(segment
		(start 20.248372 -200.47204)
		(end 20.03044 -200.31964)
		(width 0.1651)
		(layer "In5.Cu")
		(net "PE_TX2_DR12_P")
	)
	(segment
		(start 22.081998 -200.149206)
		(end 21.594064 -200.235058)
		(width 0.1651)
		(layer "In5.Cu")
		(net "PE_TX2_DR12_P")
	)
	(segment
		(start 30.641036 -230.012494)
		(end 30.595062 -229.75062)
		(width 0.1651)
		(layer "In5.Cu")
		(net "PE_TX2_DR12_P")
	)
	(segment
		(start 15.024862 -205.60792)
		(end 15.07109 -205.869794)
		(width 0.1651)
		(layer "In5.Cu")
		(net "PE_TX2_DR12_P")
	)
	(segment
		(start 39.015416 -202.30338)
		(end 23.900384 -199.638158)
		(width 0.1651)
		(layer "In5.Cu")
		(net "PE_TX2_DR12_P")
	)
	(segment
		(start 31.140908 -229.298754)
		(end 31.42488 -228.892862)
		(width 0.1651)
		(layer "In5.Cu")
		(net "PE_TX2_DR12_P")
	)
	(segment
		(start 23.900384 -199.638158)
		(end 22.234398 -199.931528)
		(width 0.1651)
		(layer "In5.Cu")
		(net "PE_TX2_DR12_P")
	)
	(segment
		(start 22.234398 -199.931528)
		(end 22.081998 -200.149206)
		(width 0.1651)
		(layer "In5.Cu")
		(net "PE_TX2_DR12_P")
	)
	(segment
		(start 32.446468 -227.105972)
		(end 32.708342 -227.059998)
		(width 0.1651)
		(layer "In5.Cu")
		(net "PE_TX2_DR12_P")
	)
	(segment
		(start 7.682484 -218.069414)
		(end 7.220966 -218.069414)
		(width 0.1651)
		(layer "In5.Cu")
		(net "PE_TX2_DR12_P")
	)
	(segment
		(start 15.854934 -204.750416)
		(end 15.570708 -205.156054)
		(width 0.1651)
		(layer "In5.Cu")
		(net "PE_TX2_DR12_P")
	)
	(segment
		(start 15.570708 -205.156054)
		(end 15.309088 -205.202282)
		(width 0.1651)
		(layer "In5.Cu")
		(net "PE_TX2_DR12_P")
	)
	(segment
		(start 26.8986 -232.032048)
		(end 28.052268 -232.032048)
		(width 0.1651)
		(layer "In5.Cu")
		(net "PE_TX2_DR12_P")
	)
	(segment
		(start 31.924498 -228.179376)
		(end 32.208724 -227.773484)
		(width 0.1651)
		(layer "In5.Cu")
		(net "PE_TX2_DR12_P")
	)
	(segment
		(start 30.879034 -229.344982)
		(end 31.140908 -229.298754)
		(width 0.1651)
		(layer "In5.Cu")
		(net "PE_TX2_DR12_P")
	)
	(segment
		(start 21.376386 -200.082658)
		(end 20.888452 -200.16851)
		(width 0.1651)
		(layer "In5.Cu")
		(net "PE_TX2_DR12_P")
	)
	(segment
		(start 7.220966 -218.069414)
		(end 6.992366 -218.298014)
		(width 0.1651)
		(layer "In5.Cu")
		(net "PE_TX2_DR12_P")
	)
	(segment
		(start 20.03044 -200.31964)
		(end 19.54276 -200.405492)
		(width 0.1651)
		(layer "In5.Cu")
		(net "PE_TX2_DR12_P")
	)
	(segment
		(start 31.662878 -228.22535)
		(end 31.924498 -228.179376)
		(width 0.1651)
		(layer "In5.Cu")
		(net "PE_TX2_DR12_P")
	)
	(segment
		(start 30.595062 -229.75062)
		(end 30.879034 -229.344982)
		(width 0.1651)
		(layer "In5.Cu")
		(net "PE_TX2_DR12_P")
	)
	(segment
		(start 19.54276 -200.405492)
		(end 17.826736 -201.606658)
		(width 0.1651)
		(layer "In5.Cu")
		(net "PE_TX2_DR12_P")
	)
	(segment
		(start 15.309088 -205.202282)
		(end 15.024862 -205.60792)
		(width 0.1651)
		(layer "In5.Cu")
		(net "PE_TX2_DR12_P")
	)
	(segment
		(start 41.973754 -204.37475)
		(end 39.015416 -202.30338)
		(width 0.1651)
		(layer "In5.Cu")
		(net "PE_TX2_DR12_P")
	)
	(segment
		(start 14.241018 -206.727298)
		(end 13.117576 -213.097364)
		(width 0.1651)
		(layer "In5.Cu")
		(net "PE_TX2_DR12_P")
	)
	(segment
		(start 32.708342 -227.059998)
		(end 43.7134 -211.341716)
		(width 0.1651)
		(layer "In5.Cu")
		(net "PE_TX2_DR12_P")
	)
	(segment
		(start 17.826736 -201.606658)
		(end 15.808706 -204.488542)
		(width 0.1651)
		(layer "In5.Cu")
		(net "PE_TX2_DR12_P")
	)
	(segment
		(start 10.434574 -216.929208)
		(end 9.18464 -217.804492)
		(width 0.1651)
		(layer "In5.Cu")
		(net "PE_TX2_DR12_P")
	)
	(segment
		(start 15.808706 -204.488542)
		(end 15.854934 -204.750416)
		(width 0.1651)
		(layer "In5.Cu")
		(net "PE_TX2_DR12_P")
	)
	(segment
		(start 32.162496 -227.511864)
		(end 32.446468 -227.105972)
		(width 0.1651)
		(layer "In5.Cu")
		(net "PE_TX2_DR12_P")
	)
	(segment
		(start 13.117576 -213.097364)
		(end 10.434574 -216.929208)
		(width 0.1651)
		(layer "In5.Cu")
		(net "PE_TX2_DR12_P")
	)
	(segment
		(start 31.42488 -228.892862)
		(end 31.378652 -228.631242)
		(width 0.1651)
		(layer "In5.Cu")
		(net "PE_TX2_DR12_P")
	)
	(segment
		(start 31.378652 -228.631242)
		(end 31.662878 -228.22535)
		(width 0.1651)
		(layer "In5.Cu")
		(net "PE_TX2_DR12_P")
	)
	(segment
		(start 28.052268 -232.032048)
		(end 30.357064 -230.418132)
		(width 0.1651)
		(layer "In5.Cu")
		(net "PE_TX2_DR12_P")
	)
	(segment
		(start 14.786864 -206.275432)
		(end 14.525244 -206.32166)
		(width 0.1651)
		(layer "In5.Cu")
		(net "PE_TX2_DR12_P")
	)
	(segment
		(start 20.888452 -200.16851)
		(end 20.736052 -200.386188)
		(width 0.1651)
		(layer "In5.Cu")
		(net "PE_TX2_DR12_P")
	)
	(segment
		(start 43.653456 -206.773272)
		(end 41.973754 -204.37475)
		(width 0.1651)
		(layer "In5.Cu")
		(net "PE_TX2_DR12_P")
	)
	(segment
		(start 15.07109 -205.869794)
		(end 14.786864 -206.275432)
		(width 0.1651)
		(layer "In5.Cu")
		(net "PE_TX2_DR12_P")
	)
	(segment
		(start 9.18464 -217.804492)
		(end 7.682484 -218.069414)
		(width 0.1651)
		(layer "In5.Cu")
		(net "PE_TX2_DR12_P")
	)
	(segment
		(start 43.7134 -211.341716)
		(end 44.086018 -209.22996)
		(width 0.1651)
		(layer "In5.Cu")
		(net "PE_TX2_DR12_P")
	)
	(segment
		(start 26.67 -231.803448)
		(end 26.8986 -232.032048)
		(width 0.1651)
		(layer "In5.Cu")
		(net "PE_TX2_DR12_P")
	)
	(segment
		(start 21.594064 -200.235058)
		(end 21.376386 -200.082658)
		(width 0.1651)
		(layer "In5.Cu")
		(net "PE_TX2_DR12_P")
	)
	(segment
		(start 44.086018 -209.22996)
		(end 43.653456 -206.773272)
		(width 0.1651)
		(layer "In5.Cu")
		(net "PE_TX2_DR12_P")
	)
	(segment
		(start 30.357064 -230.418132)
		(end 30.641036 -230.012494)
		(width 0.1651)
		(layer "In5.Cu")
		(net "PE_TX2_DR12_P")
	)
	(segment
		(start 14.525244 -206.32166)
		(end 14.241018 -206.727298)
		(width 0.1651)
		(layer "In5.Cu")
		(net "PE_TX2_DR12_P")
	)
	(segment
		(start 20.736052 -200.386188)
		(end 20.248372 -200.47204)
		(width 0.1651)
		(layer "In5.Cu")
		(net "PE_TX2_DR12_P")
	)
	(segment
		(start 2.249932 -217.54211)
		(end 3.708908 -217.54211)
		(width 0.174752)
		(layer "F.Cu")
		(net "PE_TX2_DR12_N")
	)
	(segment
		(start 23.882604 -232.609898)
		(end 24.13 -232.362502)
		(width 0.174752)
		(layer "F.Cu")
		(net "PE_TX2_DR12_N")
	)
	(segment
		(start 26.416254 -232.362502)
		(end 26.67 -232.616248)
		(width 0.174752)
		(layer "F.Cu")
		(net "PE_TX2_DR12_N")
	)
	(segment
		(start 3.905504 -217.738706)
		(end 6.738874 -217.738706)
		(width 0.174752)
		(layer "F.Cu")
		(net "PE_TX2_DR12_N")
	)
	(segment
		(start 6.738874 -217.738706)
		(end 6.992366 -217.485214)
		(width 0.174752)
		(layer "F.Cu")
		(net "PE_TX2_DR12_N")
	)
	(segment
		(start 22.800056 -232.609898)
		(end 23.882604 -232.609898)
		(width 0.174752)
		(layer "F.Cu")
		(net "PE_TX2_DR12_N")
	)
	(segment
		(start 24.13 -232.362502)
		(end 26.416254 -232.362502)
		(width 0.174752)
		(layer "F.Cu")
		(net "PE_TX2_DR12_N")
	)
	(segment
		(start 3.708908 -217.54211)
		(end 3.905504 -217.738706)
		(width 0.174752)
		(layer "F.Cu")
		(net "PE_TX2_DR12_N")
	)
	(via
		(at 26.67 -232.616248)
		(size 0.508)
		(drill 0.254)
		(layers "F.Cu" "B.Cu")
		(net "PE_TX2_DR12_N")
	)
	(via
		(at 6.992366 -217.485214)
		(size 0.508)
		(drill 0.254)
		(layers "F.Cu" "B.Cu")
		(net "PE_TX2_DR12_N")
	)
	(segment
		(start 42.229278 -204.119226)
		(end 39.154862 -201.96683)
		(width 0.1651)
		(layer "In5.Cu")
		(net "PE_TX2_DR12_N")
	)
	(segment
		(start 10.231628 -216.598754)
		(end 10.17905 -216.673938)
		(width 0.1651)
		(layer "In5.Cu")
		(net "PE_TX2_DR12_N")
	)
	(segment
		(start 44.04995 -211.481162)
		(end 44.447206 -209.22996)
		(width 0.1651)
		(layer "In5.Cu")
		(net "PE_TX2_DR12_N")
	)
	(segment
		(start 28.164536 -232.387648)
		(end 30.612588 -230.673656)
		(width 0.1651)
		(layer "In5.Cu")
		(net "PE_TX2_DR12_N")
	)
	(segment
		(start 26.67 -232.616248)
		(end 26.8986 -232.387648)
		(width 0.1651)
		(layer "In5.Cu")
		(net "PE_TX2_DR12_N")
	)
	(segment
		(start 30.612588 -230.673656)
		(end 44.04995 -211.481162)
		(width 0.1651)
		(layer "In5.Cu")
		(net "PE_TX2_DR12_N")
	)
	(segment
		(start 9.35863 -217.248486)
		(end 9.358376 -217.248486)
		(width 0.1651)
		(layer "In5.Cu")
		(net "PE_TX2_DR12_N")
	)
	(segment
		(start 19.403314 -200.068942)
		(end 17.571212 -201.351134)
		(width 0.1651)
		(layer "In5.Cu")
		(net "PE_TX2_DR12_N")
	)
	(segment
		(start 17.571212 -201.351134)
		(end 13.904468 -206.587852)
		(width 0.1651)
		(layer "In5.Cu")
		(net "PE_TX2_DR12_N")
	)
	(segment
		(start 13.904468 -206.587852)
		(end 12.781026 -212.957918)
		(width 0.1651)
		(layer "In5.Cu")
		(net "PE_TX2_DR12_N")
	)
	(segment
		(start 12.781026 -212.957918)
		(end 10.231628 -216.598754)
		(width 0.1651)
		(layer "In5.Cu")
		(net "PE_TX2_DR12_N")
	)
	(segment
		(start 26.8986 -232.387648)
		(end 28.164536 -232.387648)
		(width 0.1651)
		(layer "In5.Cu")
		(net "PE_TX2_DR12_N")
	)
	(segment
		(start 9.358376 -217.248486)
		(end 9.045194 -217.467942)
		(width 0.1651)
		(layer "In5.Cu")
		(net "PE_TX2_DR12_N")
	)
	(segment
		(start 9.045194 -217.467942)
		(end 9.04494 -217.467942)
		(width 0.1651)
		(layer "In5.Cu")
		(net "PE_TX2_DR12_N")
	)
	(segment
		(start 43.990006 -206.633826)
		(end 42.229278 -204.119226)
		(width 0.1651)
		(layer "In5.Cu")
		(net "PE_TX2_DR12_N")
	)
	(segment
		(start 7.220966 -217.713814)
		(end 6.992366 -217.485214)
		(width 0.1651)
		(layer "In5.Cu")
		(net "PE_TX2_DR12_N")
	)
	(segment
		(start 23.900384 -199.27697)
		(end 19.403314 -200.068942)
		(width 0.1651)
		(layer "In5.Cu")
		(net "PE_TX2_DR12_N")
	)
	(segment
		(start 39.154862 -201.96683)
		(end 23.900384 -199.27697)
		(width 0.1651)
		(layer "In5.Cu")
		(net "PE_TX2_DR12_N")
	)
	(segment
		(start 44.447206 -209.22996)
		(end 43.990006 -206.633826)
		(width 0.1651)
		(layer "In5.Cu")
		(net "PE_TX2_DR12_N")
	)
	(segment
		(start 7.651242 -217.713814)
		(end 7.220966 -217.713814)
		(width 0.1651)
		(layer "In5.Cu")
		(net "PE_TX2_DR12_N")
	)
	(segment
		(start 9.04494 -217.467942)
		(end 7.651242 -217.713814)
		(width 0.1651)
		(layer "In5.Cu")
		(net "PE_TX2_DR12_N")
	)
	(segment
		(start 10.17905 -216.673938)
		(end 9.35863 -217.248486)
		(width 0.1651)
		(layer "In5.Cu")
		(net "PE_TX2_DR12_N")
	)
	(segment
		(start 2.249932 -337.942174)
		(end 3.6576 -337.942174)
		(width 0.174752)
		(layer "F.Cu")
		(net "PE_TX2_DR11_P")
	)
	(segment
		(start 22.800056 -334.8101)
		(end 23.876 -334.8101)
		(width 0.174752)
		(layer "F.Cu")
		(net "PE_TX2_DR11_P")
	)
	(segment
		(start 23.876 -334.8101)
		(end 24.123396 -335.057496)
		(width 0.174752)
		(layer "F.Cu")
		(net "PE_TX2_DR11_P")
	)
	(segment
		(start 6.738112 -337.745324)
		(end 6.992366 -337.999578)
		(width 0.174752)
		(layer "F.Cu")
		(net "PE_TX2_DR11_P")
	)
	(segment
		(start 3.6576 -337.942174)
		(end 3.85445 -337.745324)
		(width 0.174752)
		(layer "F.Cu")
		(net "PE_TX2_DR11_P")
	)
	(segment
		(start 3.85445 -337.745324)
		(end 6.738112 -337.745324)
		(width 0.174752)
		(layer "F.Cu")
		(net "PE_TX2_DR11_P")
	)
	(segment
		(start 26.416 -335.057496)
		(end 26.67 -334.803496)
		(width 0.174752)
		(layer "F.Cu")
		(net "PE_TX2_DR11_P")
	)
	(segment
		(start 24.123396 -335.057496)
		(end 26.416 -335.057496)
		(width 0.174752)
		(layer "F.Cu")
		(net "PE_TX2_DR11_P")
	)
	(via
		(at 26.67 -334.803496)
		(size 0.508)
		(drill 0.254)
		(layers "F.Cu" "B.Cu")
		(net "PE_TX2_DR11_P")
	)
	(via
		(at 6.992366 -337.999578)
		(size 0.508)
		(drill 0.254)
		(layers "F.Cu" "B.Cu")
		(net "PE_TX2_DR11_P")
	)
	(segment
		(start 26.67 -334.803496)
		(end 26.8986 -335.032096)
		(width 0.1651)
		(layer "In5.Cu")
		(net "PE_TX2_DR11_P")
	)
	(segment
		(start 29.087826 -336.489548)
		(end 28.345384 -340.700868)
		(width 0.1651)
		(layer "In5.Cu")
		(net "PE_TX2_DR11_P")
	)
	(segment
		(start 26.8986 -335.032096)
		(end 27.6606 -335.032096)
		(width 0.1651)
		(layer "In5.Cu")
		(net "PE_TX2_DR11_P")
	)
	(segment
		(start 21.787358 -353.020122)
		(end 20.574 -352.171)
		(width 0.1651)
		(layer "In5.Cu")
		(net "PE_TX2_DR11_P")
	)
	(segment
		(start 9.256522 -338.014056)
		(end 7.876794 -337.770978)
		(width 0.1651)
		(layer "In5.Cu")
		(net "PE_TX2_DR11_P")
	)
	(segment
		(start 29.917898 -350.27235)
		(end 29.343604 -351.091246)
		(width 0.1651)
		(layer "In5.Cu")
		(net "PE_TX2_DR11_P")
	)
	(segment
		(start 29.97581 -349.944436)
		(end 29.917898 -350.27235)
		(width 0.1651)
		(layer "In5.Cu")
		(net "PE_TX2_DR11_P")
	)
	(segment
		(start 28.345384 -340.700868)
		(end 29.97581 -349.944436)
		(width 0.1651)
		(layer "In5.Cu")
		(net "PE_TX2_DR11_P")
	)
	(segment
		(start 28.279598 -335.141316)
		(end 28.69819 -335.434432)
		(width 0.1651)
		(layer "In5.Cu")
		(net "PE_TX2_DR11_P")
	)
	(segment
		(start 12.020042 -340.618064)
		(end 10.8966 -339.0138)
		(width 0.1651)
		(layer "In5.Cu")
		(net "PE_TX2_DR11_P")
	)
	(segment
		(start 15.921736 -348.51467)
		(end 12.567666 -343.723976)
		(width 0.1651)
		(layer "In5.Cu")
		(net "PE_TX2_DR11_P")
	)
	(segment
		(start 27.6606 -335.032096)
		(end 28.279598 -335.141316)
		(width 0.1651)
		(layer "In5.Cu")
		(net "PE_TX2_DR11_P")
	)
	(segment
		(start 24.122634 -353.432364)
		(end 21.787358 -353.020122)
		(width 0.1651)
		(layer "In5.Cu")
		(net "PE_TX2_DR11_P")
	)
	(segment
		(start 9.778746 -338.231226)
		(end 9.256522 -338.014056)
		(width 0.1651)
		(layer "In5.Cu")
		(net "PE_TX2_DR11_P")
	)
	(segment
		(start 28.69819 -335.434432)
		(end 28.970478 -335.82356)
		(width 0.1651)
		(layer "In5.Cu")
		(net "PE_TX2_DR11_P")
	)
	(segment
		(start 10.8966 -339.0138)
		(end 9.778746 -338.231226)
		(width 0.1651)
		(layer "In5.Cu")
		(net "PE_TX2_DR11_P")
	)
	(segment
		(start 28.970478 -335.82356)
		(end 29.087826 -336.489548)
		(width 0.1651)
		(layer "In5.Cu")
		(net "PE_TX2_DR11_P")
	)
	(segment
		(start 12.567666 -343.723976)
		(end 12.020042 -340.618064)
		(width 0.1651)
		(layer "In5.Cu")
		(net "PE_TX2_DR11_P")
	)
	(segment
		(start 29.343604 -351.091246)
		(end 26.6319 -352.989896)
		(width 0.1651)
		(layer "In5.Cu")
		(net "PE_TX2_DR11_P")
	)
	(segment
		(start 7.876794 -337.770978)
		(end 7.220966 -337.770978)
		(width 0.1651)
		(layer "In5.Cu")
		(net "PE_TX2_DR11_P")
	)
	(segment
		(start 20.574 -352.171)
		(end 20.02536 -351.38741)
		(width 0.1651)
		(layer "In5.Cu")
		(net "PE_TX2_DR11_P")
	)
	(segment
		(start 20.02536 -351.38741)
		(end 15.921736 -348.51467)
		(width 0.1651)
		(layer "In5.Cu")
		(net "PE_TX2_DR11_P")
	)
	(segment
		(start 26.6319 -352.989896)
		(end 24.122634 -353.432364)
		(width 0.1651)
		(layer "In5.Cu")
		(net "PE_TX2_DR11_P")
	)
	(segment
		(start 7.220966 -337.770978)
		(end 6.992366 -337.999578)
		(width 0.1651)
		(layer "In5.Cu")
		(net "PE_TX2_DR11_P")
	)
	(segment
		(start 6.738874 -337.44027)
		(end 6.992366 -337.186778)
		(width 0.174752)
		(layer "F.Cu")
		(net "PE_TX2_DR11_N")
	)
	(segment
		(start 24.13 -335.36255)
		(end 26.416254 -335.36255)
		(width 0.174752)
		(layer "F.Cu")
		(net "PE_TX2_DR11_N")
	)
	(segment
		(start 3.657854 -337.142074)
		(end 3.95605 -337.44027)
		(width 0.174752)
		(layer "F.Cu")
		(net "PE_TX2_DR11_N")
	)
	(segment
		(start 26.416254 -335.36255)
		(end 26.67 -335.616296)
		(width 0.174752)
		(layer "F.Cu")
		(net "PE_TX2_DR11_N")
	)
	(segment
		(start 22.800056 -335.609946)
		(end 23.882604 -335.609946)
		(width 0.174752)
		(layer "F.Cu")
		(net "PE_TX2_DR11_N")
	)
	(segment
		(start 23.882604 -335.609946)
		(end 24.13 -335.36255)
		(width 0.174752)
		(layer "F.Cu")
		(net "PE_TX2_DR11_N")
	)
	(segment
		(start 3.95605 -337.44027)
		(end 6.738874 -337.44027)
		(width 0.174752)
		(layer "F.Cu")
		(net "PE_TX2_DR11_N")
	)
	(segment
		(start 2.249932 -337.142074)
		(end 3.657854 -337.142074)
		(width 0.174752)
		(layer "F.Cu")
		(net "PE_TX2_DR11_N")
	)
	(via
		(at 26.67 -335.616296)
		(size 0.508)
		(drill 0.254)
		(layers "F.Cu" "B.Cu")
		(net "PE_TX2_DR11_N")
	)
	(via
		(at 6.992366 -337.186778)
		(size 0.508)
		(drill 0.254)
		(layers "F.Cu" "B.Cu")
		(net "PE_TX2_DR11_N")
	)
	(segment
		(start 28.164028 -341.720678)
		(end 28.011628 -341.938356)
		(width 0.1651)
		(layer "In5.Cu")
		(net "PE_TX2_DR11_N")
	)
	(segment
		(start 28.57246 -345.117674)
		(end 28.790138 -345.270074)
		(width 0.1651)
		(layer "In5.Cu")
		(net "PE_TX2_DR11_N")
	)
	(segment
		(start 26.492454 -352.653346)
		(end 24.122634 -353.071176)
		(width 0.1651)
		(layer "In5.Cu")
		(net "PE_TX2_DR11_N")
	)
	(segment
		(start 28.422854 -337.129882)
		(end 28.337002 -337.617562)
		(width 0.1651)
		(layer "In5.Cu")
		(net "PE_TX2_DR11_N")
	)
	(segment
		(start 16.17726 -348.259146)
		(end 15.255494 -346.942664)
		(width 0.1651)
		(layer "In5.Cu")
		(net "PE_TX2_DR11_N")
	)
	(segment
		(start 13.188188 -343.990168)
		(end 12.904216 -343.58453)
		(width 0.1651)
		(layer "In5.Cu")
		(net "PE_TX2_DR11_N")
	)
	(segment
		(start 20.280884 -351.131886)
		(end 16.17726 -348.259146)
		(width 0.1651)
		(layer "In5.Cu")
		(net "PE_TX2_DR11_N")
	)
	(segment
		(start 28.337002 -337.617562)
		(end 28.489402 -337.83524)
		(width 0.1651)
		(layer "In5.Cu")
		(net "PE_TX2_DR11_N")
	)
	(segment
		(start 21.926804 -352.683572)
		(end 20.829524 -351.915476)
		(width 0.1651)
		(layer "In5.Cu")
		(net "PE_TX2_DR11_N")
	)
	(segment
		(start 15.01775 -346.275152)
		(end 14.755876 -346.229178)
		(width 0.1651)
		(layer "In5.Cu")
		(net "PE_TX2_DR11_N")
	)
	(segment
		(start 28.640532 -336.977228)
		(end 28.422854 -337.129882)
		(width 0.1651)
		(layer "In5.Cu")
		(net "PE_TX2_DR11_N")
	)
	(segment
		(start 28.552648 -343.924382)
		(end 28.638754 -344.412062)
		(width 0.1651)
		(layer "In5.Cu")
		(net "PE_TX2_DR11_N")
	)
	(segment
		(start 26.67 -335.616296)
		(end 26.8986 -335.387696)
		(width 0.1651)
		(layer "In5.Cu")
		(net "PE_TX2_DR11_N")
	)
	(segment
		(start 29.088334 -350.835722)
		(end 26.492454 -352.653346)
		(width 0.1651)
		(layer "In5.Cu")
		(net "PE_TX2_DR11_N")
	)
	(segment
		(start 7.220966 -337.415378)
		(end 6.992366 -337.186778)
		(width 0.1651)
		(layer "In5.Cu")
		(net "PE_TX2_DR11_N")
	)
	(segment
		(start 13.734288 -344.442034)
		(end 13.450062 -344.036396)
		(width 0.1651)
		(layer "In5.Cu")
		(net "PE_TX2_DR11_N")
	)
	(segment
		(start 14.517878 -345.561666)
		(end 14.233906 -345.155774)
		(width 0.1651)
		(layer "In5.Cu")
		(net "PE_TX2_DR11_N")
	)
	(segment
		(start 28.011628 -341.938356)
		(end 28.09748 -342.426036)
		(width 0.1651)
		(layer "In5.Cu")
		(net "PE_TX2_DR11_N")
	)
	(segment
		(start 28.09748 -342.426036)
		(end 28.315158 -342.57869)
		(width 0.1651)
		(layer "In5.Cu")
		(net "PE_TX2_DR11_N")
	)
	(segment
		(start 28.489402 -337.83524)
		(end 27.984196 -340.700868)
		(width 0.1651)
		(layer "In5.Cu")
		(net "PE_TX2_DR11_N")
	)
	(segment
		(start 12.356592 -340.478618)
		(end 12.31138 -340.413848)
		(width 0.1651)
		(layer "In5.Cu")
		(net "PE_TX2_DR11_N")
	)
	(segment
		(start 9.951212 -337.917536)
		(end 9.356852 -337.670648)
		(width 0.1651)
		(layer "In5.Cu")
		(net "PE_TX2_DR11_N")
	)
	(segment
		(start 28.726638 -336.489548)
		(end 28.640532 -336.977228)
		(width 0.1651)
		(layer "In5.Cu")
		(net "PE_TX2_DR11_N")
	)
	(segment
		(start 28.401264 -343.06637)
		(end 28.248864 -343.284048)
		(width 0.1651)
		(layer "In5.Cu")
		(net "PE_TX2_DR11_N")
	)
	(segment
		(start 14.755876 -346.229178)
		(end 14.471904 -345.823286)
		(width 0.1651)
		(layer "In5.Cu")
		(net "PE_TX2_DR11_N")
	)
	(segment
		(start 12.31138 -340.414102)
		(end 12.030456 -340.012782)
		(width 0.1651)
		(layer "In5.Cu")
		(net "PE_TX2_DR11_N")
	)
	(segment
		(start 13.450062 -344.036396)
		(end 13.188188 -343.990168)
		(width 0.1651)
		(layer "In5.Cu")
		(net "PE_TX2_DR11_N")
	)
	(segment
		(start 9.356852 -337.670648)
		(end 7.908036 -337.415378)
		(width 0.1651)
		(layer "In5.Cu")
		(net "PE_TX2_DR11_N")
	)
	(segment
		(start 13.68806 -344.703908)
		(end 13.734288 -344.442034)
		(width 0.1651)
		(layer "In5.Cu")
		(net "PE_TX2_DR11_N")
	)
	(segment
		(start 15.301722 -346.681044)
		(end 15.01775 -346.275152)
		(width 0.1651)
		(layer "In5.Cu")
		(net "PE_TX2_DR11_N")
	)
	(segment
		(start 27.984196 -340.700868)
		(end 28.164028 -341.720678)
		(width 0.1651)
		(layer "In5.Cu")
		(net "PE_TX2_DR11_N")
	)
	(segment
		(start 28.442666 -335.689956)
		(end 28.633674 -335.963006)
		(width 0.1651)
		(layer "In5.Cu")
		(net "PE_TX2_DR11_N")
	)
	(segment
		(start 12.904216 -343.58453)
		(end 12.904216 -343.584276)
		(width 0.1651)
		(layer "In5.Cu")
		(net "PE_TX2_DR11_N")
	)
	(segment
		(start 29.581348 -350.13265)
		(end 29.088334 -350.835722)
		(width 0.1651)
		(layer "In5.Cu")
		(net "PE_TX2_DR11_N")
	)
	(segment
		(start 14.233906 -345.155774)
		(end 13.972032 -345.109546)
		(width 0.1651)
		(layer "In5.Cu")
		(net "PE_TX2_DR11_N")
	)
	(segment
		(start 26.8986 -335.387696)
		(end 27.629358 -335.387696)
		(width 0.1651)
		(layer "In5.Cu")
		(net "PE_TX2_DR11_N")
	)
	(segment
		(start 28.790138 -345.270074)
		(end 29.614622 -349.944436)
		(width 0.1651)
		(layer "In5.Cu")
		(net "PE_TX2_DR11_N")
	)
	(segment
		(start 28.638754 -344.412062)
		(end 28.486354 -344.629994)
		(width 0.1651)
		(layer "In5.Cu")
		(net "PE_TX2_DR11_N")
	)
	(segment
		(start 24.122634 -353.071176)
		(end 21.926804 -352.683572)
		(width 0.1651)
		(layer "In5.Cu")
		(net "PE_TX2_DR11_N")
	)
	(segment
		(start 28.486354 -344.629994)
		(end 28.57246 -345.117674)
		(width 0.1651)
		(layer "In5.Cu")
		(net "PE_TX2_DR11_N")
	)
	(segment
		(start 13.972032 -345.109546)
		(end 13.68806 -344.703908)
		(width 0.1651)
		(layer "In5.Cu")
		(net "PE_TX2_DR11_N")
	)
	(segment
		(start 11.152124 -338.758276)
		(end 9.951212 -337.917536)
		(width 0.1651)
		(layer "In5.Cu")
		(net "PE_TX2_DR11_N")
	)
	(segment
		(start 28.248864 -343.284048)
		(end 28.33497 -343.771728)
		(width 0.1651)
		(layer "In5.Cu")
		(net "PE_TX2_DR11_N")
	)
	(segment
		(start 29.614622 -349.944436)
		(end 29.581348 -350.13265)
		(width 0.1651)
		(layer "In5.Cu")
		(net "PE_TX2_DR11_N")
	)
	(segment
		(start 12.030456 -340.012782)
		(end 11.152124 -338.758276)
		(width 0.1651)
		(layer "In5.Cu")
		(net "PE_TX2_DR11_N")
	)
	(segment
		(start 15.255494 -346.942664)
		(end 15.301722 -346.681044)
		(width 0.1651)
		(layer "In5.Cu")
		(net "PE_TX2_DR11_N")
	)
	(segment
		(start 20.829524 -351.915476)
		(end 20.280884 -351.131886)
		(width 0.1651)
		(layer "In5.Cu")
		(net "PE_TX2_DR11_N")
	)
	(segment
		(start 28.315158 -342.57869)
		(end 28.401264 -343.06637)
		(width 0.1651)
		(layer "In5.Cu")
		(net "PE_TX2_DR11_N")
	)
	(segment
		(start 28.33497 -343.771728)
		(end 28.552648 -343.924382)
		(width 0.1651)
		(layer "In5.Cu")
		(net "PE_TX2_DR11_N")
	)
	(segment
		(start 27.629358 -335.387696)
		(end 28.140152 -335.477866)
		(width 0.1651)
		(layer "In5.Cu")
		(net "PE_TX2_DR11_N")
	)
	(segment
		(start 12.904216 -343.584276)
		(end 12.356592 -340.478618)
		(width 0.1651)
		(layer "In5.Cu")
		(net "PE_TX2_DR11_N")
	)
	(segment
		(start 28.633674 -335.963006)
		(end 28.726638 -336.489548)
		(width 0.1651)
		(layer "In5.Cu")
		(net "PE_TX2_DR11_N")
	)
	(segment
		(start 7.908036 -337.415378)
		(end 7.220966 -337.415378)
		(width 0.1651)
		(layer "In5.Cu")
		(net "PE_TX2_DR11_N")
	)
	(segment
		(start 28.140152 -335.477866)
		(end 28.442666 -335.689956)
		(width 0.1651)
		(layer "In5.Cu")
		(net "PE_TX2_DR11_N")
	)
	(segment
		(start 14.471904 -345.823286)
		(end 14.517878 -345.561666)
		(width 0.1651)
		(layer "In5.Cu")
		(net "PE_TX2_DR11_N")
	)
	(segment
		(start 12.31138 -340.413848)
		(end 12.31138 -340.414102)
		(width 0.1651)
		(layer "In5.Cu")
		(net "PE_TX2_DR11_N")
	)
	(segment
		(start 6.73862 -405.789384)
		(end 6.992366 -405.535638)
		(width 0.174752)
		(layer "F.Cu")
		(net "PE_TX2_DR10_P")
	)
	(segment
		(start 24.003 -438.609994)
		(end 22.800056 -438.609994)
		(width 0.174752)
		(layer "F.Cu")
		(net "PE_TX2_DR10_P")
	)
	(segment
		(start 26.67 -438.616344)
		(end 26.441654 -438.387998)
		(width 0.174752)
		(layer "F.Cu")
		(net "PE_TX2_DR10_P")
	)
	(segment
		(start 3.657854 -405.541988)
		(end 3.90525 -405.789384)
		(width 0.174752)
		(layer "F.Cu")
		(net "PE_TX2_DR10_P")
	)
	(segment
		(start 2.249932 -405.541988)
		(end 3.657854 -405.541988)
		(width 0.174752)
		(layer "F.Cu")
		(net "PE_TX2_DR10_P")
	)
	(segment
		(start 24.224996 -438.387998)
		(end 24.003 -438.609994)
		(width 0.174752)
		(layer "F.Cu")
		(net "PE_TX2_DR10_P")
	)
	(segment
		(start 3.90525 -405.789384)
		(end 6.73862 -405.789384)
		(width 0.174752)
		(layer "F.Cu")
		(net "PE_TX2_DR10_P")
	)
	(segment
		(start 26.441654 -438.387998)
		(end 24.224996 -438.387998)
		(width 0.174752)
		(layer "F.Cu")
		(net "PE_TX2_DR10_P")
	)
	(via
		(at 6.992366 -405.535638)
		(size 0.508)
		(drill 0.254)
		(layers "F.Cu" "B.Cu")
		(net "PE_TX2_DR10_P")
	)
	(via
		(at 26.67 -438.616344)
		(size 0.508)
		(drill 0.254)
		(layers "F.Cu" "B.Cu")
		(net "PE_TX2_DR10_P")
	)
	(segment
		(start 43.332654 -420.028878)
		(end 44.228258 -414.950148)
		(width 0.1651)
		(layer "In5.Cu")
		(net "PE_TX2_DR10_P")
	)
	(segment
		(start 20.827492 -407.055066)
		(end 17.90065 -407.571448)
		(width 0.1651)
		(layer "In5.Cu")
		(net "PE_TX2_DR10_P")
	)
	(segment
		(start 44.228258 -414.950148)
		(end 44.018962 -413.763206)
		(width 0.1651)
		(layer "In5.Cu")
		(net "PE_TX2_DR10_P")
	)
	(segment
		(start 17.90065 -407.571448)
		(end 7.651242 -405.764238)
		(width 0.1651)
		(layer "In5.Cu")
		(net "PE_TX2_DR10_P")
	)
	(segment
		(start 7.220966 -405.764238)
		(end 6.992366 -405.535638)
		(width 0.1651)
		(layer "In5.Cu")
		(net "PE_TX2_DR10_P")
	)
	(segment
		(start 28.164282 -438.387744)
		(end 32.700722 -435.211474)
		(width 0.1651)
		(layer "In5.Cu")
		(net "PE_TX2_DR10_P")
	)
	(segment
		(start 41.241726 -410.653992)
		(end 20.827492 -407.055066)
		(width 0.1651)
		(layer "In5.Cu")
		(net "PE_TX2_DR10_P")
	)
	(segment
		(start 44.018962 -413.763206)
		(end 42.419524 -411.478476)
		(width 0.1651)
		(layer "In5.Cu")
		(net "PE_TX2_DR10_P")
	)
	(segment
		(start 32.700722 -435.211474)
		(end 43.332654 -420.028878)
		(width 0.1651)
		(layer "In5.Cu")
		(net "PE_TX2_DR10_P")
	)
	(segment
		(start 26.8986 -438.387744)
		(end 28.164282 -438.387744)
		(width 0.1651)
		(layer "In5.Cu")
		(net "PE_TX2_DR10_P")
	)
	(segment
		(start 42.419524 -411.478476)
		(end 41.241726 -410.653992)
		(width 0.1651)
		(layer "In5.Cu")
		(net "PE_TX2_DR10_P")
	)
	(segment
		(start 7.651242 -405.764238)
		(end 7.220966 -405.764238)
		(width 0.1651)
		(layer "In5.Cu")
		(net "PE_TX2_DR10_P")
	)
	(segment
		(start 26.67 -438.616344)
		(end 26.8986 -438.387744)
		(width 0.1651)
		(layer "In5.Cu")
		(net "PE_TX2_DR10_P")
	)
	(segment
		(start 3.90525 -406.094438)
		(end 6.738366 -406.094438)
		(width 0.174752)
		(layer "F.Cu")
		(net "PE_TX2_DR10_N")
	)
	(segment
		(start 26.3906 -438.082944)
		(end 24.275796 -438.082944)
		(width 0.174752)
		(layer "F.Cu")
		(net "PE_TX2_DR10_N")
	)
	(segment
		(start 24.003 -437.810148)
		(end 22.800056 -437.810148)
		(width 0.174752)
		(layer "F.Cu")
		(net "PE_TX2_DR10_N")
	)
	(segment
		(start 26.67 -437.803544)
		(end 26.3906 -438.082944)
		(width 0.174752)
		(layer "F.Cu")
		(net "PE_TX2_DR10_N")
	)
	(segment
		(start 2.249932 -406.341834)
		(end 3.657854 -406.341834)
		(width 0.174752)
		(layer "F.Cu")
		(net "PE_TX2_DR10_N")
	)
	(segment
		(start 3.657854 -406.341834)
		(end 3.90525 -406.094438)
		(width 0.174752)
		(layer "F.Cu")
		(net "PE_TX2_DR10_N")
	)
	(segment
		(start 24.275796 -438.082944)
		(end 24.003 -437.810148)
		(width 0.174752)
		(layer "F.Cu")
		(net "PE_TX2_DR10_N")
	)
	(segment
		(start 6.738366 -406.094438)
		(end 6.992366 -406.348438)
		(width 0.174752)
		(layer "F.Cu")
		(net "PE_TX2_DR10_N")
	)
	(via
		(at 26.67 -437.803544)
		(size 0.508)
		(drill 0.254)
		(layers "F.Cu" "B.Cu")
		(net "PE_TX2_DR10_N")
	)
	(via
		(at 6.992366 -406.348438)
		(size 0.508)
		(drill 0.254)
		(layers "F.Cu" "B.Cu")
		(net "PE_TX2_DR10_N")
	)
	(segment
		(start 28.909518 -437.202072)
		(end 28.50388 -437.486298)
		(width 0.1651)
		(layer "In5.Cu")
		(net "PE_TX2_DR10_N")
	)
	(segment
		(start 29.57703 -436.964328)
		(end 29.171392 -437.2483)
		(width 0.1651)
		(layer "In5.Cu")
		(net "PE_TX2_DR10_N")
	)
	(segment
		(start 26.8986 -438.032144)
		(end 26.67 -437.803544)
		(width 0.1651)
		(layer "In5.Cu")
		(net "PE_TX2_DR10_N")
	)
	(segment
		(start 33.513268 -433.430934)
		(end 33.229042 -433.836572)
		(width 0.1651)
		(layer "In5.Cu")
		(net "PE_TX2_DR10_N")
	)
	(segment
		(start 34.012886 -432.717194)
		(end 33.751266 -432.763422)
		(width 0.1651)
		(layer "In5.Cu")
		(net "PE_TX2_DR10_N")
	)
	(segment
		(start 28.50388 -437.486298)
		(end 28.457652 -437.748172)
		(width 0.1651)
		(layer "In5.Cu")
		(net "PE_TX2_DR10_N")
	)
	(segment
		(start 43.86707 -414.950148)
		(end 42.996104 -419.889432)
		(width 0.1651)
		(layer "In5.Cu")
		(net "PE_TX2_DR10_N")
	)
	(segment
		(start 7.220966 -406.119838)
		(end 7.62 -406.119838)
		(width 0.1651)
		(layer "In5.Cu")
		(net "PE_TX2_DR10_N")
	)
	(segment
		(start 41.102026 -410.990542)
		(end 42.164 -411.734)
		(width 0.1651)
		(layer "In5.Cu")
		(net "PE_TX2_DR10_N")
	)
	(segment
		(start 34.79673 -431.597816)
		(end 34.53511 -431.644044)
		(width 0.1651)
		(layer "In5.Cu")
		(net "PE_TX2_DR10_N")
	)
	(segment
		(start 30.028896 -436.418482)
		(end 29.623258 -436.702454)
		(width 0.1651)
		(layer "In5.Cu")
		(net "PE_TX2_DR10_N")
	)
	(segment
		(start 30.696408 -436.180484)
		(end 30.29077 -436.464456)
		(width 0.1651)
		(layer "In5.Cu")
		(net "PE_TX2_DR10_N")
	)
	(segment
		(start 36.753546 -428.803816)
		(end 36.491672 -428.84979)
		(width 0.1651)
		(layer "In5.Cu")
		(net "PE_TX2_DR10_N")
	)
	(segment
		(start 17.90065 -407.932636)
		(end 17.900904 -407.932636)
		(width 0.1651)
		(layer "In5.Cu")
		(net "PE_TX2_DR10_N")
	)
	(segment
		(start 31.148274 -435.634638)
		(end 30.742636 -435.91861)
		(width 0.1651)
		(layer "In5.Cu")
		(net "PE_TX2_DR10_N")
	)
	(segment
		(start 36.2077 -429.255682)
		(end 36.253674 -429.517302)
		(width 0.1651)
		(layer "In5.Cu")
		(net "PE_TX2_DR10_N")
	)
	(segment
		(start 29.623258 -436.702454)
		(end 29.57703 -436.964328)
		(width 0.1651)
		(layer "In5.Cu")
		(net "PE_TX2_DR10_N")
	)
	(segment
		(start 36.253674 -429.517302)
		(end 34.79673 -431.597816)
		(width 0.1651)
		(layer "In5.Cu")
		(net "PE_TX2_DR10_N")
	)
	(segment
		(start 6.992366 -406.348438)
		(end 7.220966 -406.119838)
		(width 0.1651)
		(layer "In5.Cu")
		(net "PE_TX2_DR10_N")
	)
	(segment
		(start 32.967168 -433.8828)
		(end 32.683196 -434.288438)
		(width 0.1651)
		(layer "In5.Cu")
		(net "PE_TX2_DR10_N")
	)
	(segment
		(start 33.751266 -432.763422)
		(end 33.46704 -433.16906)
		(width 0.1651)
		(layer "In5.Cu")
		(net "PE_TX2_DR10_N")
	)
	(segment
		(start 32.729424 -434.550312)
		(end 32.445198 -434.95595)
		(width 0.1651)
		(layer "In5.Cu")
		(net "PE_TX2_DR10_N")
	)
	(segment
		(start 30.29077 -436.464456)
		(end 30.028896 -436.418482)
		(width 0.1651)
		(layer "In5.Cu")
		(net "PE_TX2_DR10_N")
	)
	(segment
		(start 34.297112 -432.311556)
		(end 34.012886 -432.717194)
		(width 0.1651)
		(layer "In5.Cu")
		(net "PE_TX2_DR10_N")
	)
	(segment
		(start 32.445198 -434.95595)
		(end 31.410148 -435.680612)
		(width 0.1651)
		(layer "In5.Cu")
		(net "PE_TX2_DR10_N")
	)
	(segment
		(start 7.62 -406.119838)
		(end 17.90065 -407.932636)
		(width 0.1651)
		(layer "In5.Cu")
		(net "PE_TX2_DR10_N")
	)
	(segment
		(start 43.682412 -413.902652)
		(end 43.86707 -414.950148)
		(width 0.1651)
		(layer "In5.Cu")
		(net "PE_TX2_DR10_N")
	)
	(segment
		(start 28.052014 -438.032144)
		(end 26.8986 -438.032144)
		(width 0.1651)
		(layer "In5.Cu")
		(net "PE_TX2_DR10_N")
	)
	(segment
		(start 34.53511 -431.644044)
		(end 34.250884 -432.049682)
		(width 0.1651)
		(layer "In5.Cu")
		(net "PE_TX2_DR10_N")
	)
	(segment
		(start 32.683196 -434.288438)
		(end 32.729424 -434.550312)
		(width 0.1651)
		(layer "In5.Cu")
		(net "PE_TX2_DR10_N")
	)
	(segment
		(start 42.996104 -419.889432)
		(end 36.753546 -428.803816)
		(width 0.1651)
		(layer "In5.Cu")
		(net "PE_TX2_DR10_N")
	)
	(segment
		(start 36.491672 -428.84979)
		(end 36.2077 -429.255682)
		(width 0.1651)
		(layer "In5.Cu")
		(net "PE_TX2_DR10_N")
	)
	(segment
		(start 20.827492 -407.416254)
		(end 41.102026 -410.990542)
		(width 0.1651)
		(layer "In5.Cu")
		(net "PE_TX2_DR10_N")
	)
	(segment
		(start 33.229042 -433.836572)
		(end 32.967168 -433.8828)
		(width 0.1651)
		(layer "In5.Cu")
		(net "PE_TX2_DR10_N")
	)
	(segment
		(start 42.164 -411.734)
		(end 43.682412 -413.902652)
		(width 0.1651)
		(layer "In5.Cu")
		(net "PE_TX2_DR10_N")
	)
	(segment
		(start 33.46704 -433.16906)
		(end 33.513268 -433.430934)
		(width 0.1651)
		(layer "In5.Cu")
		(net "PE_TX2_DR10_N")
	)
	(segment
		(start 30.742636 -435.91861)
		(end 30.696408 -436.180484)
		(width 0.1651)
		(layer "In5.Cu")
		(net "PE_TX2_DR10_N")
	)
	(segment
		(start 28.457652 -437.748172)
		(end 28.052014 -438.032144)
		(width 0.1651)
		(layer "In5.Cu")
		(net "PE_TX2_DR10_N")
	)
	(segment
		(start 29.171392 -437.2483)
		(end 28.909518 -437.202072)
		(width 0.1651)
		(layer "In5.Cu")
		(net "PE_TX2_DR10_N")
	)
	(segment
		(start 34.250884 -432.049682)
		(end 34.297112 -432.311556)
		(width 0.1651)
		(layer "In5.Cu")
		(net "PE_TX2_DR10_N")
	)
	(segment
		(start 17.900904 -407.932636)
		(end 20.827492 -407.416254)
		(width 0.1651)
		(layer "In5.Cu")
		(net "PE_TX2_DR10_N")
	)
	(segment
		(start 31.410148 -435.680612)
		(end 31.148274 -435.634638)
		(width 0.1651)
		(layer "In5.Cu")
		(net "PE_TX2_DR10_N")
	)
	(segment
		(start 220.584014 -376.942604)
		(end 220.330014 -377.196604)
		(width 0.174752)
		(layer "F.Cu")
		(net "PE_TX2_DR1_P")
	)
	(segment
		(start 3.905504 -390.894316)
		(end 6.738112 -390.894316)
		(width 0.174752)
		(layer "F.Cu")
		(net "PE_TX2_DR1_P")
	)
	(segment
		(start 224.199958 -377.19)
		(end 223.132396 -377.19)
		(width 0.174752)
		(layer "F.Cu")
		(net "PE_TX2_DR1_P")
	)
	(segment
		(start 6.738112 -390.894316)
		(end 6.992366 -391.14857)
		(width 0.174752)
		(layer "F.Cu")
		(net "PE_TX2_DR1_P")
	)
	(segment
		(start 2.249932 -391.141966)
		(end 3.657854 -391.141966)
		(width 0.174752)
		(layer "F.Cu")
		(net "PE_TX2_DR1_P")
	)
	(segment
		(start 3.657854 -391.141966)
		(end 3.905504 -390.894316)
		(width 0.174752)
		(layer "F.Cu")
		(net "PE_TX2_DR1_P")
	)
	(segment
		(start 223.132396 -377.19)
		(end 222.885 -376.942604)
		(width 0.174752)
		(layer "F.Cu")
		(net "PE_TX2_DR1_P")
	)
	(segment
		(start 222.885 -376.942604)
		(end 220.584014 -376.942604)
		(width 0.174752)
		(layer "F.Cu")
		(net "PE_TX2_DR1_P")
	)
	(via
		(at 220.330014 -377.196604)
		(size 0.508)
		(drill 0.254)
		(layers "F.Cu" "B.Cu")
		(net "PE_TX2_DR1_P")
	)
	(via
		(at 6.992366 -391.14857)
		(size 0.508)
		(drill 0.254)
		(layers "F.Cu" "B.Cu")
		(net "PE_TX2_DR1_P")
	)
	(segment
		(start 8.342122 -391.047224)
		(end 9.035542 -391.532872)
		(width 0.1651)
		(layer "In5.Cu")
		(net "PE_TX2_DR1_P")
	)
	(segment
		(start 9.035542 -391.532872)
		(end 12.13231 -395.955012)
		(width 0.1651)
		(layer "In5.Cu")
		(net "PE_TX2_DR1_P")
	)
	(segment
		(start 7.220966 -390.91997)
		(end 7.62 -390.91997)
		(width 0.1651)
		(layer "In5.Cu")
		(net "PE_TX2_DR1_P")
	)
	(segment
		(start 45.353986 -407.398728)
		(end 217.919808 -376.971814)
		(width 0.1651)
		(layer "In5.Cu")
		(net "PE_TX2_DR1_P")
	)
	(segment
		(start 12.13231 -395.955012)
		(end 22.912832 -403.503892)
		(width 0.1651)
		(layer "In5.Cu")
		(net "PE_TX2_DR1_P")
	)
	(segment
		(start 6.992366 -391.14857)
		(end 7.220966 -390.91997)
		(width 0.1651)
		(layer "In5.Cu")
		(net "PE_TX2_DR1_P")
	)
	(segment
		(start 22.912832 -403.503892)
		(end 45.009816 -407.398728)
		(width 0.1651)
		(layer "In5.Cu")
		(net "PE_TX2_DR1_P")
	)
	(segment
		(start 217.964004 -376.968004)
		(end 220.101414 -376.968004)
		(width 0.1651)
		(layer "In5.Cu")
		(net "PE_TX2_DR1_P")
	)
	(segment
		(start 7.62 -390.91997)
		(end 8.342122 -391.047224)
		(width 0.1651)
		(layer "In5.Cu")
		(net "PE_TX2_DR1_P")
	)
	(segment
		(start 220.101414 -376.968004)
		(end 220.330014 -377.196604)
		(width 0.1651)
		(layer "In5.Cu")
		(net "PE_TX2_DR1_P")
	)
	(arc
		(start 217.919808 -376.971814)
		(mid 217.941822 -376.968933)
		(end 217.964004 -376.968004)
		(width 0.1651)
		(layer "In5.Cu")
		(net "PE_TX2_DR1_P")
	)
	(arc
		(start 45.009816 -407.398728)
		(mid 45.181903 -407.413811)
		(end 45.353986 -407.398728)
		(width 0.1651)
		(layer "In5.Cu")
		(net "PE_TX2_DR1_P")
	)
	(segment
		(start 6.738874 -390.589262)
		(end 6.992366 -390.33577)
		(width 0.174752)
		(layer "F.Cu")
		(net "PE_TX2_DR1_N")
	)
	(segment
		(start 222.885 -376.63755)
		(end 220.58376 -376.63755)
		(width 0.174752)
		(layer "F.Cu")
		(net "PE_TX2_DR1_N")
	)
	(segment
		(start 223.132396 -376.390154)
		(end 222.885 -376.63755)
		(width 0.174752)
		(layer "F.Cu")
		(net "PE_TX2_DR1_N")
	)
	(segment
		(start 3.658108 -390.341866)
		(end 3.905504 -390.589262)
		(width 0.174752)
		(layer "F.Cu")
		(net "PE_TX2_DR1_N")
	)
	(segment
		(start 220.58376 -376.63755)
		(end 220.330014 -376.383804)
		(width 0.174752)
		(layer "F.Cu")
		(net "PE_TX2_DR1_N")
	)
	(segment
		(start 3.905504 -390.589262)
		(end 6.738874 -390.589262)
		(width 0.174752)
		(layer "F.Cu")
		(net "PE_TX2_DR1_N")
	)
	(segment
		(start 2.249932 -390.341866)
		(end 3.658108 -390.341866)
		(width 0.174752)
		(layer "F.Cu")
		(net "PE_TX2_DR1_N")
	)
	(segment
		(start 224.199958 -376.390154)
		(end 223.132396 -376.390154)
		(width 0.174752)
		(layer "F.Cu")
		(net "PE_TX2_DR1_N")
	)
	(via
		(at 6.992366 -390.33577)
		(size 0.508)
		(drill 0.254)
		(layers "F.Cu" "B.Cu")
		(net "PE_TX2_DR1_N")
	)
	(via
		(at 220.330014 -376.383804)
		(size 0.508)
		(drill 0.254)
		(layers "F.Cu" "B.Cu")
		(net "PE_TX2_DR1_N")
	)
	(segment
		(start 7.220966 -390.56437)
		(end 7.651242 -390.56437)
		(width 0.1651)
		(layer "In5.Cu")
		(net "PE_TX2_DR1_N")
	)
	(segment
		(start 9.291066 -391.277348)
		(end 12.387834 -395.699488)
		(width 0.1651)
		(layer "In5.Cu")
		(net "PE_TX2_DR1_N")
	)
	(segment
		(start 220.101414 -376.612404)
		(end 220.330014 -376.383804)
		(width 0.1651)
		(layer "In5.Cu")
		(net "PE_TX2_DR1_N")
	)
	(segment
		(start 6.992366 -390.33577)
		(end 7.220966 -390.56437)
		(width 0.1651)
		(layer "In5.Cu")
		(net "PE_TX2_DR1_N")
	)
	(segment
		(start 23.052278 -403.167342)
		(end 45.071538 -407.048462)
		(width 0.1651)
		(layer "In5.Cu")
		(net "PE_TX2_DR1_N")
	)
	(segment
		(start 217.963496 -376.612404)
		(end 220.101414 -376.612404)
		(width 0.1651)
		(layer "In5.Cu")
		(net "PE_TX2_DR1_N")
	)
	(segment
		(start 45.29201 -407.048462)
		(end 217.857578 -376.621548)
		(width 0.1651)
		(layer "In5.Cu")
		(net "PE_TX2_DR1_N")
	)
	(segment
		(start 12.387834 -395.699488)
		(end 23.052278 -403.167342)
		(width 0.1651)
		(layer "In5.Cu")
		(net "PE_TX2_DR1_N")
	)
	(segment
		(start 7.651242 -390.56437)
		(end 8.481568 -390.710674)
		(width 0.1651)
		(layer "In5.Cu")
		(net "PE_TX2_DR1_N")
	)
	(segment
		(start 8.481568 -390.710674)
		(end 9.291066 -391.277348)
		(width 0.1651)
		(layer "In5.Cu")
		(net "PE_TX2_DR1_N")
	)
	(arc
		(start 217.857578 -376.621548)
		(mid 217.910337 -376.614666)
		(end 217.963496 -376.612404)
		(width 0.1651)
		(layer "In5.Cu")
		(net "PE_TX2_DR1_N")
	)
	(arc
		(start 45.071538 -407.048462)
		(mid 45.181774 -407.058104)
		(end 45.29201 -407.048462)
		(width 0.1651)
		(layer "In5.Cu")
		(net "PE_TX2_DR1_N")
	)
	(segment
		(start 6.7183 -425.323)
		(end 3.877056 -425.323)
		(width 0.174752)
		(layer "F.Cu")
		(net "PE_TX2_DR0_P")
	)
	(segment
		(start 220.584014 -479.942652)
		(end 220.330014 -480.196652)
		(width 0.174752)
		(layer "F.Cu")
		(net "PE_TX2_DR0_P")
	)
	(segment
		(start 222.885 -479.942652)
		(end 220.584014 -479.942652)
		(width 0.174752)
		(layer "F.Cu")
		(net "PE_TX2_DR0_P")
	)
	(segment
		(start 3.877056 -425.323)
		(end 3.658108 -425.541948)
		(width 0.174752)
		(layer "F.Cu")
		(net "PE_TX2_DR0_P")
	)
	(segment
		(start 6.992366 -425.597066)
		(end 6.7183 -425.323)
		(width 0.174752)
		(layer "F.Cu")
		(net "PE_TX2_DR0_P")
	)
	(segment
		(start 223.132396 -480.190048)
		(end 222.885 -479.942652)
		(width 0.174752)
		(layer "F.Cu")
		(net "PE_TX2_DR0_P")
	)
	(segment
		(start 224.199958 -480.190048)
		(end 223.132396 -480.190048)
		(width 0.174752)
		(layer "F.Cu")
		(net "PE_TX2_DR0_P")
	)
	(segment
		(start 3.658108 -425.541948)
		(end 2.249932 -425.541948)
		(width 0.174752)
		(layer "F.Cu")
		(net "PE_TX2_DR0_P")
	)
	(via
		(at 220.330014 -480.196652)
		(size 0.508)
		(drill 0.254)
		(layers "F.Cu" "B.Cu")
		(net "PE_TX2_DR0_P")
	)
	(via
		(at 6.992366 -425.597066)
		(size 0.508)
		(drill 0.254)
		(layers "F.Cu" "B.Cu")
		(net "PE_TX2_DR0_P")
	)
	(segment
		(start 35.651694 -445.403732)
		(end 39.68623 -442.578744)
		(width 0.1651)
		(layer "In5.Cu")
		(net "PE_TX2_DR0_P")
	)
	(segment
		(start 21.837904 -456.042268)
		(end 23.358602 -456.310492)
		(width 0.1651)
		(layer "In5.Cu")
		(net "PE_TX2_DR0_P")
	)
	(segment
		(start 41.86936 -442.193426)
		(end 41.86936 -442.19368)
		(width 0.1651)
		(layer "In5.Cu")
		(net "PE_TX2_DR0_P")
	)
	(segment
		(start 16.885412 -452.246492)
		(end 19.050508 -453.76211)
		(width 0.1651)
		(layer "In5.Cu")
		(net "PE_TX2_DR0_P")
	)
	(segment
		(start 19.050508 -453.76211)
		(end 19.502882 -454.408032)
		(width 0.1651)
		(layer "In5.Cu")
		(net "PE_TX2_DR0_P")
	)
	(segment
		(start 41.869614 -442.193426)
		(end 201.200258 -470.302844)
		(width 0.1651)
		(layer "In5.Cu")
		(net "PE_TX2_DR0_P")
	)
	(segment
		(start 15.113 -449.71462)
		(end 16.885412 -452.246492)
		(width 0.1651)
		(layer "In5.Cu")
		(net "PE_TX2_DR0_P")
	)
	(segment
		(start 220.091762 -479.9584)
		(end 220.330014 -480.196652)
		(width 0.1651)
		(layer "In5.Cu")
		(net "PE_TX2_DR0_P")
	)
	(segment
		(start 6.992366 -425.597066)
		(end 7.220966 -425.368466)
		(width 0.1651)
		(layer "In5.Cu")
		(net "PE_TX2_DR0_P")
	)
	(segment
		(start 11.123422 -427.09084)
		(end 11.123676 -427.091348)
		(width 0.1651)
		(layer "In5.Cu")
		(net "PE_TX2_DR0_P")
	)
	(segment
		(start 35.495484 -445.559688)
		(end 35.495738 -445.559688)
		(width 0.1651)
		(layer "In5.Cu")
		(net "PE_TX2_DR0_P")
	)
	(segment
		(start 41.86936 -442.19368)
		(end 41.869614 -442.193426)
		(width 0.1651)
		(layer "In5.Cu")
		(net "PE_TX2_DR0_P")
	)
	(segment
		(start 27.271218 -455.620374)
		(end 29.583634 -454.001378)
		(width 0.1651)
		(layer "In5.Cu")
		(net "PE_TX2_DR0_P")
	)
	(segment
		(start 11.123676 -427.091348)
		(end 15.113 -449.71462)
		(width 0.1651)
		(layer "In5.Cu")
		(net "PE_TX2_DR0_P")
	)
	(segment
		(start 7.220966 -425.368466)
		(end 8.705342 -425.368466)
		(width 0.1651)
		(layer "In5.Cu")
		(net "PE_TX2_DR0_P")
	)
	(segment
		(start 10.436098 -426.108622)
		(end 11.123422 -427.09084)
		(width 0.1651)
		(layer "In5.Cu")
		(net "PE_TX2_DR0_P")
	)
	(segment
		(start 214.52459 -479.632264)
		(end 216.37498 -479.9584)
		(width 0.1651)
		(layer "In5.Cu")
		(net "PE_TX2_DR0_P")
	)
	(segment
		(start 8.705342 -425.368466)
		(end 9.607042 -425.527724)
		(width 0.1651)
		(layer "In5.Cu")
		(net "PE_TX2_DR0_P")
	)
	(segment
		(start 29.583634 -454.001378)
		(end 35.495484 -445.559688)
		(width 0.1651)
		(layer "In5.Cu")
		(net "PE_TX2_DR0_P")
	)
	(segment
		(start 19.502882 -454.408032)
		(end 21.837904 -456.042268)
		(width 0.1651)
		(layer "In5.Cu")
		(net "PE_TX2_DR0_P")
	)
	(segment
		(start 9.607042 -425.527724)
		(end 10.436098 -426.108622)
		(width 0.1651)
		(layer "In5.Cu")
		(net "PE_TX2_DR0_P")
	)
	(segment
		(start 23.358602 -456.310492)
		(end 27.271218 -455.620374)
		(width 0.1651)
		(layer "In5.Cu")
		(net "PE_TX2_DR0_P")
	)
	(segment
		(start 216.37498 -479.9584)
		(end 220.091762 -479.9584)
		(width 0.1651)
		(layer "In5.Cu")
		(net "PE_TX2_DR0_P")
	)
	(segment
		(start 201.200258 -470.302844)
		(end 214.52459 -479.632264)
		(width 0.1651)
		(layer "In5.Cu")
		(net "PE_TX2_DR0_P")
	)
	(segment
		(start 39.68623 -442.578744)
		(end 41.86936 -442.193426)
		(width 0.1651)
		(layer "In5.Cu")
		(net "PE_TX2_DR0_P")
	)
	(arc
		(start 35.495738 -445.559688)
		(mid 35.566893 -445.474887)
		(end 35.651694 -445.403732)
		(width 0.1651)
		(layer "In5.Cu")
		(net "PE_TX2_DR0_P")
	)
	(segment
		(start 3.933952 -425.017946)
		(end 3.657854 -424.741848)
		(width 0.174752)
		(layer "F.Cu")
		(net "PE_TX2_DR0_N")
	)
	(segment
		(start 3.657854 -424.741848)
		(end 2.249932 -424.741848)
		(width 0.174752)
		(layer "F.Cu")
		(net "PE_TX2_DR0_N")
	)
	(segment
		(start 223.139 -479.390202)
		(end 222.891604 -479.637598)
		(width 0.174752)
		(layer "F.Cu")
		(net "PE_TX2_DR0_N")
	)
	(segment
		(start 222.891604 -479.637598)
		(end 220.58376 -479.637598)
		(width 0.174752)
		(layer "F.Cu")
		(net "PE_TX2_DR0_N")
	)
	(segment
		(start 6.758686 -425.017946)
		(end 3.933952 -425.017946)
		(width 0.174752)
		(layer "F.Cu")
		(net "PE_TX2_DR0_N")
	)
	(segment
		(start 220.58376 -479.637598)
		(end 220.330014 -479.383852)
		(width 0.174752)
		(layer "F.Cu")
		(net "PE_TX2_DR0_N")
	)
	(segment
		(start 224.199958 -479.390202)
		(end 223.139 -479.390202)
		(width 0.174752)
		(layer "F.Cu")
		(net "PE_TX2_DR0_N")
	)
	(segment
		(start 6.992366 -424.784266)
		(end 6.758686 -425.017946)
		(width 0.174752)
		(layer "F.Cu")
		(net "PE_TX2_DR0_N")
	)
	(via
		(at 220.330014 -479.383852)
		(size 0.508)
		(drill 0.254)
		(layers "F.Cu" "B.Cu")
		(net "PE_TX2_DR0_N")
	)
	(via
		(at 6.992366 -424.784266)
		(size 0.508)
		(drill 0.254)
		(layers "F.Cu" "B.Cu")
		(net "PE_TX2_DR0_N")
	)
	(segment
		(start 35.447986 -445.111886)
		(end 39.547038 -442.24194)
		(width 0.1651)
		(layer "In5.Cu")
		(net "PE_TX2_DR0_N")
	)
	(segment
		(start 6.992366 -424.784266)
		(end 7.220966 -425.012866)
		(width 0.1651)
		(layer "In5.Cu")
		(net "PE_TX2_DR0_N")
	)
	(segment
		(start 9.746488 -425.191174)
		(end 10.691622 -425.853352)
		(width 0.1651)
		(layer "In5.Cu")
		(net "PE_TX2_DR0_N")
	)
	(segment
		(start 17.140936 -451.990968)
		(end 19.306032 -453.506586)
		(width 0.1651)
		(layer "In5.Cu")
		(net "PE_TX2_DR0_N")
	)
	(segment
		(start 35.204146 -445.355726)
		(end 35.204654 -445.354964)
		(width 0.1651)
		(layer "In5.Cu")
		(net "PE_TX2_DR0_N")
	)
	(segment
		(start 19.758406 -454.152508)
		(end 21.97735 -455.705718)
		(width 0.1651)
		(layer "In5.Cu")
		(net "PE_TX2_DR0_N")
	)
	(segment
		(start 39.547038 -442.24194)
		(end 41.869614 -441.832238)
		(width 0.1651)
		(layer "In5.Cu")
		(net "PE_TX2_DR0_N")
	)
	(segment
		(start 29.32811 -453.745854)
		(end 35.204146 -445.355726)
		(width 0.1651)
		(layer "In5.Cu")
		(net "PE_TX2_DR0_N")
	)
	(segment
		(start 7.220966 -425.012866)
		(end 8.736584 -425.012866)
		(width 0.1651)
		(layer "In5.Cu")
		(net "PE_TX2_DR0_N")
	)
	(segment
		(start 23.358602 -455.949304)
		(end 27.131772 -455.283824)
		(width 0.1651)
		(layer "In5.Cu")
		(net "PE_TX2_DR0_N")
	)
	(segment
		(start 19.306032 -453.506586)
		(end 19.758406 -454.152508)
		(width 0.1651)
		(layer "In5.Cu")
		(net "PE_TX2_DR0_N")
	)
	(segment
		(start 8.736584 -425.012866)
		(end 9.746488 -425.191174)
		(width 0.1651)
		(layer "In5.Cu")
		(net "PE_TX2_DR0_N")
	)
	(segment
		(start 216.406222 -479.6028)
		(end 220.111066 -479.6028)
		(width 0.1651)
		(layer "In5.Cu")
		(net "PE_TX2_DR0_N")
	)
	(segment
		(start 214.664036 -479.295714)
		(end 216.406222 -479.6028)
		(width 0.1651)
		(layer "In5.Cu")
		(net "PE_TX2_DR0_N")
	)
	(segment
		(start 15.44955 -449.575174)
		(end 17.140936 -451.990968)
		(width 0.1651)
		(layer "In5.Cu")
		(net "PE_TX2_DR0_N")
	)
	(segment
		(start 41.869614 -441.831984)
		(end 201.339704 -469.966294)
		(width 0.1651)
		(layer "In5.Cu")
		(net "PE_TX2_DR0_N")
	)
	(segment
		(start 21.97735 -455.705718)
		(end 23.358602 -455.949304)
		(width 0.1651)
		(layer "In5.Cu")
		(net "PE_TX2_DR0_N")
	)
	(segment
		(start 220.111066 -479.6028)
		(end 220.330014 -479.383852)
		(width 0.1651)
		(layer "In5.Cu")
		(net "PE_TX2_DR0_N")
	)
	(segment
		(start 10.691622 -425.853352)
		(end 11.460226 -426.951394)
		(width 0.1651)
		(layer "In5.Cu")
		(net "PE_TX2_DR0_N")
	)
	(segment
		(start 27.131772 -455.283824)
		(end 29.32811 -453.745854)
		(width 0.1651)
		(layer "In5.Cu")
		(net "PE_TX2_DR0_N")
	)
	(segment
		(start 11.460226 -426.951394)
		(end 15.44955 -449.575174)
		(width 0.1651)
		(layer "In5.Cu")
		(net "PE_TX2_DR0_N")
	)
	(segment
		(start 201.339704 -469.966294)
		(end 214.664036 -479.295714)
		(width 0.1651)
		(layer "In5.Cu")
		(net "PE_TX2_DR0_N")
	)
	(segment
		(start 41.869614 -441.832238)
		(end 41.869614 -441.831984)
		(width 0.1651)
		(layer "In5.Cu")
		(net "PE_TX2_DR0_N")
	)
	(arc
		(start 35.204654 -445.354964)
		(mid 35.315702 -445.222799)
		(end 35.447986 -445.111886)
		(width 0.1651)
		(layer "In5.Cu")
		(net "PE_TX2_DR0_N")
	)
	(segment
		(start 38.093396 -55.390034)
		(end 37.846 -55.142638)
		(width 0.174752)
		(layer "F.Cu")
		(net "PE_TX1_DR9_P")
	)
	(segment
		(start 37.846 -55.142638)
		(end 35.583876 -55.142638)
		(width 0.174752)
		(layer "F.Cu")
		(net "PE_TX1_DR9_P")
	)
	(segment
		(start 39.200074 -55.390034)
		(end 38.093396 -55.390034)
		(width 0.174752)
		(layer "F.Cu")
		(net "PE_TX1_DR9_P")
	)
	(segment
		(start 3.657854 -182.342028)
		(end 3.905504 -182.094378)
		(width 0.174752)
		(layer "F.Cu")
		(net "PE_TX1_DR9_P")
	)
	(segment
		(start 6.738112 -182.094378)
		(end 6.992366 -182.348632)
		(width 0.174752)
		(layer "F.Cu")
		(net "PE_TX1_DR9_P")
	)
	(segment
		(start 3.905504 -182.094378)
		(end 6.738112 -182.094378)
		(width 0.174752)
		(layer "F.Cu")
		(net "PE_TX1_DR9_P")
	)
	(segment
		(start 2.249932 -182.342028)
		(end 3.657854 -182.342028)
		(width 0.174752)
		(layer "F.Cu")
		(net "PE_TX1_DR9_P")
	)
	(segment
		(start 35.583876 -55.142638)
		(end 35.33013 -55.396384)
		(width 0.174752)
		(layer "F.Cu")
		(net "PE_TX1_DR9_P")
	)
	(via
		(at 35.33013 -55.396384)
		(size 0.508)
		(drill 0.254)
		(layers "F.Cu" "B.Cu")
		(net "PE_TX1_DR9_P")
	)
	(via
		(at 6.992366 -182.348632)
		(size 0.508)
		(drill 0.254)
		(layers "F.Cu" "B.Cu")
		(net "PE_TX1_DR9_P")
	)
	(segment
		(start 42.003472 -103.083868)
		(end 39.673784 -101.452934)
		(width 0.1651)
		(layer "In5.Cu")
		(net "PE_TX1_DR9_P")
	)
	(segment
		(start 35.101784 -55.168038)
		(end 35.33013 -55.396384)
		(width 0.1651)
		(layer "In5.Cu")
		(net "PE_TX1_DR9_P")
	)
	(segment
		(start 42.963592 -106.170222)
		(end 42.55897 -103.877872)
		(width 0.1651)
		(layer "In5.Cu")
		(net "PE_TX1_DR9_P")
	)
	(segment
		(start 26.799794 -170.700954)
		(end 30.14091 -151.75103)
		(width 0.1651)
		(layer "In5.Cu")
		(net "PE_TX1_DR9_P")
	)
	(segment
		(start 33.849564 -55.25008)
		(end 34.3154 -55.168038)
		(width 0.1651)
		(layer "In5.Cu")
		(net "PE_TX1_DR9_P")
	)
	(segment
		(start 32.870394 -56.32069)
		(end 33.398714 -55.565802)
		(width 0.1651)
		(layer "In5.Cu")
		(net "PE_TX1_DR9_P")
	)
	(segment
		(start 19.135344 -89.1921)
		(end 19.934428 -84.661248)
		(width 0.1651)
		(layer "In5.Cu")
		(net "PE_TX1_DR9_P")
	)
	(segment
		(start 33.398714 -55.565802)
		(end 33.849564 -55.25008)
		(width 0.1651)
		(layer "In5.Cu")
		(net "PE_TX1_DR9_P")
	)
	(segment
		(start 39.673784 -101.452934)
		(end 23.967186 -98.683318)
		(width 0.1651)
		(layer "In5.Cu")
		(net "PE_TX1_DR9_P")
	)
	(segment
		(start 30.545532 -69.506592)
		(end 32.870394 -56.32069)
		(width 0.1651)
		(layer "In5.Cu")
		(net "PE_TX1_DR9_P")
	)
	(segment
		(start 39.749984 -115.102132)
		(end 41.940226 -111.974122)
		(width 0.1651)
		(layer "In5.Cu")
		(net "PE_TX1_DR9_P")
	)
	(segment
		(start 30.14091 -151.75103)
		(end 34.350706 -145.74266)
		(width 0.1651)
		(layer "In5.Cu")
		(net "PE_TX1_DR9_P")
	)
	(segment
		(start 15.265908 -180.782976)
		(end 24.044402 -174.63643)
		(width 0.1651)
		(layer "In5.Cu")
		(net "PE_TX1_DR9_P")
	)
	(segment
		(start 41.940226 -111.974122)
		(end 42.963592 -106.170222)
		(width 0.1651)
		(layer "In5.Cu")
		(net "PE_TX1_DR9_P")
	)
	(segment
		(start 42.55897 -103.877872)
		(end 42.003472 -103.083868)
		(width 0.1651)
		(layer "In5.Cu")
		(net "PE_TX1_DR9_P")
	)
	(segment
		(start 20.001992 -94.104206)
		(end 19.135344 -89.1921)
		(width 0.1651)
		(layer "In5.Cu")
		(net "PE_TX1_DR9_P")
	)
	(segment
		(start 34.3154 -55.168038)
		(end 35.101784 -55.168038)
		(width 0.1651)
		(layer "In5.Cu")
		(net "PE_TX1_DR9_P")
	)
	(segment
		(start 39.750238 -115.102386)
		(end 39.749984 -115.102132)
		(width 0.1651)
		(layer "In5.Cu")
		(net "PE_TX1_DR9_P")
	)
	(segment
		(start 23.967186 -98.683318)
		(end 22.478492 -97.640902)
		(width 0.1651)
		(layer "In5.Cu")
		(net "PE_TX1_DR9_P")
	)
	(segment
		(start 19.934428 -84.661248)
		(end 30.545532 -69.506592)
		(width 0.1651)
		(layer "In5.Cu")
		(net "PE_TX1_DR9_P")
	)
	(segment
		(start 7.682484 -182.120032)
		(end 15.265908 -180.782976)
		(width 0.1651)
		(layer "In5.Cu")
		(net "PE_TX1_DR9_P")
	)
	(segment
		(start 6.992366 -182.348632)
		(end 7.220966 -182.120032)
		(width 0.1651)
		(layer "In5.Cu")
		(net "PE_TX1_DR9_P")
	)
	(segment
		(start 7.220966 -182.120032)
		(end 7.682484 -182.120032)
		(width 0.1651)
		(layer "In5.Cu")
		(net "PE_TX1_DR9_P")
	)
	(segment
		(start 24.044402 -174.63643)
		(end 26.799794 -170.700954)
		(width 0.1651)
		(layer "In5.Cu")
		(net "PE_TX1_DR9_P")
	)
	(segment
		(start 34.350706 -145.74266)
		(end 39.750238 -115.102386)
		(width 0.1651)
		(layer "In5.Cu")
		(net "PE_TX1_DR9_P")
	)
	(segment
		(start 22.478492 -97.640902)
		(end 20.001992 -94.104206)
		(width 0.1651)
		(layer "In5.Cu")
		(net "PE_TX1_DR9_P")
	)
	(segment
		(start 3.905504 -181.789324)
		(end 6.738874 -181.789324)
		(width 0.174752)
		(layer "F.Cu")
		(net "PE_TX1_DR9_N")
	)
	(segment
		(start 2.249932 -181.542182)
		(end 3.658362 -181.542182)
		(width 0.174752)
		(layer "F.Cu")
		(net "PE_TX1_DR9_N")
	)
	(segment
		(start 3.658362 -181.542182)
		(end 3.905504 -181.789324)
		(width 0.174752)
		(layer "F.Cu")
		(net "PE_TX1_DR9_N")
	)
	(segment
		(start 6.738874 -181.789324)
		(end 6.992366 -181.535832)
		(width 0.174752)
		(layer "F.Cu")
		(net "PE_TX1_DR9_N")
	)
	(segment
		(start 38.09365 -54.589934)
		(end 37.846 -54.837584)
		(width 0.174752)
		(layer "F.Cu")
		(net "PE_TX1_DR9_N")
	)
	(segment
		(start 39.200074 -54.589934)
		(end 38.09365 -54.589934)
		(width 0.174752)
		(layer "F.Cu")
		(net "PE_TX1_DR9_N")
	)
	(segment
		(start 37.846 -54.837584)
		(end 35.58413 -54.837584)
		(width 0.174752)
		(layer "F.Cu")
		(net "PE_TX1_DR9_N")
	)
	(segment
		(start 35.58413 -54.837584)
		(end 35.33013 -54.583584)
		(width 0.174752)
		(layer "F.Cu")
		(net "PE_TX1_DR9_N")
	)
	(via
		(at 35.33013 -54.583584)
		(size 0.508)
		(drill 0.254)
		(layers "F.Cu" "B.Cu")
		(net "PE_TX1_DR9_N")
	)
	(via
		(at 6.992366 -181.535832)
		(size 0.508)
		(drill 0.254)
		(layers "F.Cu" "B.Cu")
		(net "PE_TX1_DR9_N")
	)
	(segment
		(start 41.603676 -111.834676)
		(end 42.602404 -106.170222)
		(width 0.1651)
		(layer "In5.Cu")
		(net "PE_TX1_DR9_N")
	)
	(segment
		(start 30.208982 -69.367146)
		(end 32.533844 -56.18099)
		(width 0.1651)
		(layer "In5.Cu")
		(net "PE_TX1_DR9_N")
	)
	(segment
		(start 7.220966 -181.764432)
		(end 7.651242 -181.764432)
		(width 0.1651)
		(layer "In5.Cu")
		(net "PE_TX1_DR9_N")
	)
	(segment
		(start 7.651242 -181.764432)
		(end 15.126462 -180.446426)
		(width 0.1651)
		(layer "In5.Cu")
		(net "PE_TX1_DR9_N")
	)
	(segment
		(start 6.992366 -181.535832)
		(end 7.220966 -181.764432)
		(width 0.1651)
		(layer "In5.Cu")
		(net "PE_TX1_DR9_N")
	)
	(segment
		(start 19.665442 -94.243652)
		(end 18.774156 -89.1921)
		(width 0.1651)
		(layer "In5.Cu")
		(net "PE_TX1_DR9_N")
	)
	(segment
		(start 19.597878 -84.521802)
		(end 30.208982 -69.367146)
		(width 0.1651)
		(layer "In5.Cu")
		(net "PE_TX1_DR9_N")
	)
	(segment
		(start 33.710118 -54.91353)
		(end 34.284158 -54.812438)
		(width 0.1651)
		(layer "In5.Cu")
		(net "PE_TX1_DR9_N")
	)
	(segment
		(start 34.014156 -145.603214)
		(end 39.413688 -114.962178)
		(width 0.1651)
		(layer "In5.Cu")
		(net "PE_TX1_DR9_N")
	)
	(segment
		(start 15.126462 -180.446426)
		(end 23.788878 -174.380906)
		(width 0.1651)
		(layer "In5.Cu")
		(net "PE_TX1_DR9_N")
	)
	(segment
		(start 29.80436 -151.611584)
		(end 34.014156 -145.603214)
		(width 0.1651)
		(layer "In5.Cu")
		(net "PE_TX1_DR9_N")
	)
	(segment
		(start 39.413688 -114.962178)
		(end 41.603676 -111.834676)
		(width 0.1651)
		(layer "In5.Cu")
		(net "PE_TX1_DR9_N")
	)
	(segment
		(start 32.736282 -55.891938)
		(end 33.14319 -55.310278)
		(width 0.1651)
		(layer "In5.Cu")
		(net "PE_TX1_DR9_N")
	)
	(segment
		(start 22.222968 -97.896426)
		(end 19.665442 -94.243652)
		(width 0.1651)
		(layer "In5.Cu")
		(net "PE_TX1_DR9_N")
	)
	(segment
		(start 35.101276 -54.812438)
		(end 35.33013 -54.583584)
		(width 0.1651)
		(layer "In5.Cu")
		(net "PE_TX1_DR9_N")
	)
	(segment
		(start 23.82774 -99.019868)
		(end 22.222968 -97.896426)
		(width 0.1651)
		(layer "In5.Cu")
		(net "PE_TX1_DR9_N")
	)
	(segment
		(start 32.533844 -56.18099)
		(end 32.736282 -55.891938)
		(width 0.1651)
		(layer "In5.Cu")
		(net "PE_TX1_DR9_N")
	)
	(segment
		(start 33.14319 -55.310278)
		(end 33.710118 -54.91353)
		(width 0.1651)
		(layer "In5.Cu")
		(net "PE_TX1_DR9_N")
	)
	(segment
		(start 23.788878 -174.380906)
		(end 26.463244 -170.561508)
		(width 0.1651)
		(layer "In5.Cu")
		(net "PE_TX1_DR9_N")
	)
	(segment
		(start 39.534338 -101.789484)
		(end 23.82774 -99.019868)
		(width 0.1651)
		(layer "In5.Cu")
		(net "PE_TX1_DR9_N")
	)
	(segment
		(start 42.602404 -106.170222)
		(end 42.22242 -104.017318)
		(width 0.1651)
		(layer "In5.Cu")
		(net "PE_TX1_DR9_N")
	)
	(segment
		(start 41.747948 -103.339392)
		(end 39.534338 -101.789484)
		(width 0.1651)
		(layer "In5.Cu")
		(net "PE_TX1_DR9_N")
	)
	(segment
		(start 34.284158 -54.812438)
		(end 35.101276 -54.812438)
		(width 0.1651)
		(layer "In5.Cu")
		(net "PE_TX1_DR9_N")
	)
	(segment
		(start 18.774156 -89.1921)
		(end 19.597878 -84.521802)
		(width 0.1651)
		(layer "In5.Cu")
		(net "PE_TX1_DR9_N")
	)
	(segment
		(start 42.22242 -104.017318)
		(end 41.747948 -103.339392)
		(width 0.1651)
		(layer "In5.Cu")
		(net "PE_TX1_DR9_N")
	)
	(segment
		(start 26.463244 -170.561508)
		(end 29.80436 -151.611584)
		(width 0.1651)
		(layer "In5.Cu")
		(net "PE_TX1_DR9_N")
	)
	(segment
		(start 39.200074 -158.390082)
		(end 38.093396 -158.390082)
		(width 0.174752)
		(layer "F.Cu")
		(net "PE_TX1_DR8_P")
	)
	(segment
		(start 37.846 -158.142686)
		(end 35.583876 -158.142686)
		(width 0.174752)
		(layer "F.Cu")
		(net "PE_TX1_DR8_P")
	)
	(segment
		(start 3.905504 -202.094338)
		(end 6.738112 -202.094338)
		(width 0.174752)
		(layer "F.Cu")
		(net "PE_TX1_DR8_P")
	)
	(segment
		(start 35.583876 -158.142686)
		(end 35.33013 -158.396432)
		(width 0.174752)
		(layer "F.Cu")
		(net "PE_TX1_DR8_P")
	)
	(segment
		(start 6.738112 -202.094338)
		(end 6.992366 -202.348592)
		(width 0.174752)
		(layer "F.Cu")
		(net "PE_TX1_DR8_P")
	)
	(segment
		(start 38.093396 -158.390082)
		(end 37.846 -158.142686)
		(width 0.174752)
		(layer "F.Cu")
		(net "PE_TX1_DR8_P")
	)
	(segment
		(start 2.249932 -202.341988)
		(end 3.657854 -202.341988)
		(width 0.174752)
		(layer "F.Cu")
		(net "PE_TX1_DR8_P")
	)
	(segment
		(start 3.657854 -202.341988)
		(end 3.905504 -202.094338)
		(width 0.174752)
		(layer "F.Cu")
		(net "PE_TX1_DR8_P")
	)
	(via
		(at 35.33013 -158.396432)
		(size 0.508)
		(drill 0.254)
		(layers "F.Cu" "B.Cu")
		(net "PE_TX1_DR8_P")
	)
	(via
		(at 6.992366 -202.348592)
		(size 0.508)
		(drill 0.254)
		(layers "F.Cu" "B.Cu")
		(net "PE_TX1_DR8_P")
	)
	(segment
		(start 7.220966 -202.119992)
		(end 6.992366 -202.348592)
		(width 0.1651)
		(layer "In5.Cu")
		(net "PE_TX1_DR8_P")
	)
	(segment
		(start 35.33013 -158.396432)
		(end 35.101784 -158.168086)
		(width 0.1651)
		(layer "In5.Cu")
		(net "PE_TX1_DR8_P")
	)
	(segment
		(start 9.272524 -201.839576)
		(end 7.682484 -202.119992)
		(width 0.1651)
		(layer "In5.Cu")
		(net "PE_TX1_DR8_P")
	)
	(segment
		(start 11.68781 -200.148444)
		(end 11.687556 -200.148698)
		(width 0.1651)
		(layer "In5.Cu")
		(net "PE_TX1_DR8_P")
	)
	(segment
		(start 33.40354 -158.637224)
		(end 33.173416 -158.966154)
		(width 0.1651)
		(layer "In5.Cu")
		(net "PE_TX1_DR8_P")
	)
	(segment
		(start 32.771334 -161.245042)
		(end 33.15335 -163.411154)
		(width 0.1651)
		(layer "In5.Cu")
		(net "PE_TX1_DR8_P")
	)
	(segment
		(start 35.101784 -158.168086)
		(end 34.58591 -158.168086)
		(width 0.1651)
		(layer "In5.Cu")
		(net "PE_TX1_DR8_P")
	)
	(segment
		(start 33.173416 -158.966154)
		(end 32.771334 -161.245042)
		(width 0.1651)
		(layer "In5.Cu")
		(net "PE_TX1_DR8_P")
	)
	(segment
		(start 7.682484 -202.119992)
		(end 7.220966 -202.119992)
		(width 0.1651)
		(layer "In5.Cu")
		(net "PE_TX1_DR8_P")
	)
	(segment
		(start 11.687556 -200.148698)
		(end 9.272524 -201.839576)
		(width 0.1651)
		(layer "In5.Cu")
		(net "PE_TX1_DR8_P")
	)
	(segment
		(start 33.15335 -163.411154)
		(end 31.721044 -171.535852)
		(width 0.1651)
		(layer "In5.Cu")
		(net "PE_TX1_DR8_P")
	)
	(segment
		(start 33.90138 -158.288736)
		(end 33.40354 -158.637224)
		(width 0.1651)
		(layer "In5.Cu")
		(net "PE_TX1_DR8_P")
	)
	(segment
		(start 31.721044 -171.535852)
		(end 11.68781 -200.148444)
		(width 0.1651)
		(layer "In5.Cu")
		(net "PE_TX1_DR8_P")
	)
	(segment
		(start 34.58591 -158.168086)
		(end 33.90138 -158.288736)
		(width 0.1651)
		(layer "In5.Cu")
		(net "PE_TX1_DR8_P")
	)
	(segment
		(start 39.200074 -157.589982)
		(end 38.09365 -157.589982)
		(width 0.174752)
		(layer "F.Cu")
		(net "PE_TX1_DR8_N")
	)
	(segment
		(start 2.249932 -201.542142)
		(end 3.658362 -201.542142)
		(width 0.174752)
		(layer "F.Cu")
		(net "PE_TX1_DR8_N")
	)
	(segment
		(start 37.846 -157.837632)
		(end 35.58413 -157.837632)
		(width 0.174752)
		(layer "F.Cu")
		(net "PE_TX1_DR8_N")
	)
	(segment
		(start 6.738874 -201.789284)
		(end 6.992366 -201.535792)
		(width 0.174752)
		(layer "F.Cu")
		(net "PE_TX1_DR8_N")
	)
	(segment
		(start 38.09365 -157.589982)
		(end 37.846 -157.837632)
		(width 0.174752)
		(layer "F.Cu")
		(net "PE_TX1_DR8_N")
	)
	(segment
		(start 3.905504 -201.789284)
		(end 6.738874 -201.789284)
		(width 0.174752)
		(layer "F.Cu")
		(net "PE_TX1_DR8_N")
	)
	(segment
		(start 35.58413 -157.837632)
		(end 35.33013 -157.583632)
		(width 0.174752)
		(layer "F.Cu")
		(net "PE_TX1_DR8_N")
	)
	(segment
		(start 3.658362 -201.542142)
		(end 3.905504 -201.789284)
		(width 0.174752)
		(layer "F.Cu")
		(net "PE_TX1_DR8_N")
	)
	(via
		(at 35.33013 -157.583632)
		(size 0.508)
		(drill 0.254)
		(layers "F.Cu" "B.Cu")
		(net "PE_TX1_DR8_N")
	)
	(via
		(at 6.992366 -201.535792)
		(size 0.508)
		(drill 0.254)
		(layers "F.Cu" "B.Cu")
		(net "PE_TX1_DR8_N")
	)
	(segment
		(start 35.101276 -157.812486)
		(end 34.554668 -157.812486)
		(width 0.1651)
		(layer "In5.Cu")
		(net "PE_TX1_DR8_N")
	)
	(segment
		(start 11.432286 -199.89292)
		(end 9.133078 -201.503026)
		(width 0.1651)
		(layer "In5.Cu")
		(net "PE_TX1_DR8_N")
	)
	(segment
		(start 33.761934 -157.952186)
		(end 33.148016 -158.3817)
		(width 0.1651)
		(layer "In5.Cu")
		(net "PE_TX1_DR8_N")
	)
	(segment
		(start 31.384494 -171.396406)
		(end 11.432286 -199.89292)
		(width 0.1651)
		(layer "In5.Cu")
		(net "PE_TX1_DR8_N")
	)
	(segment
		(start 7.220966 -201.764392)
		(end 6.992366 -201.535792)
		(width 0.1651)
		(layer "In5.Cu")
		(net "PE_TX1_DR8_N")
	)
	(segment
		(start 33.148016 -158.3817)
		(end 32.836866 -158.826708)
		(width 0.1651)
		(layer "In5.Cu")
		(net "PE_TX1_DR8_N")
	)
	(segment
		(start 32.792162 -163.411154)
		(end 31.384494 -171.396406)
		(width 0.1651)
		(layer "In5.Cu")
		(net "PE_TX1_DR8_N")
	)
	(segment
		(start 32.410146 -161.245042)
		(end 32.792162 -163.411154)
		(width 0.1651)
		(layer "In5.Cu")
		(net "PE_TX1_DR8_N")
	)
	(segment
		(start 32.836866 -158.826708)
		(end 32.410146 -161.245042)
		(width 0.1651)
		(layer "In5.Cu")
		(net "PE_TX1_DR8_N")
	)
	(segment
		(start 34.554668 -157.812486)
		(end 33.761934 -157.952186)
		(width 0.1651)
		(layer "In5.Cu")
		(net "PE_TX1_DR8_N")
	)
	(segment
		(start 9.133078 -201.503026)
		(end 7.651242 -201.764392)
		(width 0.1651)
		(layer "In5.Cu")
		(net "PE_TX1_DR8_N")
	)
	(segment
		(start 35.33013 -157.583632)
		(end 35.101276 -157.812486)
		(width 0.1651)
		(layer "In5.Cu")
		(net "PE_TX1_DR8_N")
	)
	(segment
		(start 7.651242 -201.764392)
		(end 7.220966 -201.764392)
		(width 0.1651)
		(layer "In5.Cu")
		(net "PE_TX1_DR8_N")
	)
	(segment
		(start 37.846 -261.142734)
		(end 35.583876 -261.142734)
		(width 0.174752)
		(layer "F.Cu")
		(net "PE_TX1_DR7_P")
	)
	(segment
		(start 6.738112 -301.694342)
		(end 6.992366 -301.948596)
		(width 0.174752)
		(layer "F.Cu")
		(net "PE_TX1_DR7_P")
	)
	(segment
		(start 3.657854 -301.941992)
		(end 3.905504 -301.694342)
		(width 0.174752)
		(layer "F.Cu")
		(net "PE_TX1_DR7_P")
	)
	(segment
		(start 3.905504 -301.694342)
		(end 6.738112 -301.694342)
		(width 0.174752)
		(layer "F.Cu")
		(net "PE_TX1_DR7_P")
	)
	(segment
		(start 38.093396 -261.39013)
		(end 37.846 -261.142734)
		(width 0.174752)
		(layer "F.Cu")
		(net "PE_TX1_DR7_P")
	)
	(segment
		(start 2.249932 -301.941992)
		(end 3.657854 -301.941992)
		(width 0.174752)
		(layer "F.Cu")
		(net "PE_TX1_DR7_P")
	)
	(segment
		(start 35.583876 -261.142734)
		(end 35.33013 -261.39648)
		(width 0.174752)
		(layer "F.Cu")
		(net "PE_TX1_DR7_P")
	)
	(segment
		(start 39.200074 -261.39013)
		(end 38.093396 -261.39013)
		(width 0.174752)
		(layer "F.Cu")
		(net "PE_TX1_DR7_P")
	)
	(via
		(at 35.33013 -261.39648)
		(size 0.508)
		(drill 0.254)
		(layers "F.Cu" "B.Cu")
		(net "PE_TX1_DR7_P")
	)
	(via
		(at 6.992366 -301.948596)
		(size 0.508)
		(drill 0.254)
		(layers "F.Cu" "B.Cu")
		(net "PE_TX1_DR7_P")
	)
	(segment
		(start 7.682484 -301.719996)
		(end 7.220966 -301.719996)
		(width 0.1651)
		(layer "In5.Cu")
		(net "PE_TX1_DR7_P")
	)
	(segment
		(start 35.33013 -261.39648)
		(end 35.101784 -261.168134)
		(width 0.1651)
		(layer "In5.Cu")
		(net "PE_TX1_DR7_P")
	)
	(segment
		(start 32.126428 -262.518652)
		(end 29.765498 -275.904198)
		(width 0.1651)
		(layer "In5.Cu")
		(net "PE_TX1_DR7_P")
	)
	(segment
		(start 13.880084 -298.591478)
		(end 11.034268 -300.583854)
		(width 0.1651)
		(layer "In5.Cu")
		(net "PE_TX1_DR7_P")
	)
	(segment
		(start 32.749998 -261.629144)
		(end 32.126428 -262.518652)
		(width 0.1651)
		(layer "In5.Cu")
		(net "PE_TX1_DR7_P")
	)
	(segment
		(start 11.034268 -300.583854)
		(end 9.994138 -301.312326)
		(width 0.1651)
		(layer "In5.Cu")
		(net "PE_TX1_DR7_P")
	)
	(segment
		(start 29.765498 -275.904198)
		(end 13.880084 -298.591478)
		(width 0.1651)
		(layer "In5.Cu")
		(net "PE_TX1_DR7_P")
	)
	(segment
		(start 33.979358 -261.168134)
		(end 33.215834 -261.302754)
		(width 0.1651)
		(layer "In5.Cu")
		(net "PE_TX1_DR7_P")
	)
	(segment
		(start 35.101784 -261.168134)
		(end 33.979358 -261.168134)
		(width 0.1651)
		(layer "In5.Cu")
		(net "PE_TX1_DR7_P")
	)
	(segment
		(start 33.215834 -261.302754)
		(end 32.749998 -261.629144)
		(width 0.1651)
		(layer "In5.Cu")
		(net "PE_TX1_DR7_P")
	)
	(segment
		(start 9.994138 -301.312326)
		(end 7.682484 -301.719996)
		(width 0.1651)
		(layer "In5.Cu")
		(net "PE_TX1_DR7_P")
	)
	(segment
		(start 7.220966 -301.719996)
		(end 6.992366 -301.948596)
		(width 0.1651)
		(layer "In5.Cu")
		(net "PE_TX1_DR7_P")
	)
	(segment
		(start 2.249932 -301.142146)
		(end 3.658362 -301.142146)
		(width 0.174752)
		(layer "F.Cu")
		(net "PE_TX1_DR7_N")
	)
	(segment
		(start 3.658362 -301.142146)
		(end 3.905504 -301.389288)
		(width 0.174752)
		(layer "F.Cu")
		(net "PE_TX1_DR7_N")
	)
	(segment
		(start 35.58413 -260.83768)
		(end 35.33013 -260.58368)
		(width 0.174752)
		(layer "F.Cu")
		(net "PE_TX1_DR7_N")
	)
	(segment
		(start 37.846 -260.83768)
		(end 35.58413 -260.83768)
		(width 0.174752)
		(layer "F.Cu")
		(net "PE_TX1_DR7_N")
	)
	(segment
		(start 6.738874 -301.389288)
		(end 6.992366 -301.135796)
		(width 0.174752)
		(layer "F.Cu")
		(net "PE_TX1_DR7_N")
	)
	(segment
		(start 38.09365 -260.59003)
		(end 37.846 -260.83768)
		(width 0.174752)
		(layer "F.Cu")
		(net "PE_TX1_DR7_N")
	)
	(segment
		(start 3.905504 -301.389288)
		(end 6.738874 -301.389288)
		(width 0.174752)
		(layer "F.Cu")
		(net "PE_TX1_DR7_N")
	)
	(segment
		(start 39.200074 -260.59003)
		(end 38.09365 -260.59003)
		(width 0.174752)
		(layer "F.Cu")
		(net "PE_TX1_DR7_N")
	)
	(via
		(at 35.33013 -260.58368)
		(size 0.508)
		(drill 0.254)
		(layers "F.Cu" "B.Cu")
		(net "PE_TX1_DR7_N")
	)
	(via
		(at 6.992366 -301.135796)
		(size 0.508)
		(drill 0.254)
		(layers "F.Cu" "B.Cu")
		(net "PE_TX1_DR7_N")
	)
	(segment
		(start 33.076388 -260.966204)
		(end 32.494474 -261.37362)
		(width 0.1651)
		(layer "In5.Cu")
		(net "PE_TX1_DR7_N")
	)
	(segment
		(start 32.494474 -261.37362)
		(end 31.789878 -262.379206)
		(width 0.1651)
		(layer "In5.Cu")
		(net "PE_TX1_DR7_N")
	)
	(segment
		(start 35.101276 -260.812534)
		(end 33.948116 -260.812534)
		(width 0.1651)
		(layer "In5.Cu")
		(net "PE_TX1_DR7_N")
	)
	(segment
		(start 33.948116 -260.812534)
		(end 33.076388 -260.966204)
		(width 0.1651)
		(layer "In5.Cu")
		(net "PE_TX1_DR7_N")
	)
	(segment
		(start 9.854438 -300.975776)
		(end 7.651242 -301.364396)
		(width 0.1651)
		(layer "In5.Cu")
		(net "PE_TX1_DR7_N")
	)
	(segment
		(start 29.428948 -275.764752)
		(end 13.62456 -298.335954)
		(width 0.1651)
		(layer "In5.Cu")
		(net "PE_TX1_DR7_N")
	)
	(segment
		(start 13.62456 -298.335954)
		(end 10.862056 -300.270164)
		(width 0.1651)
		(layer "In5.Cu")
		(net "PE_TX1_DR7_N")
	)
	(segment
		(start 7.651242 -301.364396)
		(end 7.220966 -301.364396)
		(width 0.1651)
		(layer "In5.Cu")
		(net "PE_TX1_DR7_N")
	)
	(segment
		(start 31.789878 -262.379206)
		(end 29.428948 -275.764752)
		(width 0.1651)
		(layer "In5.Cu")
		(net "PE_TX1_DR7_N")
	)
	(segment
		(start 35.33013 -260.58368)
		(end 35.101276 -260.812534)
		(width 0.1651)
		(layer "In5.Cu")
		(net "PE_TX1_DR7_N")
	)
	(segment
		(start 10.862056 -300.270164)
		(end 9.854438 -300.975776)
		(width 0.1651)
		(layer "In5.Cu")
		(net "PE_TX1_DR7_N")
	)
	(segment
		(start 7.220966 -301.364396)
		(end 6.992366 -301.135796)
		(width 0.1651)
		(layer "In5.Cu")
		(net "PE_TX1_DR7_N")
	)
	(segment
		(start 3.657854 -347.542104)
		(end 3.905504 -347.294454)
		(width 0.174752)
		(layer "F.Cu")
		(net "PE_TX1_DR6_P")
	)
	(segment
		(start 2.249932 -347.542104)
		(end 3.657854 -347.542104)
		(width 0.174752)
		(layer "F.Cu")
		(net "PE_TX1_DR6_P")
	)
	(segment
		(start 37.846 -364.142782)
		(end 35.583876 -364.142782)
		(width 0.174752)
		(layer "F.Cu")
		(net "PE_TX1_DR6_P")
	)
	(segment
		(start 38.093396 -364.390178)
		(end 37.846 -364.142782)
		(width 0.174752)
		(layer "F.Cu")
		(net "PE_TX1_DR6_P")
	)
	(segment
		(start 3.905504 -347.294454)
		(end 6.738112 -347.294454)
		(width 0.174752)
		(layer "F.Cu")
		(net "PE_TX1_DR6_P")
	)
	(segment
		(start 6.738112 -347.294454)
		(end 6.992366 -347.548708)
		(width 0.174752)
		(layer "F.Cu")
		(net "PE_TX1_DR6_P")
	)
	(segment
		(start 35.583876 -364.142782)
		(end 35.33013 -364.396528)
		(width 0.174752)
		(layer "F.Cu")
		(net "PE_TX1_DR6_P")
	)
	(segment
		(start 39.200074 -364.390178)
		(end 38.093396 -364.390178)
		(width 0.174752)
		(layer "F.Cu")
		(net "PE_TX1_DR6_P")
	)
	(via
		(at 6.992366 -347.548708)
		(size 0.508)
		(drill 0.254)
		(layers "F.Cu" "B.Cu")
		(net "PE_TX1_DR6_P")
	)
	(via
		(at 35.33013 -364.396528)
		(size 0.508)
		(drill 0.254)
		(layers "F.Cu" "B.Cu")
		(net "PE_TX1_DR6_P")
	)
	(segment
		(start 8.44042 -347.4593)
		(end 7.651242 -347.320108)
		(width 0.1651)
		(layer "In5.Cu")
		(net "PE_TX1_DR6_P")
	)
	(segment
		(start 8.93572 -347.806264)
		(end 8.442452 -347.460824)
		(width 0.1651)
		(layer "In5.Cu")
		(net "PE_TX1_DR6_P")
	)
	(segment
		(start 13.794232 -354.74402)
		(end 11.364976 -351.274888)
		(width 0.1651)
		(layer "In5.Cu")
		(net "PE_TX1_DR6_P")
	)
	(segment
		(start 14.24813 -357.319834)
		(end 13.794232 -354.74402)
		(width 0.1651)
		(layer "In5.Cu")
		(net "PE_TX1_DR6_P")
	)
	(segment
		(start 16.041624 -359.881424)
		(end 14.24813 -357.319834)
		(width 0.1651)
		(layer "In5.Cu")
		(net "PE_TX1_DR6_P")
	)
	(segment
		(start 11.364976 -351.274888)
		(end 8.93572 -347.80601)
		(width 0.1651)
		(layer "In5.Cu")
		(net "PE_TX1_DR6_P")
	)
	(segment
		(start 35.33013 -364.396528)
		(end 35.101784 -364.168182)
		(width 0.1651)
		(layer "In5.Cu")
		(net "PE_TX1_DR6_P")
	)
	(segment
		(start 8.442452 -347.460824)
		(end 8.44042 -347.4593)
		(width 0.1651)
		(layer "In5.Cu")
		(net "PE_TX1_DR6_P")
	)
	(segment
		(start 18.21942 -361.405678)
		(end 16.041624 -359.881424)
		(width 0.1651)
		(layer "In5.Cu")
		(net "PE_TX1_DR6_P")
	)
	(segment
		(start 7.651242 -347.320108)
		(end 7.220966 -347.320108)
		(width 0.1651)
		(layer "In5.Cu")
		(net "PE_TX1_DR6_P")
	)
	(segment
		(start 7.220966 -347.320108)
		(end 6.992366 -347.548708)
		(width 0.1651)
		(layer "In5.Cu")
		(net "PE_TX1_DR6_P")
	)
	(segment
		(start 35.101784 -364.168182)
		(end 33.885632 -364.168182)
		(width 0.1651)
		(layer "In5.Cu")
		(net "PE_TX1_DR6_P")
	)
	(segment
		(start 33.885632 -364.168182)
		(end 18.21942 -361.405678)
		(width 0.1651)
		(layer "In5.Cu")
		(net "PE_TX1_DR6_P")
	)
	(segment
		(start 8.93572 -347.80601)
		(end 8.93572 -347.806264)
		(width 0.1651)
		(layer "In5.Cu")
		(net "PE_TX1_DR6_P")
	)
	(segment
		(start 2.249932 -346.742004)
		(end 3.658108 -346.742004)
		(width 0.174752)
		(layer "F.Cu")
		(net "PE_TX1_DR6_N")
	)
	(segment
		(start 3.658108 -346.742004)
		(end 3.905504 -346.9894)
		(width 0.174752)
		(layer "F.Cu")
		(net "PE_TX1_DR6_N")
	)
	(segment
		(start 3.905504 -346.9894)
		(end 6.738874 -346.9894)
		(width 0.174752)
		(layer "F.Cu")
		(net "PE_TX1_DR6_N")
	)
	(segment
		(start 6.738874 -346.9894)
		(end 6.992366 -346.735908)
		(width 0.174752)
		(layer "F.Cu")
		(net "PE_TX1_DR6_N")
	)
	(segment
		(start 37.846 -363.837728)
		(end 35.58413 -363.837728)
		(width 0.174752)
		(layer "F.Cu")
		(net "PE_TX1_DR6_N")
	)
	(segment
		(start 35.58413 -363.837728)
		(end 35.33013 -363.583728)
		(width 0.174752)
		(layer "F.Cu")
		(net "PE_TX1_DR6_N")
	)
	(segment
		(start 39.200074 -363.590078)
		(end 38.09365 -363.590078)
		(width 0.174752)
		(layer "F.Cu")
		(net "PE_TX1_DR6_N")
	)
	(segment
		(start 38.09365 -363.590078)
		(end 37.846 -363.837728)
		(width 0.174752)
		(layer "F.Cu")
		(net "PE_TX1_DR6_N")
	)
	(via
		(at 6.992366 -346.735908)
		(size 0.508)
		(drill 0.254)
		(layers "F.Cu" "B.Cu")
		(net "PE_TX1_DR6_N")
	)
	(via
		(at 35.33013 -363.583728)
		(size 0.508)
		(drill 0.254)
		(layers "F.Cu" "B.Cu")
		(net "PE_TX1_DR6_N")
	)
	(segment
		(start 6.992366 -346.735908)
		(end 7.220966 -346.964508)
		(width 0.1651)
		(layer "In5.Cu")
		(net "PE_TX1_DR6_N")
	)
	(segment
		(start 9.190228 -347.550232)
		(end 9.19099 -347.550232)
		(width 0.1651)
		(layer "In5.Cu")
		(net "PE_TX1_DR6_N")
	)
	(segment
		(start 14.130782 -354.604574)
		(end 14.58468 -357.180388)
		(width 0.1651)
		(layer "In5.Cu")
		(net "PE_TX1_DR6_N")
	)
	(segment
		(start 7.682484 -346.964508)
		(end 8.579866 -347.12275)
		(width 0.1651)
		(layer "In5.Cu")
		(net "PE_TX1_DR6_N")
	)
	(segment
		(start 35.101276 -363.812582)
		(end 35.33013 -363.583728)
		(width 0.1651)
		(layer "In5.Cu")
		(net "PE_TX1_DR6_N")
	)
	(segment
		(start 18.358866 -361.069128)
		(end 33.916874 -363.812582)
		(width 0.1651)
		(layer "In5.Cu")
		(net "PE_TX1_DR6_N")
	)
	(segment
		(start 8.579866 -347.12275)
		(end 9.190228 -347.550232)
		(width 0.1651)
		(layer "In5.Cu")
		(net "PE_TX1_DR6_N")
	)
	(segment
		(start 16.297148 -359.6259)
		(end 18.358866 -361.069128)
		(width 0.1651)
		(layer "In5.Cu")
		(net "PE_TX1_DR6_N")
	)
	(segment
		(start 9.19099 -347.550232)
		(end 14.130782 -354.604574)
		(width 0.1651)
		(layer "In5.Cu")
		(net "PE_TX1_DR6_N")
	)
	(segment
		(start 7.220966 -346.964508)
		(end 7.682484 -346.964508)
		(width 0.1651)
		(layer "In5.Cu")
		(net "PE_TX1_DR6_N")
	)
	(segment
		(start 14.58468 -357.180388)
		(end 16.297148 -359.6259)
		(width 0.1651)
		(layer "In5.Cu")
		(net "PE_TX1_DR6_N")
	)
	(segment
		(start 33.916874 -363.812582)
		(end 35.101276 -363.812582)
		(width 0.1651)
		(layer "In5.Cu")
		(net "PE_TX1_DR6_N")
	)
	(segment
		(start 2.249932 -436.741824)
		(end 3.570224 -436.741824)
		(width 0.174752)
		(layer "F.Cu")
		(net "PE_TX1_DR5_P")
	)
	(segment
		(start 37.7317 -466.825076)
		(end 35.57143 -466.825076)
		(width 0.174752)
		(layer "F.Cu")
		(net "PE_TX1_DR5_P")
	)
	(segment
		(start 6.73862 -437.037988)
		(end 6.992366 -436.784242)
		(width 0.174752)
		(layer "F.Cu")
		(net "PE_TX1_DR5_P")
	)
	(segment
		(start 37.96665 -466.590126)
		(end 37.7317 -466.825076)
		(width 0.174752)
		(layer "F.Cu")
		(net "PE_TX1_DR5_P")
	)
	(segment
		(start 3.570224 -436.741824)
		(end 3.866388 -437.037988)
		(width 0.174752)
		(layer "F.Cu")
		(net "PE_TX1_DR5_P")
	)
	(segment
		(start 35.57143 -466.825076)
		(end 35.33013 -466.583776)
		(width 0.174752)
		(layer "F.Cu")
		(net "PE_TX1_DR5_P")
	)
	(segment
		(start 39.200074 -466.590126)
		(end 37.96665 -466.590126)
		(width 0.174752)
		(layer "F.Cu")
		(net "PE_TX1_DR5_P")
	)
	(segment
		(start 3.866388 -437.037988)
		(end 6.73862 -437.037988)
		(width 0.174752)
		(layer "F.Cu")
		(net "PE_TX1_DR5_P")
	)
	(via
		(at 35.33013 -466.583776)
		(size 0.508)
		(drill 0.254)
		(layers "F.Cu" "B.Cu")
		(net "PE_TX1_DR5_P")
	)
	(via
		(at 6.992366 -436.784242)
		(size 0.508)
		(drill 0.254)
		(layers "F.Cu" "B.Cu")
		(net "PE_TX1_DR5_P")
	)
	(segment
		(start 14.277848 -461.493616)
		(end 10.329672 -439.086752)
		(width 0.1651)
		(layer "In5.Cu")
		(net "PE_TX1_DR5_P")
	)
	(segment
		(start 7.220966 -437.012842)
		(end 6.992366 -436.784242)
		(width 0.1651)
		(layer "In5.Cu")
		(net "PE_TX1_DR5_P")
	)
	(segment
		(start 19.753834 -466.665818)
		(end 16.11503 -464.117944)
		(width 0.1651)
		(layer "In5.Cu")
		(net "PE_TX1_DR5_P")
	)
	(segment
		(start 16.11503 -464.117944)
		(end 14.277848 -461.493616)
		(width 0.1651)
		(layer "In5.Cu")
		(net "PE_TX1_DR5_P")
	)
	(segment
		(start 9.37768 -437.72709)
		(end 8.545576 -437.144414)
		(width 0.1651)
		(layer "In5.Cu")
		(net "PE_TX1_DR5_P")
	)
	(segment
		(start 35.33013 -466.583776)
		(end 35.101276 -466.81263)
		(width 0.1651)
		(layer "In5.Cu")
		(net "PE_TX1_DR5_P")
	)
	(segment
		(start 35.101276 -466.81263)
		(end 33.885632 -466.81263)
		(width 0.1651)
		(layer "In5.Cu")
		(net "PE_TX1_DR5_P")
	)
	(segment
		(start 8.545576 -437.144414)
		(end 7.799324 -437.012842)
		(width 0.1651)
		(layer "In5.Cu")
		(net "PE_TX1_DR5_P")
	)
	(segment
		(start 27.19959 -467.97849)
		(end 19.753834 -466.665818)
		(width 0.1651)
		(layer "In5.Cu")
		(net "PE_TX1_DR5_P")
	)
	(segment
		(start 33.885632 -466.81263)
		(end 27.279346 -467.97722)
		(width 0.1651)
		(layer "In5.Cu")
		(net "PE_TX1_DR5_P")
	)
	(segment
		(start 10.329672 -439.086752)
		(end 9.37768 -437.72709)
		(width 0.1651)
		(layer "In5.Cu")
		(net "PE_TX1_DR5_P")
	)
	(segment
		(start 7.799324 -437.012842)
		(end 7.220966 -437.012842)
		(width 0.1651)
		(layer "In5.Cu")
		(net "PE_TX1_DR5_P")
	)
	(arc
		(start 27.279346 -467.97722)
		(mid 27.239517 -467.981016)
		(end 27.19959 -467.97849)
		(width 0.1651)
		(layer "In5.Cu")
		(net "PE_TX1_DR5_P")
	)
	(segment
		(start 39.200074 -467.390226)
		(end 37.966396 -467.390226)
		(width 0.174752)
		(layer "F.Cu")
		(net "PE_TX1_DR5_N")
	)
	(segment
		(start 37.966396 -467.390226)
		(end 37.7063 -467.13013)
		(width 0.174752)
		(layer "F.Cu")
		(net "PE_TX1_DR5_N")
	)
	(segment
		(start 3.85699 -437.343042)
		(end 6.738366 -437.343042)
		(width 0.174752)
		(layer "F.Cu")
		(net "PE_TX1_DR5_N")
	)
	(segment
		(start 2.249932 -437.541924)
		(end 3.658108 -437.541924)
		(width 0.174752)
		(layer "F.Cu")
		(net "PE_TX1_DR5_N")
	)
	(segment
		(start 37.7063 -467.13013)
		(end 35.596576 -467.13013)
		(width 0.174752)
		(layer "F.Cu")
		(net "PE_TX1_DR5_N")
	)
	(segment
		(start 35.596576 -467.13013)
		(end 35.33013 -467.396576)
		(width 0.174752)
		(layer "F.Cu")
		(net "PE_TX1_DR5_N")
	)
	(segment
		(start 3.658108 -437.541924)
		(end 3.85699 -437.343042)
		(width 0.174752)
		(layer "F.Cu")
		(net "PE_TX1_DR5_N")
	)
	(segment
		(start 6.738366 -437.343042)
		(end 6.992366 -437.597042)
		(width 0.174752)
		(layer "F.Cu")
		(net "PE_TX1_DR5_N")
	)
	(via
		(at 6.992366 -437.597042)
		(size 0.508)
		(drill 0.254)
		(layers "F.Cu" "B.Cu")
		(net "PE_TX1_DR5_N")
	)
	(via
		(at 35.33013 -467.396576)
		(size 0.508)
		(drill 0.254)
		(layers "F.Cu" "B.Cu")
		(net "PE_TX1_DR5_N")
	)
	(segment
		(start 9.122664 -437.982868)
		(end 9.122156 -437.982614)
		(width 0.1651)
		(layer "In5.Cu")
		(net "PE_TX1_DR5_N")
	)
	(segment
		(start 8.40613 -437.480964)
		(end 7.768082 -437.368442)
		(width 0.1651)
		(layer "In5.Cu")
		(net "PE_TX1_DR5_N")
	)
	(segment
		(start 13.941298 -461.633062)
		(end 9.993122 -439.226198)
		(width 0.1651)
		(layer "In5.Cu")
		(net "PE_TX1_DR5_N")
	)
	(segment
		(start 33.916874 -467.16823)
		(end 27.342592 -468.32774)
		(width 0.1651)
		(layer "In5.Cu")
		(net "PE_TX1_DR5_N")
	)
	(segment
		(start 35.101784 -467.16823)
		(end 33.916874 -467.16823)
		(width 0.1651)
		(layer "In5.Cu")
		(net "PE_TX1_DR5_N")
	)
	(segment
		(start 27.342592 -468.32774)
		(end 27.302968 -468.333582)
		(width 0.1651)
		(layer "In5.Cu")
		(net "PE_TX1_DR5_N")
	)
	(segment
		(start 27.302968 -468.333582)
		(end 27.274774 -468.35314)
		(width 0.1651)
		(layer "In5.Cu")
		(net "PE_TX1_DR5_N")
	)
	(segment
		(start 7.768082 -437.368442)
		(end 7.220966 -437.368442)
		(width 0.1651)
		(layer "In5.Cu")
		(net "PE_TX1_DR5_N")
	)
	(segment
		(start 35.33013 -467.396576)
		(end 35.101784 -467.16823)
		(width 0.1651)
		(layer "In5.Cu")
		(net "PE_TX1_DR5_N")
	)
	(segment
		(start 27.274774 -468.35314)
		(end 19.614388 -467.002368)
		(width 0.1651)
		(layer "In5.Cu")
		(net "PE_TX1_DR5_N")
	)
	(segment
		(start 9.993122 -439.226198)
		(end 9.122664 -437.982868)
		(width 0.1651)
		(layer "In5.Cu")
		(net "PE_TX1_DR5_N")
	)
	(segment
		(start 19.614388 -467.002368)
		(end 15.859506 -464.373468)
		(width 0.1651)
		(layer "In5.Cu")
		(net "PE_TX1_DR5_N")
	)
	(segment
		(start 7.220966 -437.368442)
		(end 6.992366 -437.597042)
		(width 0.1651)
		(layer "In5.Cu")
		(net "PE_TX1_DR5_N")
	)
	(segment
		(start 15.859506 -464.373468)
		(end 13.941298 -461.633062)
		(width 0.1651)
		(layer "In5.Cu")
		(net "PE_TX1_DR5_N")
	)
	(segment
		(start 9.122156 -437.982614)
		(end 8.40613 -437.480964)
		(width 0.1651)
		(layer "In5.Cu")
		(net "PE_TX1_DR5_N")
	)
	(segment
		(start 6.738112 -227.69449)
		(end 6.992366 -227.948744)
		(width 0.174752)
		(layer "F.Cu")
		(net "PE_TX1_DR4_P")
	)
	(segment
		(start 3.657854 -227.94214)
		(end 3.905504 -227.69449)
		(width 0.174752)
		(layer "F.Cu")
		(net "PE_TX1_DR4_P")
	)
	(segment
		(start 2.249932 -227.94214)
		(end 3.657854 -227.94214)
		(width 0.174752)
		(layer "F.Cu")
		(net "PE_TX1_DR4_P")
	)
	(segment
		(start 222.758 -55.142638)
		(end 220.58376 -55.142638)
		(width 0.174752)
		(layer "F.Cu")
		(net "PE_TX1_DR4_P")
	)
	(segment
		(start 224.199958 -55.390034)
		(end 223.005396 -55.390034)
		(width 0.174752)
		(layer "F.Cu")
		(net "PE_TX1_DR4_P")
	)
	(segment
		(start 220.58376 -55.142638)
		(end 220.330014 -55.396384)
		(width 0.174752)
		(layer "F.Cu")
		(net "PE_TX1_DR4_P")
	)
	(segment
		(start 223.005396 -55.390034)
		(end 222.758 -55.142638)
		(width 0.174752)
		(layer "F.Cu")
		(net "PE_TX1_DR4_P")
	)
	(segment
		(start 3.905504 -227.69449)
		(end 6.738112 -227.69449)
		(width 0.174752)
		(layer "F.Cu")
		(net "PE_TX1_DR4_P")
	)
	(via
		(at 6.992366 -227.948744)
		(size 0.508)
		(drill 0.254)
		(layers "F.Cu" "B.Cu")
		(net "PE_TX1_DR4_P")
	)
	(via
		(at 220.330014 -55.396384)
		(size 0.508)
		(drill 0.254)
		(layers "F.Cu" "B.Cu")
		(net "PE_TX1_DR4_P")
	)
	(segment
		(start 7.220966 -227.720144)
		(end 7.651242 -227.720144)
		(width 0.1651)
		(layer "In5.Cu")
		(net "PE_TX1_DR4_P")
	)
	(segment
		(start 24.404066 -249.8217)
		(end 26.372312 -249.403362)
		(width 0.1651)
		(layer "In5.Cu")
		(net "PE_TX1_DR4_P")
	)
	(segment
		(start 8.86206 -228.23932)
		(end 8.945372 -228.297232)
		(width 0.1651)
		(layer "In5.Cu")
		(net "PE_TX1_DR4_P")
	)
	(segment
		(start 8.778748 -228.180646)
		(end 8.86206 -228.23932)
		(width 0.1651)
		(layer "In5.Cu")
		(net "PE_TX1_DR4_P")
	)
	(segment
		(start 26.372312 -249.403362)
		(end 29.50718 -247.36933)
		(width 0.1651)
		(layer "In5.Cu")
		(net "PE_TX1_DR4_P")
	)
	(segment
		(start 218.43492 -55.632858)
		(end 219.150946 -55.168038)
		(width 0.1651)
		(layer "In5.Cu")
		(net "PE_TX1_DR4_P")
	)
	(segment
		(start 13.941044 -235.431838)
		(end 15.476728 -244.141752)
		(width 0.1651)
		(layer "In5.Cu")
		(net "PE_TX1_DR4_P")
	)
	(segment
		(start 8.945372 -228.297232)
		(end 8.945118 -228.297232)
		(width 0.1651)
		(layer "In5.Cu")
		(net "PE_TX1_DR4_P")
	)
	(segment
		(start 8.278622 -227.830634)
		(end 8.61187 -228.063806)
		(width 0.1651)
		(layer "In5.Cu")
		(net "PE_TX1_DR4_P")
	)
	(segment
		(start 29.50718 -247.36933)
		(end 30.691074 -245.678452)
		(width 0.1651)
		(layer "In5.Cu")
		(net "PE_TX1_DR4_P")
	)
	(segment
		(start 8.61187 -228.063806)
		(end 8.637778 -228.082094)
		(width 0.1651)
		(layer "In5.Cu")
		(net "PE_TX1_DR4_P")
	)
	(segment
		(start 21.74494 -249.256042)
		(end 24.404066 -249.8217)
		(width 0.1651)
		(layer "In5.Cu")
		(net "PE_TX1_DR4_P")
	)
	(segment
		(start 217.719148 -56.097678)
		(end 218.43492 -55.632858)
		(width 0.1651)
		(layer "In5.Cu")
		(net "PE_TX1_DR4_P")
	)
	(segment
		(start 30.691074 -245.678452)
		(end 31.987236 -238.321342)
		(width 0.1651)
		(layer "In5.Cu")
		(net "PE_TX1_DR4_P")
	)
	(segment
		(start 15.476728 -244.141752)
		(end 17.099026 -246.639588)
		(width 0.1651)
		(layer "In5.Cu")
		(net "PE_TX1_DR4_P")
	)
	(segment
		(start 7.651242 -227.720144)
		(end 8.278622 -227.830634)
		(width 0.1651)
		(layer "In5.Cu")
		(net "PE_TX1_DR4_P")
	)
	(segment
		(start 220.101668 -55.168038)
		(end 220.330014 -55.396384)
		(width 0.1651)
		(layer "In5.Cu")
		(net "PE_TX1_DR4_P")
	)
	(segment
		(start 88.38184 -157.781244)
		(end 204.477112 -76.489306)
		(width 0.1651)
		(layer "In5.Cu")
		(net "PE_TX1_DR4_P")
	)
	(segment
		(start 8.945118 -228.297232)
		(end 13.941044 -235.431838)
		(width 0.1651)
		(layer "In5.Cu")
		(net "PE_TX1_DR4_P")
	)
	(segment
		(start 31.987236 -238.321342)
		(end 88.38184 -157.781244)
		(width 0.1651)
		(layer "In5.Cu")
		(net "PE_TX1_DR4_P")
	)
	(segment
		(start 8.637778 -228.082094)
		(end 8.778748 -228.180646)
		(width 0.1651)
		(layer "In5.Cu")
		(net "PE_TX1_DR4_P")
	)
	(segment
		(start 17.099026 -246.639588)
		(end 20.827492 -249.060716)
		(width 0.1651)
		(layer "In5.Cu")
		(net "PE_TX1_DR4_P")
	)
	(segment
		(start 204.477112 -76.489306)
		(end 217.719148 -56.097678)
		(width 0.1651)
		(layer "In5.Cu")
		(net "PE_TX1_DR4_P")
	)
	(segment
		(start 219.150946 -55.168038)
		(end 220.101668 -55.168038)
		(width 0.1651)
		(layer "In5.Cu")
		(net "PE_TX1_DR4_P")
	)
	(segment
		(start 20.827492 -249.060716)
		(end 21.74494 -249.256042)
		(width 0.1651)
		(layer "In5.Cu")
		(net "PE_TX1_DR4_P")
	)
	(segment
		(start 6.992366 -227.948744)
		(end 7.220966 -227.720144)
		(width 0.1651)
		(layer "In5.Cu")
		(net "PE_TX1_DR4_P")
	)
	(segment
		(start 6.738874 -227.389436)
		(end 6.992366 -227.135944)
		(width 0.174752)
		(layer "F.Cu")
		(net "PE_TX1_DR4_N")
	)
	(segment
		(start 3.905504 -227.389436)
		(end 6.738874 -227.389436)
		(width 0.174752)
		(layer "F.Cu")
		(net "PE_TX1_DR4_N")
	)
	(segment
		(start 2.249932 -227.14204)
		(end 3.658108 -227.14204)
		(width 0.174752)
		(layer "F.Cu")
		(net "PE_TX1_DR4_N")
	)
	(segment
		(start 220.584014 -54.837584)
		(end 220.330014 -54.583584)
		(width 0.174752)
		(layer "F.Cu")
		(net "PE_TX1_DR4_N")
	)
	(segment
		(start 222.758 -54.837584)
		(end 220.584014 -54.837584)
		(width 0.174752)
		(layer "F.Cu")
		(net "PE_TX1_DR4_N")
	)
	(segment
		(start 3.658108 -227.14204)
		(end 3.905504 -227.389436)
		(width 0.174752)
		(layer "F.Cu")
		(net "PE_TX1_DR4_N")
	)
	(segment
		(start 223.00565 -54.589934)
		(end 222.758 -54.837584)
		(width 0.174752)
		(layer "F.Cu")
		(net "PE_TX1_DR4_N")
	)
	(segment
		(start 224.199958 -54.589934)
		(end 223.00565 -54.589934)
		(width 0.174752)
		(layer "F.Cu")
		(net "PE_TX1_DR4_N")
	)
	(via
		(at 6.992366 -227.135944)
		(size 0.508)
		(drill 0.254)
		(layers "F.Cu" "B.Cu")
		(net "PE_TX1_DR4_N")
	)
	(via
		(at 220.330014 -54.583584)
		(size 0.508)
		(drill 0.254)
		(layers "F.Cu" "B.Cu")
		(net "PE_TX1_DR4_N")
	)
	(segment
		(start 29.255466 -247.108726)
		(end 30.354524 -245.539006)
		(width 0.1651)
		(layer "In5.Cu")
		(net "PE_TX1_DR4_N")
	)
	(segment
		(start 24.404066 -249.457972)
		(end 26.233882 -249.069098)
		(width 0.1651)
		(layer "In5.Cu")
		(net "PE_TX1_DR4_N")
	)
	(segment
		(start 31.650686 -238.181896)
		(end 88.126316 -157.52572)
		(width 0.1651)
		(layer "In5.Cu")
		(net "PE_TX1_DR4_N")
	)
	(segment
		(start 30.354524 -245.539006)
		(end 31.650686 -238.181896)
		(width 0.1651)
		(layer "In5.Cu")
		(net "PE_TX1_DR4_N")
	)
	(segment
		(start 20.965922 -248.726452)
		(end 24.404066 -249.457972)
		(width 0.1651)
		(layer "In5.Cu")
		(net "PE_TX1_DR4_N")
	)
	(segment
		(start 7.220966 -227.364544)
		(end 7.682484 -227.364544)
		(width 0.1651)
		(layer "In5.Cu")
		(net "PE_TX1_DR4_N")
	)
	(segment
		(start 9.200642 -228.041708)
		(end 14.277594 -235.292392)
		(width 0.1651)
		(layer "In5.Cu")
		(net "PE_TX1_DR4_N")
	)
	(segment
		(start 220.10116 -54.812438)
		(end 220.330014 -54.583584)
		(width 0.1651)
		(layer "In5.Cu")
		(net "PE_TX1_DR4_N")
	)
	(segment
		(start 15.814548 -244.008656)
		(end 17.356328 -246.382286)
		(width 0.1651)
		(layer "In5.Cu")
		(net "PE_TX1_DR4_N")
	)
	(segment
		(start 14.277594 -235.292392)
		(end 15.814548 -244.008656)
		(width 0.1651)
		(layer "In5.Cu")
		(net "PE_TX1_DR4_N")
	)
	(segment
		(start 17.356328 -246.382286)
		(end 20.965922 -248.726452)
		(width 0.1651)
		(layer "In5.Cu")
		(net "PE_TX1_DR4_N")
	)
	(segment
		(start 88.126316 -157.52572)
		(end 204.216508 -76.237592)
		(width 0.1651)
		(layer "In5.Cu")
		(net "PE_TX1_DR4_N")
	)
	(segment
		(start 219.045536 -54.812438)
		(end 220.10116 -54.812438)
		(width 0.1651)
		(layer "In5.Cu")
		(net "PE_TX1_DR4_N")
	)
	(segment
		(start 8.418068 -227.494084)
		(end 9.200642 -228.041708)
		(width 0.1651)
		(layer "In5.Cu")
		(net "PE_TX1_DR4_N")
	)
	(segment
		(start 217.461846 -55.840376)
		(end 219.045536 -54.812438)
		(width 0.1651)
		(layer "In5.Cu")
		(net "PE_TX1_DR4_N")
	)
	(segment
		(start 7.682484 -227.364544)
		(end 8.418068 -227.494084)
		(width 0.1651)
		(layer "In5.Cu")
		(net "PE_TX1_DR4_N")
	)
	(segment
		(start 26.233882 -249.069098)
		(end 29.255466 -247.108726)
		(width 0.1651)
		(layer "In5.Cu")
		(net "PE_TX1_DR4_N")
	)
	(segment
		(start 204.216508 -76.237592)
		(end 217.461846 -55.840376)
		(width 0.1651)
		(layer "In5.Cu")
		(net "PE_TX1_DR4_N")
	)
	(segment
		(start 6.992366 -227.135944)
		(end 7.220966 -227.364544)
		(width 0.1651)
		(layer "In5.Cu")
		(net "PE_TX1_DR4_N")
	)
	(segment
		(start 222.885 -158.142686)
		(end 220.58376 -158.142686)
		(width 0.174752)
		(layer "F.Cu")
		(net "PE_TX1_DR3_P")
	)
	(segment
		(start 2.249932 -289.14217)
		(end 3.657854 -289.14217)
		(width 0.174752)
		(layer "F.Cu")
		(net "PE_TX1_DR3_P")
	)
	(segment
		(start 3.657854 -289.14217)
		(end 3.905504 -288.89452)
		(width 0.174752)
		(layer "F.Cu")
		(net "PE_TX1_DR3_P")
	)
	(segment
		(start 3.905504 -288.89452)
		(end 6.738112 -288.89452)
		(width 0.174752)
		(layer "F.Cu")
		(net "PE_TX1_DR3_P")
	)
	(segment
		(start 224.199958 -158.390082)
		(end 223.132396 -158.390082)
		(width 0.174752)
		(layer "F.Cu")
		(net "PE_TX1_DR3_P")
	)
	(segment
		(start 6.738112 -288.89452)
		(end 6.992366 -289.148774)
		(width 0.174752)
		(layer "F.Cu")
		(net "PE_TX1_DR3_P")
	)
	(segment
		(start 223.132396 -158.390082)
		(end 222.885 -158.142686)
		(width 0.174752)
		(layer "F.Cu")
		(net "PE_TX1_DR3_P")
	)
	(segment
		(start 220.58376 -158.142686)
		(end 220.330014 -158.396432)
		(width 0.174752)
		(layer "F.Cu")
		(net "PE_TX1_DR3_P")
	)
	(via
		(at 220.330014 -158.396432)
		(size 0.508)
		(drill 0.254)
		(layers "F.Cu" "B.Cu")
		(net "PE_TX1_DR3_P")
	)
	(via
		(at 6.992366 -289.148774)
		(size 0.508)
		(drill 0.254)
		(layers "F.Cu" "B.Cu")
		(net "PE_TX1_DR3_P")
	)
	(segment
		(start 7.220966 -288.920174)
		(end 6.992366 -289.148774)
		(width 0.1651)
		(layer "In5.Cu")
		(net "PE_TX1_DR3_P")
	)
	(segment
		(start 81.61655 -193.472816)
		(end 55.506874 -211.754974)
		(width 0.1651)
		(layer "In5.Cu")
		(net "PE_TX1_DR3_P")
	)
	(segment
		(start 29.119576 -256.247138)
		(end 26.420826 -271.55902)
		(width 0.1651)
		(layer "In5.Cu")
		(net "PE_TX1_DR3_P")
	)
	(segment
		(start 195.614544 -173.368208)
		(end 81.61655 -193.472816)
		(width 0.1651)
		(layer "In5.Cu")
		(net "PE_TX1_DR3_P")
	)
	(segment
		(start 34.364676 -248.755916)
		(end 34.319464 -248.820686)
		(width 0.1651)
		(layer "In5.Cu")
		(net "PE_TX1_DR3_P")
	)
	(segment
		(start 34.319464 -248.820686)
		(end 34.319464 -248.820432)
		(width 0.1651)
		(layer "In5.Cu")
		(net "PE_TX1_DR3_P")
	)
	(segment
		(start 26.420826 -271.55902)
		(end 18.663412 -282.636722)
		(width 0.1651)
		(layer "In5.Cu")
		(net "PE_TX1_DR3_P")
	)
	(segment
		(start 219.022422 -158.168086)
		(end 195.614544 -173.368208)
		(width 0.1651)
		(layer "In5.Cu")
		(net "PE_TX1_DR3_P")
	)
	(segment
		(start 10.364724 -288.447226)
		(end 7.682484 -288.920174)
		(width 0.1651)
		(layer "In5.Cu")
		(net "PE_TX1_DR3_P")
	)
	(segment
		(start 35.967162 -239.67186)
		(end 34.364676 -248.755916)
		(width 0.1651)
		(layer "In5.Cu")
		(net "PE_TX1_DR3_P")
	)
	(segment
		(start 34.319464 -248.820432)
		(end 29.119576 -256.247138)
		(width 0.1651)
		(layer "In5.Cu")
		(net "PE_TX1_DR3_P")
	)
	(segment
		(start 7.682484 -288.920174)
		(end 7.220966 -288.920174)
		(width 0.1651)
		(layer "In5.Cu")
		(net "PE_TX1_DR3_P")
	)
	(segment
		(start 220.330014 -158.396432)
		(end 220.101668 -158.168086)
		(width 0.1651)
		(layer "In5.Cu")
		(net "PE_TX1_DR3_P")
	)
	(segment
		(start 18.663412 -282.636722)
		(end 10.364724 -288.447226)
		(width 0.1651)
		(layer "In5.Cu")
		(net "PE_TX1_DR3_P")
	)
	(segment
		(start 55.506874 -211.754974)
		(end 35.967162 -239.67186)
		(width 0.1651)
		(layer "In5.Cu")
		(net "PE_TX1_DR3_P")
	)
	(segment
		(start 220.101668 -158.168086)
		(end 219.022422 -158.168086)
		(width 0.1651)
		(layer "In5.Cu")
		(net "PE_TX1_DR3_P")
	)
	(segment
		(start 6.738874 -288.589466)
		(end 6.992366 -288.335974)
		(width 0.174752)
		(layer "F.Cu")
		(net "PE_TX1_DR3_N")
	)
	(segment
		(start 222.89135 -157.837632)
		(end 220.584014 -157.837632)
		(width 0.174752)
		(layer "F.Cu")
		(net "PE_TX1_DR3_N")
	)
	(segment
		(start 3.905504 -288.589466)
		(end 6.738874 -288.589466)
		(width 0.174752)
		(layer "F.Cu")
		(net "PE_TX1_DR3_N")
	)
	(segment
		(start 224.199958 -157.589982)
		(end 223.139 -157.589982)
		(width 0.174752)
		(layer "F.Cu")
		(net "PE_TX1_DR3_N")
	)
	(segment
		(start 223.139 -157.589982)
		(end 222.89135 -157.837632)
		(width 0.174752)
		(layer "F.Cu")
		(net "PE_TX1_DR3_N")
	)
	(segment
		(start 220.584014 -157.837632)
		(end 220.330014 -157.583632)
		(width 0.174752)
		(layer "F.Cu")
		(net "PE_TX1_DR3_N")
	)
	(segment
		(start 3.658108 -288.34207)
		(end 3.905504 -288.589466)
		(width 0.174752)
		(layer "F.Cu")
		(net "PE_TX1_DR3_N")
	)
	(segment
		(start 2.249932 -288.34207)
		(end 3.658108 -288.34207)
		(width 0.174752)
		(layer "F.Cu")
		(net "PE_TX1_DR3_N")
	)
	(via
		(at 220.330014 -157.583632)
		(size 0.508)
		(drill 0.254)
		(layers "F.Cu" "B.Cu")
		(net "PE_TX1_DR3_N")
	)
	(via
		(at 6.992366 -288.335974)
		(size 0.508)
		(drill 0.254)
		(layers "F.Cu" "B.Cu")
		(net "PE_TX1_DR3_N")
	)
	(segment
		(start 26.084276 -271.419574)
		(end 18.407888 -282.381198)
		(width 0.1651)
		(layer "In5.Cu")
		(net "PE_TX1_DR3_N")
	)
	(segment
		(start 220.330014 -157.583632)
		(end 220.10116 -157.812486)
		(width 0.1651)
		(layer "In5.Cu")
		(net "PE_TX1_DR3_N")
	)
	(segment
		(start 55.25135 -211.49945)
		(end 35.630358 -239.532922)
		(width 0.1651)
		(layer "In5.Cu")
		(net "PE_TX1_DR3_N")
	)
	(segment
		(start 218.917012 -157.812486)
		(end 195.481448 -173.030388)
		(width 0.1651)
		(layer "In5.Cu")
		(net "PE_TX1_DR3_N")
	)
	(segment
		(start 35.630358 -239.532922)
		(end 34.028126 -248.616216)
		(width 0.1651)
		(layer "In5.Cu")
		(net "PE_TX1_DR3_N")
	)
	(segment
		(start 28.783026 -256.107692)
		(end 26.084276 -271.419574)
		(width 0.1651)
		(layer "In5.Cu")
		(net "PE_TX1_DR3_N")
	)
	(segment
		(start 195.481448 -173.030388)
		(end 81.477104 -193.136266)
		(width 0.1651)
		(layer "In5.Cu")
		(net "PE_TX1_DR3_N")
	)
	(segment
		(start 34.028126 -248.616216)
		(end 28.783026 -256.107692)
		(width 0.1651)
		(layer "In5.Cu")
		(net "PE_TX1_DR3_N")
	)
	(segment
		(start 10.225278 -288.110676)
		(end 7.651242 -288.564574)
		(width 0.1651)
		(layer "In5.Cu")
		(net "PE_TX1_DR3_N")
	)
	(segment
		(start 220.10116 -157.812486)
		(end 218.917012 -157.812486)
		(width 0.1651)
		(layer "In5.Cu")
		(net "PE_TX1_DR3_N")
	)
	(segment
		(start 7.651242 -288.564574)
		(end 7.220966 -288.564574)
		(width 0.1651)
		(layer "In5.Cu")
		(net "PE_TX1_DR3_N")
	)
	(segment
		(start 7.220966 -288.564574)
		(end 6.992366 -288.335974)
		(width 0.1651)
		(layer "In5.Cu")
		(net "PE_TX1_DR3_N")
	)
	(segment
		(start 81.477104 -193.136266)
		(end 55.25135 -211.49945)
		(width 0.1651)
		(layer "In5.Cu")
		(net "PE_TX1_DR3_N")
	)
	(segment
		(start 18.407888 -282.381198)
		(end 10.225278 -288.110676)
		(width 0.1651)
		(layer "In5.Cu")
		(net "PE_TX1_DR3_N")
	)
	(segment
		(start 3.657854 -319.54216)
		(end 3.905504 -319.29451)
		(width 0.174752)
		(layer "F.Cu")
		(net "PE_TX1_DR2_P")
	)
	(segment
		(start 224.199958 -261.39013)
		(end 223.132396 -261.39013)
		(width 0.174752)
		(layer "F.Cu")
		(net "PE_TX1_DR2_P")
	)
	(segment
		(start 220.58376 -261.142734)
		(end 220.330014 -261.39648)
		(width 0.174752)
		(layer "F.Cu")
		(net "PE_TX1_DR2_P")
	)
	(segment
		(start 222.885 -261.142734)
		(end 220.58376 -261.142734)
		(width 0.174752)
		(layer "F.Cu")
		(net "PE_TX1_DR2_P")
	)
	(segment
		(start 6.738112 -319.29451)
		(end 6.992366 -319.548764)
		(width 0.174752)
		(layer "F.Cu")
		(net "PE_TX1_DR2_P")
	)
	(segment
		(start 3.905504 -319.29451)
		(end 6.738112 -319.29451)
		(width 0.174752)
		(layer "F.Cu")
		(net "PE_TX1_DR2_P")
	)
	(segment
		(start 2.249932 -319.54216)
		(end 3.657854 -319.54216)
		(width 0.174752)
		(layer "F.Cu")
		(net "PE_TX1_DR2_P")
	)
	(segment
		(start 223.132396 -261.39013)
		(end 222.885 -261.142734)
		(width 0.174752)
		(layer "F.Cu")
		(net "PE_TX1_DR2_P")
	)
	(via
		(at 6.992366 -319.548764)
		(size 0.508)
		(drill 0.254)
		(layers "F.Cu" "B.Cu")
		(net "PE_TX1_DR2_P")
	)
	(via
		(at 220.330014 -261.39648)
		(size 0.508)
		(drill 0.254)
		(layers "F.Cu" "B.Cu")
		(net "PE_TX1_DR2_P")
	)
	(segment
		(start 217.919046 -261.168134)
		(end 220.101668 -261.168134)
		(width 0.1651)
		(layer "In5.Cu")
		(net "PE_TX1_DR2_P")
	)
	(segment
		(start 39.097966 -304.106072)
		(end 45.134276 -303.041558)
		(width 0.1651)
		(layer "In5.Cu")
		(net "PE_TX1_DR2_P")
	)
	(segment
		(start 220.101668 -261.168134)
		(end 220.330014 -261.39648)
		(width 0.1651)
		(layer "In5.Cu")
		(net "PE_TX1_DR2_P")
	)
	(segment
		(start 10.442448 -317.78575)
		(end 12.386818 -315.00826)
		(width 0.1651)
		(layer "In5.Cu")
		(net "PE_TX1_DR2_P")
	)
	(segment
		(start 6.992366 -319.548764)
		(end 7.220966 -319.320164)
		(width 0.1651)
		(layer "In5.Cu")
		(net "PE_TX1_DR2_P")
	)
	(segment
		(start 15.28318 -305.278536)
		(end 20.291298 -301.771558)
		(width 0.1651)
		(layer "In5.Cu")
		(net "PE_TX1_DR2_P")
	)
	(segment
		(start 66.897504 -287.802066)
		(end 217.919046 -261.168134)
		(width 0.1651)
		(layer "In5.Cu")
		(net "PE_TX1_DR2_P")
	)
	(segment
		(start 7.220966 -319.320164)
		(end 7.682484 -319.320164)
		(width 0.1651)
		(layer "In5.Cu")
		(net "PE_TX1_DR2_P")
	)
	(segment
		(start 7.682484 -319.320164)
		(end 8.441944 -319.186306)
		(width 0.1651)
		(layer "In5.Cu")
		(net "PE_TX1_DR2_P")
	)
	(segment
		(start 13.70457 -307.53304)
		(end 15.28318 -305.278536)
		(width 0.1651)
		(layer "In5.Cu")
		(net "PE_TX1_DR2_P")
	)
	(segment
		(start 12.386818 -315.00826)
		(end 13.70457 -307.53304)
		(width 0.1651)
		(layer "In5.Cu")
		(net "PE_TX1_DR2_P")
	)
	(segment
		(start 8.441944 -319.186306)
		(end 10.442448 -317.78575)
		(width 0.1651)
		(layer "In5.Cu")
		(net "PE_TX1_DR2_P")
	)
	(segment
		(start 45.134276 -303.041558)
		(end 66.897504 -287.802066)
		(width 0.1651)
		(layer "In5.Cu")
		(net "PE_TX1_DR2_P")
	)
	(segment
		(start 20.291298 -301.771558)
		(end 23.075646 -301.28083)
		(width 0.1651)
		(layer "In5.Cu")
		(net "PE_TX1_DR2_P")
	)
	(segment
		(start 23.075646 -301.28083)
		(end 39.097966 -304.106072)
		(width 0.1651)
		(layer "In5.Cu")
		(net "PE_TX1_DR2_P")
	)
	(segment
		(start 222.885 -260.83768)
		(end 220.584014 -260.83768)
		(width 0.174752)
		(layer "F.Cu")
		(net "PE_TX1_DR2_N")
	)
	(segment
		(start 220.584014 -260.83768)
		(end 220.330014 -260.58368)
		(width 0.174752)
		(layer "F.Cu")
		(net "PE_TX1_DR2_N")
	)
	(segment
		(start 6.738874 -318.989456)
		(end 6.992366 -318.735964)
		(width 0.174752)
		(layer "F.Cu")
		(net "PE_TX1_DR2_N")
	)
	(segment
		(start 2.249932 -318.74206)
		(end 3.658108 -318.74206)
		(width 0.174752)
		(layer "F.Cu")
		(net "PE_TX1_DR2_N")
	)
	(segment
		(start 223.13265 -260.59003)
		(end 222.885 -260.83768)
		(width 0.174752)
		(layer "F.Cu")
		(net "PE_TX1_DR2_N")
	)
	(segment
		(start 3.658108 -318.74206)
		(end 3.905504 -318.989456)
		(width 0.174752)
		(layer "F.Cu")
		(net "PE_TX1_DR2_N")
	)
	(segment
		(start 224.199958 -260.59003)
		(end 223.13265 -260.59003)
		(width 0.174752)
		(layer "F.Cu")
		(net "PE_TX1_DR2_N")
	)
	(segment
		(start 3.905504 -318.989456)
		(end 6.738874 -318.989456)
		(width 0.174752)
		(layer "F.Cu")
		(net "PE_TX1_DR2_N")
	)
	(via
		(at 6.992366 -318.735964)
		(size 0.508)
		(drill 0.254)
		(layers "F.Cu" "B.Cu")
		(net "PE_TX1_DR2_N")
	)
	(via
		(at 220.330014 -260.58368)
		(size 0.508)
		(drill 0.254)
		(layers "F.Cu" "B.Cu")
		(net "PE_TX1_DR2_N")
	)
	(segment
		(start 13.36802 -307.393594)
		(end 12.050268 -314.868814)
		(width 0.1651)
		(layer "In5.Cu")
		(net "PE_TX1_DR2_N")
	)
	(segment
		(start 39.097966 -303.744884)
		(end 23.075646 -300.919642)
		(width 0.1651)
		(layer "In5.Cu")
		(net "PE_TX1_DR2_N")
	)
	(segment
		(start 66.758058 -287.465516)
		(end 44.99483 -302.705008)
		(width 0.1651)
		(layer "In5.Cu")
		(net "PE_TX1_DR2_N")
	)
	(segment
		(start 7.220966 -318.964564)
		(end 6.992366 -318.735964)
		(width 0.1651)
		(layer "In5.Cu")
		(net "PE_TX1_DR2_N")
	)
	(segment
		(start 20.151852 -301.435008)
		(end 15.027656 -305.023012)
		(width 0.1651)
		(layer "In5.Cu")
		(net "PE_TX1_DR2_N")
	)
	(segment
		(start 7.651242 -318.964564)
		(end 7.220966 -318.964564)
		(width 0.1651)
		(layer "In5.Cu")
		(net "PE_TX1_DR2_N")
	)
	(segment
		(start 217.887804 -260.812534)
		(end 66.758058 -287.465516)
		(width 0.1651)
		(layer "In5.Cu")
		(net "PE_TX1_DR2_N")
	)
	(segment
		(start 44.99483 -302.705008)
		(end 39.097966 -303.744884)
		(width 0.1651)
		(layer "In5.Cu")
		(net "PE_TX1_DR2_N")
	)
	(segment
		(start 15.027656 -305.023012)
		(end 13.36802 -307.393594)
		(width 0.1651)
		(layer "In5.Cu")
		(net "PE_TX1_DR2_N")
	)
	(segment
		(start 220.10116 -260.812534)
		(end 217.887804 -260.812534)
		(width 0.1651)
		(layer "In5.Cu")
		(net "PE_TX1_DR2_N")
	)
	(segment
		(start 10.186924 -317.530226)
		(end 8.302498 -318.849756)
		(width 0.1651)
		(layer "In5.Cu")
		(net "PE_TX1_DR2_N")
	)
	(segment
		(start 220.330014 -260.58368)
		(end 220.10116 -260.812534)
		(width 0.1651)
		(layer "In5.Cu")
		(net "PE_TX1_DR2_N")
	)
	(segment
		(start 23.075646 -300.919642)
		(end 20.151852 -301.435008)
		(width 0.1651)
		(layer "In5.Cu")
		(net "PE_TX1_DR2_N")
	)
	(segment
		(start 8.302498 -318.849756)
		(end 7.651242 -318.964564)
		(width 0.1651)
		(layer "In5.Cu")
		(net "PE_TX1_DR2_N")
	)
	(segment
		(start 12.050268 -314.868814)
		(end 10.186924 -317.530226)
		(width 0.1651)
		(layer "In5.Cu")
		(net "PE_TX1_DR2_N")
	)
	(segment
		(start 24.123396 -38.857174)
		(end 26.416254 -38.857174)
		(width 0.174752)
		(layer "F.Cu")
		(net "PE_TX1_DR14_P")
	)
	(segment
		(start 22.800056 -38.609778)
		(end 23.876 -38.609778)
		(width 0.174752)
		(layer "F.Cu")
		(net "PE_TX1_DR14_P")
	)
	(segment
		(start 26.416254 -38.857174)
		(end 26.67 -38.603428)
		(width 0.174752)
		(layer "F.Cu")
		(net "PE_TX1_DR14_P")
	)
	(segment
		(start 3.85445 -153.345388)
		(end 6.738366 -153.345388)
		(width 0.174752)
		(layer "F.Cu")
		(net "PE_TX1_DR14_P")
	)
	(segment
		(start 2.249932 -153.541984)
		(end 3.657854 -153.541984)
		(width 0.174752)
		(layer "F.Cu")
		(net "PE_TX1_DR14_P")
	)
	(segment
		(start 6.738366 -153.345388)
		(end 6.992366 -153.599388)
		(width 0.174752)
		(layer "F.Cu")
		(net "PE_TX1_DR14_P")
	)
	(segment
		(start 23.876 -38.609778)
		(end 24.123396 -38.857174)
		(width 0.174752)
		(layer "F.Cu")
		(net "PE_TX1_DR14_P")
	)
	(segment
		(start 3.657854 -153.541984)
		(end 3.85445 -153.345388)
		(width 0.174752)
		(layer "F.Cu")
		(net "PE_TX1_DR14_P")
	)
	(via
		(at 26.67 -38.603428)
		(size 0.508)
		(drill 0.254)
		(layers "F.Cu" "B.Cu")
		(net "PE_TX1_DR14_P")
	)
	(via
		(at 6.992366 -153.599388)
		(size 0.508)
		(drill 0.254)
		(layers "F.Cu" "B.Cu")
		(net "PE_TX1_DR14_P")
	)
	(segment
		(start 12.613132 -138.359134)
		(end 6.652006 -104.54386)
		(width 0.1651)
		(layer "In5.Cu")
		(net "PE_TX1_DR14_P")
	)
	(segment
		(start 26.898346 -38.831774)
		(end 26.67 -38.603428)
		(width 0.1651)
		(layer "In5.Cu")
		(net "PE_TX1_DR14_P")
	)
	(segment
		(start 6.652006 -104.54386)
		(end 9.609836 -87.770716)
		(width 0.1651)
		(layer "In5.Cu")
		(net "PE_TX1_DR14_P")
	)
	(segment
		(start 7.859776 -153.283158)
		(end 8.403844 -153.187146)
		(width 0.1651)
		(layer "In5.Cu")
		(net "PE_TX1_DR14_P")
	)
	(segment
		(start 7.362952 -153.370788)
		(end 7.859776 -153.283158)
		(width 0.1651)
		(layer "In5.Cu")
		(net "PE_TX1_DR14_P")
	)
	(segment
		(start 28.083256 -38.831774)
		(end 26.898346 -38.831774)
		(width 0.1651)
		(layer "In5.Cu")
		(net "PE_TX1_DR14_P")
	)
	(segment
		(start 30.05455 -40.855392)
		(end 29.911294 -40.042084)
		(width 0.1651)
		(layer "In5.Cu")
		(net "PE_TX1_DR14_P")
	)
	(segment
		(start 30.054804 -40.855392)
		(end 30.05455 -40.855392)
		(width 0.1651)
		(layer "In5.Cu")
		(net "PE_TX1_DR14_P")
	)
	(segment
		(start 6.992366 -153.599388)
		(end 7.220966 -153.370788)
		(width 0.1651)
		(layer "In5.Cu")
		(net "PE_TX1_DR14_P")
	)
	(segment
		(start 7.220966 -153.370788)
		(end 7.362952 -153.370788)
		(width 0.1651)
		(layer "In5.Cu")
		(net "PE_TX1_DR14_P")
	)
	(segment
		(start 29.54147 -39.513764)
		(end 28.72994 -38.94582)
		(width 0.1651)
		(layer "In5.Cu")
		(net "PE_TX1_DR14_P")
	)
	(segment
		(start 10.347198 -151.214074)
		(end 12.613132 -138.359134)
		(width 0.1651)
		(layer "In5.Cu")
		(net "PE_TX1_DR14_P")
	)
	(segment
		(start 8.403844 -153.187146)
		(end 9.506966 -152.414986)
		(width 0.1651)
		(layer "In5.Cu")
		(net "PE_TX1_DR14_P")
	)
	(segment
		(start 9.609836 -87.770716)
		(end 25.929082 -64.46393)
		(width 0.1651)
		(layer "In5.Cu")
		(net "PE_TX1_DR14_P")
	)
	(segment
		(start 29.911294 -40.042084)
		(end 29.54147 -39.513764)
		(width 0.1651)
		(layer "In5.Cu")
		(net "PE_TX1_DR14_P")
	)
	(segment
		(start 25.929082 -64.46393)
		(end 27.056588 -58.06948)
		(width 0.1651)
		(layer "In5.Cu")
		(net "PE_TX1_DR14_P")
	)
	(segment
		(start 28.72994 -38.94582)
		(end 28.083256 -38.831774)
		(width 0.1651)
		(layer "In5.Cu")
		(net "PE_TX1_DR14_P")
	)
	(segment
		(start 27.056588 -58.06948)
		(end 30.054804 -41.067228)
		(width 0.1651)
		(layer "In5.Cu")
		(net "PE_TX1_DR14_P")
	)
	(segment
		(start 9.506966 -152.414986)
		(end 10.347198 -151.214074)
		(width 0.1651)
		(layer "In5.Cu")
		(net "PE_TX1_DR14_P")
	)
	(arc
		(start 30.054804 -41.067228)
		(mid 30.064074 -40.96131)
		(end 30.054804 -40.855392)
		(width 0.1651)
		(layer "In5.Cu")
		(net "PE_TX1_DR14_P")
	)
	(segment
		(start 23.88235 -39.409878)
		(end 24.13 -39.162228)
		(width 0.174752)
		(layer "F.Cu")
		(net "PE_TX1_DR14_N")
	)
	(segment
		(start 6.73862 -153.040334)
		(end 6.992366 -152.786588)
		(width 0.174752)
		(layer "F.Cu")
		(net "PE_TX1_DR14_N")
	)
	(segment
		(start 26.416 -39.162228)
		(end 26.67 -39.416228)
		(width 0.174752)
		(layer "F.Cu")
		(net "PE_TX1_DR14_N")
	)
	(segment
		(start 3.657854 -152.742138)
		(end 3.95605 -153.040334)
		(width 0.174752)
		(layer "F.Cu")
		(net "PE_TX1_DR14_N")
	)
	(segment
		(start 3.95605 -153.040334)
		(end 6.73862 -153.040334)
		(width 0.174752)
		(layer "F.Cu")
		(net "PE_TX1_DR14_N")
	)
	(segment
		(start 22.800056 -39.409878)
		(end 23.88235 -39.409878)
		(width 0.174752)
		(layer "F.Cu")
		(net "PE_TX1_DR14_N")
	)
	(segment
		(start 2.249932 -152.742138)
		(end 3.657854 -152.742138)
		(width 0.174752)
		(layer "F.Cu")
		(net "PE_TX1_DR14_N")
	)
	(segment
		(start 24.13 -39.162228)
		(end 26.416 -39.162228)
		(width 0.174752)
		(layer "F.Cu")
		(net "PE_TX1_DR14_N")
	)
	(via
		(at 6.992366 -152.786588)
		(size 0.508)
		(drill 0.254)
		(layers "F.Cu" "B.Cu")
		(net "PE_TX1_DR14_N")
	)
	(via
		(at 26.67 -39.416228)
		(size 0.508)
		(drill 0.254)
		(layers "F.Cu" "B.Cu")
		(net "PE_TX1_DR14_N")
	)
	(segment
		(start 29.285946 -39.769288)
		(end 28.590494 -39.28237)
		(width 0.1651)
		(layer "In5.Cu")
		(net "PE_TX1_DR14_N")
	)
	(segment
		(start 26.898854 -39.187374)
		(end 26.67 -39.416228)
		(width 0.1651)
		(layer "In5.Cu")
		(net "PE_TX1_DR14_N")
	)
	(segment
		(start 10.354564 -148.039582)
		(end 10.44067 -147.551902)
		(width 0.1651)
		(layer "In5.Cu")
		(net "PE_TX1_DR14_N")
	)
	(segment
		(start 29.704284 -40.917114)
		(end 29.574744 -40.18153)
		(width 0.1651)
		(layer "In5.Cu")
		(net "PE_TX1_DR14_N")
	)
	(segment
		(start 10.010648 -151.074628)
		(end 10.269982 -149.603206)
		(width 0.1651)
		(layer "In5.Cu")
		(net "PE_TX1_DR14_N")
	)
	(segment
		(start 29.574744 -40.18153)
		(end 29.285946 -39.769288)
		(width 0.1651)
		(layer "In5.Cu")
		(net "PE_TX1_DR14_N")
	)
	(segment
		(start 28.052014 -39.187374)
		(end 26.898854 -39.187374)
		(width 0.1651)
		(layer "In5.Cu")
		(net "PE_TX1_DR14_N")
	)
	(segment
		(start 10.269982 -149.603206)
		(end 10.117582 -149.385274)
		(width 0.1651)
		(layer "In5.Cu")
		(net "PE_TX1_DR14_N")
	)
	(segment
		(start 11.122914 -144.763236)
		(end 10.97026 -144.545558)
		(width 0.1651)
		(layer "In5.Cu")
		(net "PE_TX1_DR14_N")
	)
	(segment
		(start 11.293602 -142.711932)
		(end 11.51128 -142.559532)
		(width 0.1651)
		(layer "In5.Cu")
		(net "PE_TX1_DR14_N")
	)
	(segment
		(start 11.444732 -141.85392)
		(end 11.530838 -141.36624)
		(width 0.1651)
		(layer "In5.Cu")
		(net "PE_TX1_DR14_N")
	)
	(segment
		(start 10.97026 -144.545558)
		(end 11.056366 -144.057878)
		(width 0.1651)
		(layer "In5.Cu")
		(net "PE_TX1_DR14_N")
	)
	(segment
		(start 26.706322 -58.007758)
		(end 29.704538 -41.00576)
		(width 0.1651)
		(layer "In5.Cu")
		(net "PE_TX1_DR14_N")
	)
	(segment
		(start 9.251442 -152.159462)
		(end 10.010648 -151.074628)
		(width 0.1651)
		(layer "In5.Cu")
		(net "PE_TX1_DR14_N")
	)
	(segment
		(start 8.264398 -152.850596)
		(end 9.251442 -152.159462)
		(width 0.1651)
		(layer "In5.Cu")
		(net "PE_TX1_DR14_N")
	)
	(segment
		(start 11.530838 -141.36624)
		(end 11.748516 -141.21384)
		(width 0.1651)
		(layer "In5.Cu")
		(net "PE_TX1_DR14_N")
	)
	(segment
		(start 11.36015 -143.417544)
		(end 11.207496 -143.199612)
		(width 0.1651)
		(layer "In5.Cu")
		(net "PE_TX1_DR14_N")
	)
	(segment
		(start 6.500876 -105.73512)
		(end 6.290818 -104.54386)
		(width 0.1651)
		(layer "In5.Cu")
		(net "PE_TX1_DR14_N")
	)
	(segment
		(start 7.33171 -153.015188)
		(end 8.264398 -152.850596)
		(width 0.1651)
		(layer "In5.Cu")
		(net "PE_TX1_DR14_N")
	)
	(segment
		(start 6.585458 -107.29849)
		(end 6.738112 -107.080558)
		(width 0.1651)
		(layer "In5.Cu")
		(net "PE_TX1_DR14_N")
	)
	(segment
		(start 12.251944 -138.359134)
		(end 6.889242 -107.93857)
		(width 0.1651)
		(layer "In5.Cu")
		(net "PE_TX1_DR14_N")
	)
	(segment
		(start 10.507218 -148.25726)
		(end 10.354564 -148.039582)
		(width 0.1651)
		(layer "In5.Cu")
		(net "PE_TX1_DR14_N")
	)
	(segment
		(start 11.51128 -142.559532)
		(end 11.597386 -142.071852)
		(width 0.1651)
		(layer "In5.Cu")
		(net "PE_TX1_DR14_N")
	)
	(segment
		(start 9.273286 -87.63127)
		(end 25.592532 -64.324484)
		(width 0.1651)
		(layer "In5.Cu")
		(net "PE_TX1_DR14_N")
	)
	(segment
		(start 28.590494 -39.28237)
		(end 28.052014 -39.187374)
		(width 0.1651)
		(layer "In5.Cu")
		(net "PE_TX1_DR14_N")
	)
	(segment
		(start 7.220966 -153.015188)
		(end 7.33171 -153.015188)
		(width 0.1651)
		(layer "In5.Cu")
		(net "PE_TX1_DR14_N")
	)
	(segment
		(start 10.117582 -149.385274)
		(end 10.203434 -148.897594)
		(width 0.1651)
		(layer "In5.Cu")
		(net "PE_TX1_DR14_N")
	)
	(segment
		(start 6.889242 -107.93857)
		(end 6.671564 -107.78617)
		(width 0.1651)
		(layer "In5.Cu")
		(net "PE_TX1_DR14_N")
	)
	(segment
		(start 29.704538 -40.917368)
		(end 29.704284 -40.917114)
		(width 0.1651)
		(layer "In5.Cu")
		(net "PE_TX1_DR14_N")
	)
	(segment
		(start 25.592532 -64.324484)
		(end 26.706322 -58.007758)
		(width 0.1651)
		(layer "In5.Cu")
		(net "PE_TX1_DR14_N")
	)
	(segment
		(start 6.290818 -104.54386)
		(end 9.273286 -87.63127)
		(width 0.1651)
		(layer "In5.Cu")
		(net "PE_TX1_DR14_N")
	)
	(segment
		(start 11.597386 -142.071852)
		(end 11.444732 -141.85392)
		(width 0.1651)
		(layer "In5.Cu")
		(net "PE_TX1_DR14_N")
	)
	(segment
		(start 11.056366 -144.057878)
		(end 11.274044 -143.905224)
		(width 0.1651)
		(layer "In5.Cu")
		(net "PE_TX1_DR14_N")
	)
	(segment
		(start 6.652006 -106.592878)
		(end 6.434328 -106.440478)
		(width 0.1651)
		(layer "In5.Cu")
		(net "PE_TX1_DR14_N")
	)
	(segment
		(start 10.44067 -147.551902)
		(end 10.658348 -147.399248)
		(width 0.1651)
		(layer "In5.Cu")
		(net "PE_TX1_DR14_N")
	)
	(segment
		(start 6.434328 -106.440478)
		(end 6.348222 -105.952798)
		(width 0.1651)
		(layer "In5.Cu")
		(net "PE_TX1_DR14_N")
	)
	(segment
		(start 11.274044 -143.905224)
		(end 11.36015 -143.417544)
		(width 0.1651)
		(layer "In5.Cu")
		(net "PE_TX1_DR14_N")
	)
	(segment
		(start 10.658348 -147.399248)
		(end 10.658094 -147.399248)
		(width 0.1651)
		(layer "In5.Cu")
		(net "PE_TX1_DR14_N")
	)
	(segment
		(start 6.738112 -107.080558)
		(end 6.652006 -106.592878)
		(width 0.1651)
		(layer "In5.Cu")
		(net "PE_TX1_DR14_N")
	)
	(segment
		(start 6.348222 -105.952798)
		(end 6.500876 -105.73512)
		(width 0.1651)
		(layer "In5.Cu")
		(net "PE_TX1_DR14_N")
	)
	(segment
		(start 10.658094 -147.399248)
		(end 11.122914 -144.763236)
		(width 0.1651)
		(layer "In5.Cu")
		(net "PE_TX1_DR14_N")
	)
	(segment
		(start 11.748516 -141.21384)
		(end 12.251944 -138.359134)
		(width 0.1651)
		(layer "In5.Cu")
		(net "PE_TX1_DR14_N")
	)
	(segment
		(start 6.992366 -152.786588)
		(end 7.220966 -153.015188)
		(width 0.1651)
		(layer "In5.Cu")
		(net "PE_TX1_DR14_N")
	)
	(segment
		(start 6.671564 -107.78617)
		(end 6.585458 -107.29849)
		(width 0.1651)
		(layer "In5.Cu")
		(net "PE_TX1_DR14_N")
	)
	(segment
		(start 10.421112 -148.745194)
		(end 10.507218 -148.25726)
		(width 0.1651)
		(layer "In5.Cu")
		(net "PE_TX1_DR14_N")
	)
	(segment
		(start 11.207496 -143.199612)
		(end 11.293602 -142.711932)
		(width 0.1651)
		(layer "In5.Cu")
		(net "PE_TX1_DR14_N")
	)
	(segment
		(start 10.203434 -148.897594)
		(end 10.421112 -148.745194)
		(width 0.1651)
		(layer "In5.Cu")
		(net "PE_TX1_DR14_N")
	)
	(arc
		(start 29.704538 -41.00576)
		(mid 29.708412 -40.961564)
		(end 29.704538 -40.917368)
		(width 0.1651)
		(layer "In5.Cu")
		(net "PE_TX1_DR14_N")
	)
	(segment
		(start 3.6576 -169.542206)
		(end 3.85445 -169.345356)
		(width 0.174752)
		(layer "F.Cu")
		(net "PE_TX1_DR13_P")
	)
	(segment
		(start 2.249932 -169.542206)
		(end 3.6576 -169.542206)
		(width 0.174752)
		(layer "F.Cu")
		(net "PE_TX1_DR13_P")
	)
	(segment
		(start 24.032718 -141.609826)
		(end 24.280114 -141.857222)
		(width 0.174752)
		(layer "F.Cu")
		(net "PE_TX1_DR13_P")
	)
	(segment
		(start 3.85445 -169.345356)
		(end 6.738112 -169.345356)
		(width 0.174752)
		(layer "F.Cu")
		(net "PE_TX1_DR13_P")
	)
	(segment
		(start 26.416254 -141.857222)
		(end 26.67 -141.603476)
		(width 0.174752)
		(layer "F.Cu")
		(net "PE_TX1_DR13_P")
	)
	(segment
		(start 24.280114 -141.857222)
		(end 26.416254 -141.857222)
		(width 0.174752)
		(layer "F.Cu")
		(net "PE_TX1_DR13_P")
	)
	(segment
		(start 22.800056 -141.609826)
		(end 24.032718 -141.609826)
		(width 0.174752)
		(layer "F.Cu")
		(net "PE_TX1_DR13_P")
	)
	(segment
		(start 6.738112 -169.345356)
		(end 6.992366 -169.59961)
		(width 0.174752)
		(layer "F.Cu")
		(net "PE_TX1_DR13_P")
	)
	(via
		(at 6.992366 -169.59961)
		(size 0.508)
		(drill 0.254)
		(layers "F.Cu" "B.Cu")
		(net "PE_TX1_DR13_P")
	)
	(via
		(at 26.67 -141.603476)
		(size 0.508)
		(drill 0.254)
		(layers "F.Cu" "B.Cu")
		(net "PE_TX1_DR13_P")
	)
	(segment
		(start 28.380944 -142.160752)
		(end 28.417012 -142.21206)
		(width 0.1651)
		(layer "In5.Cu")
		(net "PE_TX1_DR13_P")
	)
	(segment
		(start 20.593812 -167.692324)
		(end 9.47547 -169.65295)
		(width 0.1651)
		(layer "In5.Cu")
		(net "PE_TX1_DR13_P")
	)
	(segment
		(start 7.220966 -169.37101)
		(end 6.992366 -169.59961)
		(width 0.1651)
		(layer "In5.Cu")
		(net "PE_TX1_DR13_P")
	)
	(segment
		(start 23.680166 -164.65804)
		(end 22.480524 -166.371524)
		(width 0.1651)
		(layer "In5.Cu")
		(net "PE_TX1_DR13_P")
	)
	(segment
		(start 28.669996 -142.57401)
		(end 28.858972 -143.645382)
		(width 0.1651)
		(layer "In5.Cu")
		(net "PE_TX1_DR13_P")
	)
	(segment
		(start 28.41752 -142.212822)
		(end 28.669996 -142.57401)
		(width 0.1651)
		(layer "In5.Cu")
		(net "PE_TX1_DR13_P")
	)
	(segment
		(start 26.752296 -147.249134)
		(end 23.680166 -164.65804)
		(width 0.1651)
		(layer "In5.Cu")
		(net "PE_TX1_DR13_P")
	)
	(segment
		(start 28.417012 -142.21206)
		(end 28.41752 -142.212822)
		(width 0.1651)
		(layer "In5.Cu")
		(net "PE_TX1_DR13_P")
	)
	(segment
		(start 28.858972 -143.645382)
		(end 28.718764 -144.440148)
		(width 0.1651)
		(layer "In5.Cu")
		(net "PE_TX1_DR13_P")
	)
	(segment
		(start 28.718764 -144.440148)
		(end 26.752296 -147.249134)
		(width 0.1651)
		(layer "In5.Cu")
		(net "PE_TX1_DR13_P")
	)
	(segment
		(start 22.480524 -166.371524)
		(end 20.593812 -167.692324)
		(width 0.1651)
		(layer "In5.Cu")
		(net "PE_TX1_DR13_P")
	)
	(segment
		(start 9.47547 -169.65295)
		(end 7.876794 -169.37101)
		(width 0.1651)
		(layer "In5.Cu")
		(net "PE_TX1_DR13_P")
	)
	(segment
		(start 7.876794 -169.37101)
		(end 7.220966 -169.37101)
		(width 0.1651)
		(layer "In5.Cu")
		(net "PE_TX1_DR13_P")
	)
	(segment
		(start 26.67 -141.603476)
		(end 26.898346 -141.831822)
		(width 0.1651)
		(layer "In5.Cu")
		(net "PE_TX1_DR13_P")
	)
	(segment
		(start 27.590242 -141.831822)
		(end 28.018994 -141.907514)
		(width 0.1651)
		(layer "In5.Cu")
		(net "PE_TX1_DR13_P")
	)
	(segment
		(start 26.898346 -141.831822)
		(end 27.590242 -141.831822)
		(width 0.1651)
		(layer "In5.Cu")
		(net "PE_TX1_DR13_P")
	)
	(segment
		(start 28.018994 -141.907514)
		(end 28.380944 -142.160752)
		(width 0.1651)
		(layer "In5.Cu")
		(net "PE_TX1_DR13_P")
	)
	(segment
		(start 22.800056 -142.409926)
		(end 24.046434 -142.409926)
		(width 0.174752)
		(layer "F.Cu")
		(net "PE_TX1_DR13_N")
	)
	(segment
		(start 26.416 -142.162276)
		(end 26.67 -142.416276)
		(width 0.174752)
		(layer "F.Cu")
		(net "PE_TX1_DR13_N")
	)
	(segment
		(start 3.95605 -169.040302)
		(end 6.738874 -169.040302)
		(width 0.174752)
		(layer "F.Cu")
		(net "PE_TX1_DR13_N")
	)
	(segment
		(start 24.294084 -142.162276)
		(end 26.416 -142.162276)
		(width 0.174752)
		(layer "F.Cu")
		(net "PE_TX1_DR13_N")
	)
	(segment
		(start 3.657854 -168.742106)
		(end 3.95605 -169.040302)
		(width 0.174752)
		(layer "F.Cu")
		(net "PE_TX1_DR13_N")
	)
	(segment
		(start 24.046434 -142.409926)
		(end 24.294084 -142.162276)
		(width 0.174752)
		(layer "F.Cu")
		(net "PE_TX1_DR13_N")
	)
	(segment
		(start 6.738874 -169.040302)
		(end 6.992366 -168.78681)
		(width 0.174752)
		(layer "F.Cu")
		(net "PE_TX1_DR13_N")
	)
	(segment
		(start 2.249932 -168.742106)
		(end 3.657854 -168.742106)
		(width 0.174752)
		(layer "F.Cu")
		(net "PE_TX1_DR13_N")
	)
	(via
		(at 6.992366 -168.78681)
		(size 0.508)
		(drill 0.254)
		(layers "F.Cu" "B.Cu")
		(net "PE_TX1_DR13_N")
	)
	(via
		(at 26.67 -142.416276)
		(size 0.508)
		(drill 0.254)
		(layers "F.Cu" "B.Cu")
		(net "PE_TX1_DR13_N")
	)
	(segment
		(start 23.818088 -161.827972)
		(end 23.904194 -161.340292)
		(width 0.1651)
		(layer "In5.Cu")
		(net "PE_TX1_DR13_N")
	)
	(segment
		(start 22.225 -166.116)
		(end 23.343108 -164.519356)
		(width 0.1651)
		(layer "In5.Cu")
		(net "PE_TX1_DR13_N")
	)
	(segment
		(start 16.384524 -167.882316)
		(end 16.602456 -168.03497)
		(width 0.1651)
		(layer "In5.Cu")
		(net "PE_TX1_DR13_N")
	)
	(segment
		(start 7.908036 -169.01541)
		(end 9.47547 -169.291762)
		(width 0.1651)
		(layer "In5.Cu")
		(net "PE_TX1_DR13_N")
	)
	(segment
		(start 27.437334 -145.322798)
		(end 27.721306 -144.916906)
		(width 0.1651)
		(layer "In5.Cu")
		(net "PE_TX1_DR13_N")
	)
	(segment
		(start 15.896844 -167.968422)
		(end 16.384524 -167.882316)
		(width 0.1651)
		(layer "In5.Cu")
		(net "PE_TX1_DR13_N")
	)
	(segment
		(start 26.65349 -146.442176)
		(end 26.937716 -146.036284)
		(width 0.1651)
		(layer "In5.Cu")
		(net "PE_TX1_DR13_N")
	)
	(segment
		(start 6.992366 -168.78681)
		(end 7.220966 -169.01541)
		(width 0.1651)
		(layer "In5.Cu")
		(net "PE_TX1_DR13_N")
	)
	(segment
		(start 15.744444 -168.1861)
		(end 15.896844 -167.968422)
		(width 0.1651)
		(layer "In5.Cu")
		(net "PE_TX1_DR13_N")
	)
	(segment
		(start 27.98318 -144.870678)
		(end 28.382214 -144.300702)
		(width 0.1651)
		(layer "In5.Cu")
		(net "PE_TX1_DR13_N")
	)
	(segment
		(start 17.948148 -167.797734)
		(end 20.454366 -167.355774)
		(width 0.1651)
		(layer "In5.Cu")
		(net "PE_TX1_DR13_N")
	)
	(segment
		(start 7.220966 -169.01541)
		(end 7.908036 -169.01541)
		(width 0.1651)
		(layer "In5.Cu")
		(net "PE_TX1_DR13_N")
	)
	(segment
		(start 26.898854 -142.187422)
		(end 26.67 -142.416276)
		(width 0.1651)
		(layer "In5.Cu")
		(net "PE_TX1_DR13_N")
	)
	(segment
		(start 27.721306 -144.916906)
		(end 27.98318 -144.870678)
		(width 0.1651)
		(layer "In5.Cu")
		(net "PE_TX1_DR13_N")
	)
	(segment
		(start 17.090136 -167.948864)
		(end 17.24279 -167.731186)
		(width 0.1651)
		(layer "In5.Cu")
		(net "PE_TX1_DR13_N")
	)
	(segment
		(start 23.666704 -162.685984)
		(end 23.514304 -162.468052)
		(width 0.1651)
		(layer "In5.Cu")
		(net "PE_TX1_DR13_N")
	)
	(segment
		(start 26.699718 -146.70405)
		(end 26.65349 -146.442176)
		(width 0.1651)
		(layer "In5.Cu")
		(net "PE_TX1_DR13_N")
	)
	(segment
		(start 28.382214 -144.300702)
		(end 28.497784 -143.645382)
		(width 0.1651)
		(layer "In5.Cu")
		(net "PE_TX1_DR13_N")
	)
	(segment
		(start 26.415746 -147.109688)
		(end 26.699718 -146.70405)
		(width 0.1651)
		(layer "In5.Cu")
		(net "PE_TX1_DR13_N")
	)
	(segment
		(start 23.36292 -163.326064)
		(end 23.580598 -163.173664)
		(width 0.1651)
		(layer "In5.Cu")
		(net "PE_TX1_DR13_N")
	)
	(segment
		(start 27.483562 -145.584418)
		(end 27.437334 -145.322798)
		(width 0.1651)
		(layer "In5.Cu")
		(net "PE_TX1_DR13_N")
	)
	(segment
		(start 28.497784 -143.645382)
		(end 28.333192 -142.713456)
		(width 0.1651)
		(layer "In5.Cu")
		(net "PE_TX1_DR13_N")
	)
	(segment
		(start 17.73047 -167.645334)
		(end 17.948148 -167.797734)
		(width 0.1651)
		(layer "In5.Cu")
		(net "PE_TX1_DR13_N")
	)
	(segment
		(start 23.276814 -163.813744)
		(end 23.36292 -163.326064)
		(width 0.1651)
		(layer "In5.Cu")
		(net "PE_TX1_DR13_N")
	)
	(segment
		(start 28.125674 -142.41653)
		(end 27.879548 -142.244064)
		(width 0.1651)
		(layer "In5.Cu")
		(net "PE_TX1_DR13_N")
	)
	(segment
		(start 23.514304 -162.468052)
		(end 23.60041 -161.980372)
		(width 0.1651)
		(layer "In5.Cu")
		(net "PE_TX1_DR13_N")
	)
	(segment
		(start 24.055832 -160.482026)
		(end 26.415746 -147.109688)
		(width 0.1651)
		(layer "In5.Cu")
		(net "PE_TX1_DR13_N")
	)
	(segment
		(start 28.333192 -142.713456)
		(end 28.125674 -142.41653)
		(width 0.1651)
		(layer "In5.Cu")
		(net "PE_TX1_DR13_N")
	)
	(segment
		(start 23.580598 -163.173664)
		(end 23.666704 -162.685984)
		(width 0.1651)
		(layer "In5.Cu")
		(net "PE_TX1_DR13_N")
	)
	(segment
		(start 20.454366 -167.355774)
		(end 22.225 -166.116)
		(width 0.1651)
		(layer "In5.Cu")
		(net "PE_TX1_DR13_N")
	)
	(segment
		(start 16.602456 -168.03497)
		(end 17.090136 -167.948864)
		(width 0.1651)
		(layer "In5.Cu")
		(net "PE_TX1_DR13_N")
	)
	(segment
		(start 27.199336 -145.99031)
		(end 27.483562 -145.584418)
		(width 0.1651)
		(layer "In5.Cu")
		(net "PE_TX1_DR13_N")
	)
	(segment
		(start 24.055578 -160.48228)
		(end 24.055832 -160.482026)
		(width 0.1651)
		(layer "In5.Cu")
		(net "PE_TX1_DR13_N")
	)
	(segment
		(start 23.904194 -161.340292)
		(end 23.751794 -161.12236)
		(width 0.1651)
		(layer "In5.Cu")
		(net "PE_TX1_DR13_N")
	)
	(segment
		(start 23.751794 -161.12236)
		(end 23.8379 -160.63468)
		(width 0.1651)
		(layer "In5.Cu")
		(net "PE_TX1_DR13_N")
	)
	(segment
		(start 23.8379 -160.63468)
		(end 24.055578 -160.48228)
		(width 0.1651)
		(layer "In5.Cu")
		(net "PE_TX1_DR13_N")
	)
	(segment
		(start 23.429214 -164.031676)
		(end 23.276814 -163.813744)
		(width 0.1651)
		(layer "In5.Cu")
		(net "PE_TX1_DR13_N")
	)
	(segment
		(start 23.60041 -161.980372)
		(end 23.818088 -161.827972)
		(width 0.1651)
		(layer "In5.Cu")
		(net "PE_TX1_DR13_N")
	)
	(segment
		(start 17.24279 -167.731186)
		(end 17.73047 -167.645334)
		(width 0.1651)
		(layer "In5.Cu")
		(net "PE_TX1_DR13_N")
	)
	(segment
		(start 23.343108 -164.519356)
		(end 23.429214 -164.031676)
		(width 0.1651)
		(layer "In5.Cu")
		(net "PE_TX1_DR13_N")
	)
	(segment
		(start 9.47547 -169.291762)
		(end 15.744444 -168.1861)
		(width 0.1651)
		(layer "In5.Cu")
		(net "PE_TX1_DR13_N")
	)
	(segment
		(start 27.879548 -142.244064)
		(end 27.559 -142.187422)
		(width 0.1651)
		(layer "In5.Cu")
		(net "PE_TX1_DR13_N")
	)
	(segment
		(start 27.559 -142.187422)
		(end 26.898854 -142.187422)
		(width 0.1651)
		(layer "In5.Cu")
		(net "PE_TX1_DR13_N")
	)
	(segment
		(start 26.937716 -146.036284)
		(end 27.199336 -145.99031)
		(width 0.1651)
		(layer "In5.Cu")
		(net "PE_TX1_DR13_N")
	)
	(segment
		(start 6.738112 -214.843614)
		(end 6.992366 -215.097868)
		(width 0.174752)
		(layer "F.Cu")
		(net "PE_TX1_DR12_P")
	)
	(segment
		(start 24.123396 -244.85727)
		(end 26.416254 -244.85727)
		(width 0.174752)
		(layer "F.Cu")
		(net "PE_TX1_DR12_P")
	)
	(segment
		(start 26.416254 -244.85727)
		(end 26.67 -244.603524)
		(width 0.174752)
		(layer "F.Cu")
		(net "PE_TX1_DR12_P")
	)
	(segment
		(start 23.876 -244.609874)
		(end 24.123396 -244.85727)
		(width 0.174752)
		(layer "F.Cu")
		(net "PE_TX1_DR12_P")
	)
	(segment
		(start 2.249932 -215.142064)
		(end 3.607054 -215.142064)
		(width 0.174752)
		(layer "F.Cu")
		(net "PE_TX1_DR12_P")
	)
	(segment
		(start 3.607054 -215.142064)
		(end 3.905504 -214.843614)
		(width 0.174752)
		(layer "F.Cu")
		(net "PE_TX1_DR12_P")
	)
	(segment
		(start 22.800056 -244.609874)
		(end 23.876 -244.609874)
		(width 0.174752)
		(layer "F.Cu")
		(net "PE_TX1_DR12_P")
	)
	(segment
		(start 3.905504 -214.843614)
		(end 6.738112 -214.843614)
		(width 0.174752)
		(layer "F.Cu")
		(net "PE_TX1_DR12_P")
	)
	(via
		(at 6.992366 -215.097868)
		(size 0.508)
		(drill 0.254)
		(layers "F.Cu" "B.Cu")
		(net "PE_TX1_DR12_P")
	)
	(via
		(at 26.67 -244.603524)
		(size 0.508)
		(drill 0.254)
		(layers "F.Cu" "B.Cu")
		(net "PE_TX1_DR12_P")
	)
	(segment
		(start 29.719524 -240.785396)
		(end 29.17952 -243.847366)
		(width 0.1651)
		(layer "In5.Cu")
		(net "PE_TX1_DR12_P")
	)
	(segment
		(start 31.062676 -233.167428)
		(end 30.844998 -233.320082)
		(width 0.1651)
		(layer "In5.Cu")
		(net "PE_TX1_DR12_P")
	)
	(segment
		(start 30.10789 -238.581692)
		(end 29.890212 -238.734346)
		(width 0.1651)
		(layer "In5.Cu")
		(net "PE_TX1_DR12_P")
	)
	(segment
		(start 30.996382 -232.46207)
		(end 31.148782 -232.679748)
		(width 0.1651)
		(layer "In5.Cu")
		(net "PE_TX1_DR12_P")
	)
	(segment
		(start 31.148782 -232.679748)
		(end 31.062676 -233.167428)
		(width 0.1651)
		(layer "In5.Cu")
		(net "PE_TX1_DR12_P")
	)
	(segment
		(start 30.911546 -234.02544)
		(end 30.34538 -237.236)
		(width 0.1651)
		(layer "In5.Cu")
		(net "PE_TX1_DR12_P")
	)
	(segment
		(start 31.404306 -231.231186)
		(end 31.300166 -231.821736)
		(width 0.1651)
		(layer "In5.Cu")
		(net "PE_TX1_DR12_P")
	)
	(segment
		(start 44.471336 -212.568536)
		(end 31.404306 -231.231186)
		(width 0.1651)
		(layer "In5.Cu")
		(net "PE_TX1_DR12_P")
	)
	(segment
		(start 29.652976 -240.080038)
		(end 29.56687 -240.567718)
		(width 0.1651)
		(layer "In5.Cu")
		(net "PE_TX1_DR12_P")
	)
	(segment
		(start 27.813 -244.83187)
		(end 26.898346 -244.83187)
		(width 0.1651)
		(layer "In5.Cu")
		(net "PE_TX1_DR12_P")
	)
	(segment
		(start 26.898346 -244.83187)
		(end 26.67 -244.603524)
		(width 0.1651)
		(layer "In5.Cu")
		(net "PE_TX1_DR12_P")
	)
	(segment
		(start 19.945604 -198.98614)
		(end 21.353018 -198.737982)
		(width 0.1651)
		(layer "In5.Cu")
		(net "PE_TX1_DR12_P")
	)
	(segment
		(start 29.890212 -238.734346)
		(end 29.80436 -239.222026)
		(width 0.1651)
		(layer "In5.Cu")
		(net "PE_TX1_DR12_P")
	)
	(segment
		(start 29.56687 -240.567718)
		(end 29.719524 -240.785396)
		(width 0.1651)
		(layer "In5.Cu")
		(net "PE_TX1_DR12_P")
	)
	(segment
		(start 45.044868 -209.31378)
		(end 44.471336 -212.568536)
		(width 0.1651)
		(layer "In5.Cu")
		(net "PE_TX1_DR12_P")
	)
	(segment
		(start 7.220966 -214.869268)
		(end 7.682484 -214.869268)
		(width 0.1651)
		(layer "In5.Cu")
		(net "PE_TX1_DR12_P")
	)
	(segment
		(start 29.17952 -243.847366)
		(end 28.774136 -244.426232)
		(width 0.1651)
		(layer "In5.Cu")
		(net "PE_TX1_DR12_P")
	)
	(segment
		(start 28.323286 -244.741954)
		(end 27.813 -244.83187)
		(width 0.1651)
		(layer "In5.Cu")
		(net "PE_TX1_DR12_P")
	)
	(segment
		(start 30.758892 -233.807762)
		(end 30.911546 -234.02544)
		(width 0.1651)
		(layer "In5.Cu")
		(net "PE_TX1_DR12_P")
	)
	(segment
		(start 22.69871 -198.500492)
		(end 39.4589 -201.454258)
		(width 0.1651)
		(layer "In5.Cu")
		(net "PE_TX1_DR12_P")
	)
	(segment
		(start 10.590784 -213.393528)
		(end 11.029442 -212.767418)
		(width 0.1651)
		(layer "In5.Cu")
		(net "PE_TX1_DR12_P")
	)
	(segment
		(start 12.51966 -210.639152)
		(end 13.25626 -206.46009)
		(width 0.1651)
		(layer "In5.Cu")
		(net "PE_TX1_DR12_P")
	)
	(segment
		(start 44.506896 -206.2607)
		(end 45.044868 -209.31378)
		(width 0.1651)
		(layer "In5.Cu")
		(net "PE_TX1_DR12_P")
	)
	(segment
		(start 29.95676 -239.439704)
		(end 29.870654 -239.927384)
		(width 0.1651)
		(layer "In5.Cu")
		(net "PE_TX1_DR12_P")
	)
	(segment
		(start 8.752078 -214.680546)
		(end 10.590784 -213.393528)
		(width 0.1651)
		(layer "In5.Cu")
		(net "PE_TX1_DR12_P")
	)
	(segment
		(start 13.25626 -206.46009)
		(end 17.089628 -200.985882)
		(width 0.1651)
		(layer "In5.Cu")
		(net "PE_TX1_DR12_P")
	)
	(segment
		(start 28.774136 -244.426232)
		(end 28.323286 -244.741954)
		(width 0.1651)
		(layer "In5.Cu")
		(net "PE_TX1_DR12_P")
	)
	(segment
		(start 30.34538 -237.236)
		(end 30.127702 -237.3884)
		(width 0.1651)
		(layer "In5.Cu")
		(net "PE_TX1_DR12_P")
	)
	(segment
		(start 31.300166 -231.821736)
		(end 31.082488 -231.97439)
		(width 0.1651)
		(layer "In5.Cu")
		(net "PE_TX1_DR12_P")
	)
	(segment
		(start 11.291062 -212.72119)
		(end 11.575288 -212.315552)
		(width 0.1651)
		(layer "In5.Cu")
		(net "PE_TX1_DR12_P")
	)
	(segment
		(start 7.682484 -214.869268)
		(end 8.752078 -214.680546)
		(width 0.1651)
		(layer "In5.Cu")
		(net "PE_TX1_DR12_P")
	)
	(segment
		(start 42.760138 -203.766166)
		(end 44.506896 -206.2607)
		(width 0.1651)
		(layer "In5.Cu")
		(net "PE_TX1_DR12_P")
	)
	(segment
		(start 6.992366 -215.097868)
		(end 7.220966 -214.869268)
		(width 0.1651)
		(layer "In5.Cu")
		(net "PE_TX1_DR12_P")
	)
	(segment
		(start 22.21103 -198.586598)
		(end 22.69871 -198.500492)
		(width 0.1651)
		(layer "In5.Cu")
		(net "PE_TX1_DR12_P")
	)
	(segment
		(start 31.082488 -231.97439)
		(end 30.996382 -232.46207)
		(width 0.1651)
		(layer "In5.Cu")
		(net "PE_TX1_DR12_P")
	)
	(segment
		(start 21.570696 -198.890382)
		(end 22.058376 -198.804276)
		(width 0.1651)
		(layer "In5.Cu")
		(net "PE_TX1_DR12_P")
	)
	(segment
		(start 11.575288 -212.315552)
		(end 11.52906 -212.053678)
		(width 0.1651)
		(layer "In5.Cu")
		(net "PE_TX1_DR12_P")
	)
	(segment
		(start 30.127702 -237.3884)
		(end 30.041596 -237.876334)
		(width 0.1651)
		(layer "In5.Cu")
		(net "PE_TX1_DR12_P")
	)
	(segment
		(start 21.353018 -198.737982)
		(end 21.570696 -198.890382)
		(width 0.1651)
		(layer "In5.Cu")
		(net "PE_TX1_DR12_P")
	)
	(segment
		(start 30.193996 -238.094012)
		(end 30.10789 -238.581692)
		(width 0.1651)
		(layer "In5.Cu")
		(net "PE_TX1_DR12_P")
	)
	(segment
		(start 22.058376 -198.804276)
		(end 22.21103 -198.586598)
		(width 0.1651)
		(layer "In5.Cu")
		(net "PE_TX1_DR12_P")
	)
	(segment
		(start 39.4589 -201.454258)
		(end 42.760138 -203.766166)
		(width 0.1651)
		(layer "In5.Cu")
		(net "PE_TX1_DR12_P")
	)
	(segment
		(start 11.52906 -212.053678)
		(end 12.51966 -210.639152)
		(width 0.1651)
		(layer "In5.Cu")
		(net "PE_TX1_DR12_P")
	)
	(segment
		(start 17.089628 -200.985882)
		(end 19.945604 -198.98614)
		(width 0.1651)
		(layer "In5.Cu")
		(net "PE_TX1_DR12_P")
	)
	(segment
		(start 29.80436 -239.222026)
		(end 29.95676 -239.439704)
		(width 0.1651)
		(layer "In5.Cu")
		(net "PE_TX1_DR12_P")
	)
	(segment
		(start 29.870654 -239.927384)
		(end 29.652976 -240.080038)
		(width 0.1651)
		(layer "In5.Cu")
		(net "PE_TX1_DR12_P")
	)
	(segment
		(start 30.844998 -233.320082)
		(end 30.758892 -233.807762)
		(width 0.1651)
		(layer "In5.Cu")
		(net "PE_TX1_DR12_P")
	)
	(segment
		(start 30.041596 -237.876334)
		(end 30.193996 -238.094012)
		(width 0.1651)
		(layer "In5.Cu")
		(net "PE_TX1_DR12_P")
	)
	(segment
		(start 11.029442 -212.767418)
		(end 11.291062 -212.72119)
		(width 0.1651)
		(layer "In5.Cu")
		(net "PE_TX1_DR12_P")
	)
	(segment
		(start 3.709162 -214.342218)
		(end 3.905504 -214.53856)
		(width 0.174752)
		(layer "F.Cu")
		(net "PE_TX1_DR12_N")
	)
	(segment
		(start 26.416 -245.162324)
		(end 26.67 -245.416324)
		(width 0.174752)
		(layer "F.Cu")
		(net "PE_TX1_DR12_N")
	)
	(segment
		(start 2.249932 -214.342218)
		(end 3.709162 -214.342218)
		(width 0.174752)
		(layer "F.Cu")
		(net "PE_TX1_DR12_N")
	)
	(segment
		(start 6.738874 -214.53856)
		(end 6.992366 -214.285068)
		(width 0.174752)
		(layer "F.Cu")
		(net "PE_TX1_DR12_N")
	)
	(segment
		(start 3.905504 -214.53856)
		(end 6.738874 -214.53856)
		(width 0.174752)
		(layer "F.Cu")
		(net "PE_TX1_DR12_N")
	)
	(segment
		(start 23.88235 -245.409974)
		(end 24.13 -245.162324)
		(width 0.174752)
		(layer "F.Cu")
		(net "PE_TX1_DR12_N")
	)
	(segment
		(start 22.800056 -245.409974)
		(end 23.88235 -245.409974)
		(width 0.174752)
		(layer "F.Cu")
		(net "PE_TX1_DR12_N")
	)
	(segment
		(start 24.13 -245.162324)
		(end 26.416 -245.162324)
		(width 0.174752)
		(layer "F.Cu")
		(net "PE_TX1_DR12_N")
	)
	(via
		(at 6.992366 -214.285068)
		(size 0.508)
		(drill 0.254)
		(layers "F.Cu" "B.Cu")
		(net "PE_TX1_DR12_N")
	)
	(via
		(at 26.67 -245.416324)
		(size 0.508)
		(drill 0.254)
		(layers "F.Cu" "B.Cu")
		(net "PE_TX1_DR12_N")
	)
	(segment
		(start 22.69871 -198.139304)
		(end 39.598346 -201.117708)
		(width 0.1651)
		(layer "In5.Cu")
		(net "PE_TX1_DR12_N")
	)
	(segment
		(start 31.740856 -231.370632)
		(end 29.51607 -243.986812)
		(width 0.1651)
		(layer "In5.Cu")
		(net "PE_TX1_DR12_N")
	)
	(segment
		(start 19.806158 -198.64959)
		(end 22.69871 -198.139304)
		(width 0.1651)
		(layer "In5.Cu")
		(net "PE_TX1_DR12_N")
	)
	(segment
		(start 26.898854 -245.18747)
		(end 26.67 -245.416324)
		(width 0.1651)
		(layer "In5.Cu")
		(net "PE_TX1_DR12_N")
	)
	(segment
		(start 28.462732 -245.078504)
		(end 27.844242 -245.18747)
		(width 0.1651)
		(layer "In5.Cu")
		(net "PE_TX1_DR12_N")
	)
	(segment
		(start 45.406056 -209.31378)
		(end 44.807886 -212.707982)
		(width 0.1651)
		(layer "In5.Cu")
		(net "PE_TX1_DR12_N")
	)
	(segment
		(start 7.220966 -214.513668)
		(end 7.651242 -214.513668)
		(width 0.1651)
		(layer "In5.Cu")
		(net "PE_TX1_DR12_N")
	)
	(segment
		(start 29.51607 -243.986812)
		(end 29.02966 -244.681756)
		(width 0.1651)
		(layer "In5.Cu")
		(net "PE_TX1_DR12_N")
	)
	(segment
		(start 6.992366 -214.285068)
		(end 7.220966 -214.513668)
		(width 0.1651)
		(layer "In5.Cu")
		(net "PE_TX1_DR12_N")
	)
	(segment
		(start 10.335768 -213.137496)
		(end 12.18311 -210.499706)
		(width 0.1651)
		(layer "In5.Cu")
		(net "PE_TX1_DR12_N")
	)
	(segment
		(start 7.651242 -214.513668)
		(end 8.612378 -214.343996)
		(width 0.1651)
		(layer "In5.Cu")
		(net "PE_TX1_DR12_N")
	)
	(segment
		(start 44.843446 -206.121254)
		(end 45.406056 -209.31378)
		(width 0.1651)
		(layer "In5.Cu")
		(net "PE_TX1_DR12_N")
	)
	(segment
		(start 43.015662 -203.510642)
		(end 44.843446 -206.121254)
		(width 0.1651)
		(layer "In5.Cu")
		(net "PE_TX1_DR12_N")
	)
	(segment
		(start 27.844242 -245.18747)
		(end 26.898854 -245.18747)
		(width 0.1651)
		(layer "In5.Cu")
		(net "PE_TX1_DR12_N")
	)
	(segment
		(start 12.91971 -206.320644)
		(end 16.834104 -200.730358)
		(width 0.1651)
		(layer "In5.Cu")
		(net "PE_TX1_DR12_N")
	)
	(segment
		(start 29.02966 -244.681756)
		(end 28.462732 -245.078504)
		(width 0.1651)
		(layer "In5.Cu")
		(net "PE_TX1_DR12_N")
	)
	(segment
		(start 16.834104 -200.730358)
		(end 19.806158 -198.64959)
		(width 0.1651)
		(layer "In5.Cu")
		(net "PE_TX1_DR12_N")
	)
	(segment
		(start 39.598346 -201.117708)
		(end 43.015662 -203.510642)
		(width 0.1651)
		(layer "In5.Cu")
		(net "PE_TX1_DR12_N")
	)
	(segment
		(start 8.612378 -214.343996)
		(end 10.335768 -213.137496)
		(width 0.1651)
		(layer "In5.Cu")
		(net "PE_TX1_DR12_N")
	)
	(segment
		(start 44.807886 -212.707982)
		(end 31.740856 -231.370632)
		(width 0.1651)
		(layer "In5.Cu")
		(net "PE_TX1_DR12_N")
	)
	(segment
		(start 12.18311 -210.499706)
		(end 12.91971 -206.320644)
		(width 0.1651)
		(layer "In5.Cu")
		(net "PE_TX1_DR12_N")
	)
	(segment
		(start 26.416254 -347.857318)
		(end 26.67 -347.603572)
		(width 0.174752)
		(layer "F.Cu")
		(net "PE_TX1_DR11_P")
	)
	(segment
		(start 6.738366 -334.545432)
		(end 6.992366 -334.799432)
		(width 0.174752)
		(layer "F.Cu")
		(net "PE_TX1_DR11_P")
	)
	(segment
		(start 3.657854 -334.742028)
		(end 3.85445 -334.545432)
		(width 0.174752)
		(layer "F.Cu")
		(net "PE_TX1_DR11_P")
	)
	(segment
		(start 23.876 -347.609922)
		(end 24.123396 -347.857318)
		(width 0.174752)
		(layer "F.Cu")
		(net "PE_TX1_DR11_P")
	)
	(segment
		(start 2.249932 -334.742028)
		(end 3.657854 -334.742028)
		(width 0.174752)
		(layer "F.Cu")
		(net "PE_TX1_DR11_P")
	)
	(segment
		(start 24.123396 -347.857318)
		(end 26.416254 -347.857318)
		(width 0.174752)
		(layer "F.Cu")
		(net "PE_TX1_DR11_P")
	)
	(segment
		(start 3.85445 -334.545432)
		(end 6.738366 -334.545432)
		(width 0.174752)
		(layer "F.Cu")
		(net "PE_TX1_DR11_P")
	)
	(segment
		(start 22.800056 -347.609922)
		(end 23.876 -347.609922)
		(width 0.174752)
		(layer "F.Cu")
		(net "PE_TX1_DR11_P")
	)
	(via
		(at 26.67 -347.603572)
		(size 0.508)
		(drill 0.254)
		(layers "F.Cu" "B.Cu")
		(net "PE_TX1_DR11_P")
	)
	(via
		(at 6.992366 -334.799432)
		(size 0.508)
		(drill 0.254)
		(layers "F.Cu" "B.Cu")
		(net "PE_TX1_DR11_P")
	)
	(segment
		(start 28.669996 -348.58325)
		(end 28.670758 -348.583758)
		(width 0.1651)
		(layer "In5.Cu")
		(net "PE_TX1_DR11_P")
	)
	(segment
		(start 21.992082 -351.995486)
		(end 21.336 -351.536)
		(width 0.1651)
		(layer "In5.Cu")
		(net "PE_TX1_DR11_P")
	)
	(segment
		(start 27.9527 -347.895926)
		(end 28.41625 -348.22003)
		(width 0.1651)
		(layer "In5.Cu")
		(net "PE_TX1_DR11_P")
	)
	(segment
		(start 27.96032 -350.829118)
		(end 26.788364 -351.649792)
		(width 0.1651)
		(layer "In5.Cu")
		(net "PE_TX1_DR11_P")
	)
	(segment
		(start 16.32077 -346.748608)
		(end 15.33652 -341.168736)
		(width 0.1651)
		(layer "In5.Cu")
		(net "PE_TX1_DR11_P")
	)
	(segment
		(start 28.41625 -348.22003)
		(end 28.669996 -348.58325)
		(width 0.1651)
		(layer "In5.Cu")
		(net "PE_TX1_DR11_P")
	)
	(segment
		(start 26.788364 -351.649792)
		(end 23.410926 -352.245676)
		(width 0.1651)
		(layer "In5.Cu")
		(net "PE_TX1_DR11_P")
	)
	(segment
		(start 20.498308 -350.366584)
		(end 17.272 -348.107)
		(width 0.1651)
		(layer "In5.Cu")
		(net "PE_TX1_DR11_P")
	)
	(segment
		(start 28.670758 -348.583758)
		(end 28.777692 -349.19158)
		(width 0.1651)
		(layer "In5.Cu")
		(net "PE_TX1_DR11_P")
	)
	(segment
		(start 28.777692 -349.19158)
		(end 28.666948 -349.819976)
		(width 0.1651)
		(layer "In5.Cu")
		(net "PE_TX1_DR11_P")
	)
	(segment
		(start 27.590242 -347.831918)
		(end 27.9527 -347.895926)
		(width 0.1651)
		(layer "In5.Cu")
		(net "PE_TX1_DR11_P")
	)
	(segment
		(start 21.336 -351.536)
		(end 20.560792 -350.428814)
		(width 0.1651)
		(layer "In5.Cu")
		(net "PE_TX1_DR11_P")
	)
	(segment
		(start 28.666948 -349.819976)
		(end 27.96032 -350.829118)
		(width 0.1651)
		(layer "In5.Cu")
		(net "PE_TX1_DR11_P")
	)
	(segment
		(start 23.410926 -352.245676)
		(end 21.992082 -351.995486)
		(width 0.1651)
		(layer "In5.Cu")
		(net "PE_TX1_DR11_P")
	)
	(segment
		(start 26.67 -347.603572)
		(end 26.898346 -347.831918)
		(width 0.1651)
		(layer "In5.Cu")
		(net "PE_TX1_DR11_P")
	)
	(segment
		(start 12.629896 -337.303364)
		(end 9.003284 -334.763872)
		(width 0.1651)
		(layer "In5.Cu")
		(net "PE_TX1_DR11_P")
	)
	(segment
		(start 7.908036 -334.570832)
		(end 7.220966 -334.570832)
		(width 0.1651)
		(layer "In5.Cu")
		(net "PE_TX1_DR11_P")
	)
	(segment
		(start 7.220966 -334.570832)
		(end 6.992366 -334.799432)
		(width 0.1651)
		(layer "In5.Cu")
		(net "PE_TX1_DR11_P")
	)
	(segment
		(start 26.898346 -347.831918)
		(end 27.590242 -347.831918)
		(width 0.1651)
		(layer "In5.Cu")
		(net "PE_TX1_DR11_P")
	)
	(segment
		(start 9.003284 -334.763872)
		(end 7.908036 -334.570832)
		(width 0.1651)
		(layer "In5.Cu")
		(net "PE_TX1_DR11_P")
	)
	(segment
		(start 17.272 -348.107)
		(end 16.32077 -346.748608)
		(width 0.1651)
		(layer "In5.Cu")
		(net "PE_TX1_DR11_P")
	)
	(segment
		(start 15.33652 -341.168736)
		(end 12.629896 -337.303364)
		(width 0.1651)
		(layer "In5.Cu")
		(net "PE_TX1_DR11_P")
	)
	(arc
		(start 20.560792 -350.428814)
		(mid 20.532279 -350.394958)
		(end 20.498308 -350.366584)
		(width 0.1651)
		(layer "In5.Cu")
		(net "PE_TX1_DR11_P")
	)
	(segment
		(start 2.249932 -333.942182)
		(end 3.657854 -333.942182)
		(width 0.174752)
		(layer "F.Cu")
		(net "PE_TX1_DR11_N")
	)
	(segment
		(start 26.416 -348.162372)
		(end 26.67 -348.416372)
		(width 0.174752)
		(layer "F.Cu")
		(net "PE_TX1_DR11_N")
	)
	(segment
		(start 22.800056 -348.410022)
		(end 23.88235 -348.410022)
		(width 0.174752)
		(layer "F.Cu")
		(net "PE_TX1_DR11_N")
	)
	(segment
		(start 24.13 -348.162372)
		(end 26.416 -348.162372)
		(width 0.174752)
		(layer "F.Cu")
		(net "PE_TX1_DR11_N")
	)
	(segment
		(start 3.95605 -334.240378)
		(end 6.73862 -334.240378)
		(width 0.174752)
		(layer "F.Cu")
		(net "PE_TX1_DR11_N")
	)
	(segment
		(start 6.73862 -334.240378)
		(end 6.992366 -333.986632)
		(width 0.174752)
		(layer "F.Cu")
		(net "PE_TX1_DR11_N")
	)
	(segment
		(start 3.657854 -333.942182)
		(end 3.95605 -334.240378)
		(width 0.174752)
		(layer "F.Cu")
		(net "PE_TX1_DR11_N")
	)
	(segment
		(start 23.88235 -348.410022)
		(end 24.13 -348.162372)
		(width 0.174752)
		(layer "F.Cu")
		(net "PE_TX1_DR11_N")
	)
	(via
		(at 26.67 -348.416372)
		(size 0.508)
		(drill 0.254)
		(layers "F.Cu" "B.Cu")
		(net "PE_TX1_DR11_N")
	)
	(via
		(at 6.992366 -333.986632)
		(size 0.508)
		(drill 0.254)
		(layers "F.Cu" "B.Cu")
		(net "PE_TX1_DR11_N")
	)
	(segment
		(start 10.667746 -335.495138)
		(end 10.262108 -335.211166)
		(width 0.1651)
		(layer "In5.Cu")
		(net "PE_TX1_DR11_N")
	)
	(segment
		(start 16.027654 -341.957406)
		(end 15.809976 -341.805006)
		(width 0.1651)
		(layer "In5.Cu")
		(net "PE_TX1_DR11_N")
	)
	(segment
		(start 16.198596 -344.00871)
		(end 16.35125 -343.791032)
		(width 0.1651)
		(layer "In5.Cu")
		(net "PE_TX1_DR11_N")
	)
	(segment
		(start 16.35125 -343.791032)
		(end 16.265144 -343.303352)
		(width 0.1651)
		(layer "In5.Cu")
		(net "PE_TX1_DR11_N")
	)
	(segment
		(start 16.588486 -345.136724)
		(end 16.50238 -344.649044)
		(width 0.1651)
		(layer "In5.Cu")
		(net "PE_TX1_DR11_N")
	)
	(segment
		(start 10.21588 -334.949292)
		(end 9.810242 -334.66532)
		(width 0.1651)
		(layer "In5.Cu")
		(net "PE_TX1_DR11_N")
	)
	(segment
		(start 22.131528 -351.658936)
		(end 21.591524 -351.280476)
		(width 0.1651)
		(layer "In5.Cu")
		(net "PE_TX1_DR11_N")
	)
	(segment
		(start 15.809976 -341.805006)
		(end 15.67307 -341.02929)
		(width 0.1651)
		(layer "In5.Cu")
		(net "PE_TX1_DR11_N")
	)
	(segment
		(start 12.88542 -337.04784)
		(end 11.381486 -335.99501)
		(width 0.1651)
		(layer "In5.Cu")
		(net "PE_TX1_DR11_N")
	)
	(segment
		(start 28.333954 -348.723204)
		(end 28.416504 -349.19158)
		(width 0.1651)
		(layer "In5.Cu")
		(net "PE_TX1_DR11_N")
	)
	(segment
		(start 13.715238 -337.905598)
		(end 13.431266 -337.499706)
		(width 0.1651)
		(layer "In5.Cu")
		(net "PE_TX1_DR11_N")
	)
	(segment
		(start 7.220966 -334.215232)
		(end 6.992366 -333.986632)
		(width 0.1651)
		(layer "In5.Cu")
		(net "PE_TX1_DR11_N")
	)
	(segment
		(start 27.704796 -350.573594)
		(end 26.648918 -351.312988)
		(width 0.1651)
		(layer "In5.Cu")
		(net "PE_TX1_DR11_N")
	)
	(segment
		(start 16.047466 -343.150698)
		(end 15.96136 -342.663018)
		(width 0.1651)
		(layer "In5.Cu")
		(net "PE_TX1_DR11_N")
	)
	(segment
		(start 17.527524 -347.851476)
		(end 16.65732 -346.609162)
		(width 0.1651)
		(layer "In5.Cu")
		(net "PE_TX1_DR11_N")
	)
	(segment
		(start 9.14273 -334.427322)
		(end 7.939278 -334.215232)
		(width 0.1651)
		(layer "In5.Cu")
		(net "PE_TX1_DR11_N")
	)
	(segment
		(start 9.810242 -334.66532)
		(end 9.548368 -334.711294)
		(width 0.1651)
		(layer "In5.Cu")
		(net "PE_TX1_DR11_N")
	)
	(segment
		(start 14.21511 -338.619084)
		(end 13.953236 -338.57311)
		(width 0.1651)
		(layer "In5.Cu")
		(net "PE_TX1_DR11_N")
	)
	(segment
		(start 16.436086 -345.354402)
		(end 16.588486 -345.136724)
		(width 0.1651)
		(layer "In5.Cu")
		(net "PE_TX1_DR11_N")
	)
	(segment
		(start 10.92962 -335.44891)
		(end 10.667746 -335.495138)
		(width 0.1651)
		(layer "In5.Cu")
		(net "PE_TX1_DR11_N")
	)
	(segment
		(start 13.169392 -337.453478)
		(end 12.88542 -337.04784)
		(width 0.1651)
		(layer "In5.Cu")
		(net "PE_TX1_DR11_N")
	)
	(segment
		(start 13.669264 -338.167218)
		(end 13.715238 -337.905598)
		(width 0.1651)
		(layer "In5.Cu")
		(net "PE_TX1_DR11_N")
	)
	(segment
		(start 14.452854 -339.286596)
		(end 14.499082 -339.024976)
		(width 0.1651)
		(layer "In5.Cu")
		(net "PE_TX1_DR11_N")
	)
	(segment
		(start 14.499082 -339.024976)
		(end 14.21511 -338.619084)
		(width 0.1651)
		(layer "In5.Cu")
		(net "PE_TX1_DR11_N")
	)
	(segment
		(start 15.96136 -342.663018)
		(end 16.11376 -342.44534)
		(width 0.1651)
		(layer "In5.Cu")
		(net "PE_TX1_DR11_N")
	)
	(segment
		(start 27.813254 -348.232476)
		(end 28.160726 -348.475554)
		(width 0.1651)
		(layer "In5.Cu")
		(net "PE_TX1_DR11_N")
	)
	(segment
		(start 16.265144 -343.303352)
		(end 16.047466 -343.150698)
		(width 0.1651)
		(layer "In5.Cu")
		(net "PE_TX1_DR11_N")
	)
	(segment
		(start 9.548368 -334.711294)
		(end 9.14273 -334.427322)
		(width 0.1651)
		(layer "In5.Cu")
		(net "PE_TX1_DR11_N")
	)
	(segment
		(start 26.898854 -348.187518)
		(end 27.559 -348.187518)
		(width 0.1651)
		(layer "In5.Cu")
		(net "PE_TX1_DR11_N")
	)
	(segment
		(start 27.559 -348.187518)
		(end 27.813254 -348.232476)
		(width 0.1651)
		(layer "In5.Cu")
		(net "PE_TX1_DR11_N")
	)
	(segment
		(start 15.67307 -341.02929)
		(end 14.452854 -339.286596)
		(width 0.1651)
		(layer "In5.Cu")
		(net "PE_TX1_DR11_N")
	)
	(segment
		(start 11.381486 -335.99501)
		(end 11.335258 -335.733136)
		(width 0.1651)
		(layer "In5.Cu")
		(net "PE_TX1_DR11_N")
	)
	(segment
		(start 21.591524 -351.280476)
		(end 20.852638 -350.224852)
		(width 0.1651)
		(layer "In5.Cu")
		(net "PE_TX1_DR11_N")
	)
	(segment
		(start 28.330398 -349.68053)
		(end 27.705304 -350.57334)
		(width 0.1651)
		(layer "In5.Cu")
		(net "PE_TX1_DR11_N")
	)
	(segment
		(start 23.410926 -351.884488)
		(end 22.131528 -351.658936)
		(width 0.1651)
		(layer "In5.Cu")
		(net "PE_TX1_DR11_N")
	)
	(segment
		(start 20.70227 -350.074992)
		(end 17.527524 -347.851476)
		(width 0.1651)
		(layer "In5.Cu")
		(net "PE_TX1_DR11_N")
	)
	(segment
		(start 16.284702 -344.49639)
		(end 16.198596 -344.00871)
		(width 0.1651)
		(layer "In5.Cu")
		(net "PE_TX1_DR11_N")
	)
	(segment
		(start 11.335258 -335.733136)
		(end 10.92962 -335.44891)
		(width 0.1651)
		(layer "In5.Cu")
		(net "PE_TX1_DR11_N")
	)
	(segment
		(start 16.11376 -342.44534)
		(end 16.027654 -341.957406)
		(width 0.1651)
		(layer "In5.Cu")
		(net "PE_TX1_DR11_N")
	)
	(segment
		(start 16.50238 -344.649044)
		(end 16.284702 -344.49639)
		(width 0.1651)
		(layer "In5.Cu")
		(net "PE_TX1_DR11_N")
	)
	(segment
		(start 16.65732 -346.609162)
		(end 16.436086 -345.354402)
		(width 0.1651)
		(layer "In5.Cu")
		(net "PE_TX1_DR11_N")
	)
	(segment
		(start 26.67 -348.416372)
		(end 26.898854 -348.187518)
		(width 0.1651)
		(layer "In5.Cu")
		(net "PE_TX1_DR11_N")
	)
	(segment
		(start 13.953236 -338.57311)
		(end 13.669264 -338.167218)
		(width 0.1651)
		(layer "In5.Cu")
		(net "PE_TX1_DR11_N")
	)
	(segment
		(start 27.705304 -350.57334)
		(end 27.704796 -350.573594)
		(width 0.1651)
		(layer "In5.Cu")
		(net "PE_TX1_DR11_N")
	)
	(segment
		(start 7.939278 -334.215232)
		(end 7.220966 -334.215232)
		(width 0.1651)
		(layer "In5.Cu")
		(net "PE_TX1_DR11_N")
	)
	(segment
		(start 13.431266 -337.499706)
		(end 13.169392 -337.453478)
		(width 0.1651)
		(layer "In5.Cu")
		(net "PE_TX1_DR11_N")
	)
	(segment
		(start 26.648918 -351.312988)
		(end 23.410926 -351.884488)
		(width 0.1651)
		(layer "In5.Cu")
		(net "PE_TX1_DR11_N")
	)
	(segment
		(start 10.262108 -335.211166)
		(end 10.21588 -334.949292)
		(width 0.1651)
		(layer "In5.Cu")
		(net "PE_TX1_DR11_N")
	)
	(segment
		(start 28.416504 -349.19158)
		(end 28.330398 -349.68053)
		(width 0.1651)
		(layer "In5.Cu")
		(net "PE_TX1_DR11_N")
	)
	(segment
		(start 28.160726 -348.475554)
		(end 28.333954 -348.723204)
		(width 0.1651)
		(layer "In5.Cu")
		(net "PE_TX1_DR11_N")
	)
	(arc
		(start 20.702778 -350.075246)
		(mid 20.702524 -350.075119)
		(end 20.70227 -350.074992)
		(width 0.1651)
		(layer "In5.Cu")
		(net "PE_TX1_DR11_N")
	)
	(arc
		(start 20.852638 -350.224852)
		(mid 20.784261 -350.143484)
		(end 20.702778 -350.075246)
		(width 0.1651)
		(layer "In5.Cu")
		(net "PE_TX1_DR11_N")
	)
	(segment
		(start 26.67 -451.41642)
		(end 26.4414 -451.18782)
		(width 0.174752)
		(layer "F.Cu")
		(net "PE_TX1_DR10_P")
	)
	(segment
		(start 23.95093 -451.41007)
		(end 22.800056 -451.41007)
		(width 0.174752)
		(layer "F.Cu")
		(net "PE_TX1_DR10_P")
	)
	(segment
		(start 24.17318 -451.18782)
		(end 23.95093 -451.41007)
		(width 0.174752)
		(layer "F.Cu")
		(net "PE_TX1_DR10_P")
	)
	(segment
		(start 6.738874 -402.589238)
		(end 6.992366 -402.335746)
		(width 0.174752)
		(layer "F.Cu")
		(net "PE_TX1_DR10_P")
	)
	(segment
		(start 26.4414 -451.18782)
		(end 24.17318 -451.18782)
		(width 0.174752)
		(layer "F.Cu")
		(net "PE_TX1_DR10_P")
	)
	(segment
		(start 2.249932 -402.341842)
		(end 3.658108 -402.341842)
		(width 0.174752)
		(layer "F.Cu")
		(net "PE_TX1_DR10_P")
	)
	(segment
		(start 3.905504 -402.589238)
		(end 6.738874 -402.589238)
		(width 0.174752)
		(layer "F.Cu")
		(net "PE_TX1_DR10_P")
	)
	(segment
		(start 3.658108 -402.341842)
		(end 3.905504 -402.589238)
		(width 0.174752)
		(layer "F.Cu")
		(net "PE_TX1_DR10_P")
	)
	(via
		(at 6.992366 -402.335746)
		(size 0.508)
		(drill 0.254)
		(layers "F.Cu" "B.Cu")
		(net "PE_TX1_DR10_P")
	)
	(via
		(at 26.67 -451.41642)
		(size 0.508)
		(drill 0.254)
		(layers "F.Cu" "B.Cu")
		(net "PE_TX1_DR10_P")
	)
	(segment
		(start 43.04157 -410.771086)
		(end 41.643046 -409.791916)
		(width 0.1651)
		(layer "In5.Cu")
		(net "PE_TX1_DR10_P")
	)
	(segment
		(start 7.220966 -402.564346)
		(end 6.992366 -402.335746)
		(width 0.1651)
		(layer "In5.Cu")
		(net "PE_TX1_DR10_P")
	)
	(segment
		(start 7.651242 -402.564346)
		(end 7.220966 -402.564346)
		(width 0.1651)
		(layer "In5.Cu")
		(net "PE_TX1_DR10_P")
	)
	(segment
		(start 43.862244 -422.28135)
		(end 45.158406 -414.929828)
		(width 0.1651)
		(layer "In5.Cu")
		(net "PE_TX1_DR10_P")
	)
	(segment
		(start 43.76166 -422.52519)
		(end 43.761406 -422.524936)
		(width 0.1651)
		(layer "In5.Cu")
		(net "PE_TX1_DR10_P")
	)
	(segment
		(start 29.256228 -450.515482)
		(end 29.54655 -450.100446)
		(width 0.1651)
		(layer "In5.Cu")
		(net "PE_TX1_DR10_P")
	)
	(segment
		(start 12.99972 -403.507702)
		(end 7.651242 -402.564346)
		(width 0.1651)
		(layer "In5.Cu")
		(net "PE_TX1_DR10_P")
	)
	(segment
		(start 43.862244 -422.281096)
		(end 43.862244 -422.28135)
		(width 0.1651)
		(layer "In5.Cu")
		(net "PE_TX1_DR10_P")
	)
	(segment
		(start 41.643046 -409.791916)
		(end 15.35684 -405.158194)
		(width 0.1651)
		(layer "In5.Cu")
		(net "PE_TX1_DR10_P")
	)
	(segment
		(start 26.898854 -451.187566)
		(end 27.717242 -451.187566)
		(width 0.1651)
		(layer "In5.Cu")
		(net "PE_TX1_DR10_P")
	)
	(segment
		(start 31.260542 -440.377834)
		(end 43.76166 -422.52519)
		(width 0.1651)
		(layer "In5.Cu")
		(net "PE_TX1_DR10_P")
	)
	(segment
		(start 26.67 -451.41642)
		(end 26.898854 -451.187566)
		(width 0.1651)
		(layer "In5.Cu")
		(net "PE_TX1_DR10_P")
	)
	(segment
		(start 27.717242 -451.187566)
		(end 28.490926 -451.050914)
		(width 0.1651)
		(layer "In5.Cu")
		(net "PE_TX1_DR10_P")
	)
	(segment
		(start 29.256228 -450.515228)
		(end 29.256228 -450.515482)
		(width 0.1651)
		(layer "In5.Cu")
		(net "PE_TX1_DR10_P")
	)
	(segment
		(start 45.158406 -414.929828)
		(end 44.89069 -413.412686)
		(width 0.1651)
		(layer "In5.Cu")
		(net "PE_TX1_DR10_P")
	)
	(segment
		(start 44.89069 -413.412686)
		(end 43.04157 -410.771086)
		(width 0.1651)
		(layer "In5.Cu")
		(net "PE_TX1_DR10_P")
	)
	(segment
		(start 15.35684 -405.158194)
		(end 12.99972 -403.507702)
		(width 0.1651)
		(layer "In5.Cu")
		(net "PE_TX1_DR10_P")
	)
	(segment
		(start 29.54655 -450.100446)
		(end 31.260542 -440.377834)
		(width 0.1651)
		(layer "In5.Cu")
		(net "PE_TX1_DR10_P")
	)
	(segment
		(start 28.490926 -451.050914)
		(end 29.256228 -450.515228)
		(width 0.1651)
		(layer "In5.Cu")
		(net "PE_TX1_DR10_P")
	)
	(arc
		(start 43.761406 -422.524936)
		(mid 43.825151 -422.40853)
		(end 43.862244 -422.281096)
		(width 0.1651)
		(layer "In5.Cu")
		(net "PE_TX1_DR10_P")
	)
	(segment
		(start 26.67 -450.60362)
		(end 26.390854 -450.882766)
		(width 0.174752)
		(layer "F.Cu")
		(net "PE_TX1_DR10_N")
	)
	(segment
		(start 3.905504 -402.894292)
		(end 6.738112 -402.894292)
		(width 0.174752)
		(layer "F.Cu")
		(net "PE_TX1_DR10_N")
	)
	(segment
		(start 2.249932 -403.141942)
		(end 3.657854 -403.141942)
		(width 0.174752)
		(layer "F.Cu")
		(net "PE_TX1_DR10_N")
	)
	(segment
		(start 23.88997 -450.60997)
		(end 22.800056 -450.60997)
		(width 0.174752)
		(layer "F.Cu")
		(net "PE_TX1_DR10_N")
	)
	(segment
		(start 3.657854 -403.141942)
		(end 3.905504 -402.894292)
		(width 0.174752)
		(layer "F.Cu")
		(net "PE_TX1_DR10_N")
	)
	(segment
		(start 24.162766 -450.882766)
		(end 23.88997 -450.60997)
		(width 0.174752)
		(layer "F.Cu")
		(net "PE_TX1_DR10_N")
	)
	(segment
		(start 26.390854 -450.882766)
		(end 24.162766 -450.882766)
		(width 0.174752)
		(layer "F.Cu")
		(net "PE_TX1_DR10_N")
	)
	(segment
		(start 6.738112 -402.894292)
		(end 6.992366 -403.148546)
		(width 0.174752)
		(layer "F.Cu")
		(net "PE_TX1_DR10_N")
	)
	(via
		(at 26.67 -450.60362)
		(size 0.508)
		(drill 0.254)
		(layers "F.Cu" "B.Cu")
		(net "PE_TX1_DR10_N")
	)
	(via
		(at 6.992366 -403.148546)
		(size 0.508)
		(drill 0.254)
		(layers "F.Cu" "B.Cu")
		(net "PE_TX1_DR10_N")
	)
	(segment
		(start 31.207964 -439.83275)
		(end 30.923992 -440.238388)
		(width 0.1651)
		(layer "In5.Cu")
		(net "PE_TX1_DR10_N")
	)
	(segment
		(start 32.229806 -438.04586)
		(end 31.945834 -438.451498)
		(width 0.1651)
		(layer "In5.Cu")
		(net "PE_TX1_DR10_N")
	)
	(segment
		(start 35.807142 -433.264564)
		(end 33.275524 -436.880254)
		(width 0.1651)
		(layer "In5.Cu")
		(net "PE_TX1_DR10_N")
	)
	(segment
		(start 35.760914 -433.002944)
		(end 35.807142 -433.264564)
		(width 0.1651)
		(layer "In5.Cu")
		(net "PE_TX1_DR10_N")
	)
	(segment
		(start 29.185616 -449.995544)
		(end 29.000704 -450.259958)
		(width 0.1651)
		(layer "In5.Cu")
		(net "PE_TX1_DR10_N")
	)
	(segment
		(start 31.707836 -439.11901)
		(end 31.445962 -439.165238)
		(width 0.1651)
		(layer "In5.Cu")
		(net "PE_TX1_DR10_N")
	)
	(segment
		(start 12.860274 -403.844252)
		(end 15.217394 -405.494744)
		(width 0.1651)
		(layer "In5.Cu")
		(net "PE_TX1_DR10_N")
	)
	(segment
		(start 43.470068 -422.320974)
		(end 36.307014 -432.551078)
		(width 0.1651)
		(layer "In5.Cu")
		(net "PE_TX1_DR10_N")
	)
	(segment
		(start 43.511978 -422.219374)
		(end 43.511724 -422.219374)
		(width 0.1651)
		(layer "In5.Cu")
		(net "PE_TX1_DR10_N")
	)
	(segment
		(start 36.04514 -432.597052)
		(end 35.760914 -433.002944)
		(width 0.1651)
		(layer "In5.Cu")
		(net "PE_TX1_DR10_N")
	)
	(segment
		(start 28.35148 -450.714364)
		(end 27.686 -450.831966)
		(width 0.1651)
		(layer "In5.Cu")
		(net "PE_TX1_DR10_N")
	)
	(segment
		(start 33.01365 -436.926482)
		(end 32.729424 -437.33212)
		(width 0.1651)
		(layer "In5.Cu")
		(net "PE_TX1_DR10_N")
	)
	(segment
		(start 29.703776 -446.07607)
		(end 29.617924 -446.564004)
		(width 0.1651)
		(layer "In5.Cu")
		(net "PE_TX1_DR10_N")
	)
	(segment
		(start 29.143198 -449.255388)
		(end 29.295852 -449.47332)
		(width 0.1651)
		(layer "In5.Cu")
		(net "PE_TX1_DR10_N")
	)
	(segment
		(start 41.503346 -410.128466)
		(end 42.786046 -411.02661)
		(width 0.1651)
		(layer "In5.Cu")
		(net "PE_TX1_DR10_N")
	)
	(segment
		(start 32.775652 -437.593994)
		(end 32.49168 -437.999632)
		(width 0.1651)
		(layer "In5.Cu")
		(net "PE_TX1_DR10_N")
	)
	(segment
		(start 6.992366 -403.148546)
		(end 7.220966 -402.919946)
		(width 0.1651)
		(layer "In5.Cu")
		(net "PE_TX1_DR10_N")
	)
	(segment
		(start 44.55414 -413.552132)
		(end 44.797218 -414.929828)
		(width 0.1651)
		(layer "In5.Cu")
		(net "PE_TX1_DR10_N")
	)
	(segment
		(start 33.275524 -436.880254)
		(end 33.01365 -436.926482)
		(width 0.1651)
		(layer "In5.Cu")
		(net "PE_TX1_DR10_N")
	)
	(segment
		(start 44.797218 -414.929828)
		(end 43.511978 -422.219374)
		(width 0.1651)
		(layer "In5.Cu")
		(net "PE_TX1_DR10_N")
	)
	(segment
		(start 29.446982 -448.615308)
		(end 29.229304 -448.767708)
		(width 0.1651)
		(layer "In5.Cu")
		(net "PE_TX1_DR10_N")
	)
	(segment
		(start 32.729424 -437.33212)
		(end 32.775652 -437.593994)
		(width 0.1651)
		(layer "In5.Cu")
		(net "PE_TX1_DR10_N")
	)
	(segment
		(start 29.617924 -446.564004)
		(end 29.770324 -446.781682)
		(width 0.1651)
		(layer "In5.Cu")
		(net "PE_TX1_DR10_N")
	)
	(segment
		(start 29.46654 -447.422016)
		(end 29.380434 -447.909696)
		(width 0.1651)
		(layer "In5.Cu")
		(net "PE_TX1_DR10_N")
	)
	(segment
		(start 31.945834 -438.451498)
		(end 31.991808 -438.713372)
		(width 0.1651)
		(layer "In5.Cu")
		(net "PE_TX1_DR10_N")
	)
	(segment
		(start 32.49168 -437.999632)
		(end 32.229806 -438.04586)
		(width 0.1651)
		(layer "In5.Cu")
		(net "PE_TX1_DR10_N")
	)
	(segment
		(start 29.380434 -447.909696)
		(end 29.533088 -448.127374)
		(width 0.1651)
		(layer "In5.Cu")
		(net "PE_TX1_DR10_N")
	)
	(segment
		(start 29.209746 -449.961)
		(end 29.185616 -449.995544)
		(width 0.1651)
		(layer "In5.Cu")
		(net "PE_TX1_DR10_N")
	)
	(segment
		(start 31.445962 -439.165238)
		(end 31.16199 -439.570876)
		(width 0.1651)
		(layer "In5.Cu")
		(net "PE_TX1_DR10_N")
	)
	(segment
		(start 29.229304 -448.767708)
		(end 29.143198 -449.255388)
		(width 0.1651)
		(layer "In5.Cu")
		(net "PE_TX1_DR10_N")
	)
	(segment
		(start 15.217394 -405.494744)
		(end 41.503346 -410.128466)
		(width 0.1651)
		(layer "In5.Cu")
		(net "PE_TX1_DR10_N")
	)
	(segment
		(start 30.923992 -440.238388)
		(end 29.921454 -445.92367)
		(width 0.1651)
		(layer "In5.Cu")
		(net "PE_TX1_DR10_N")
	)
	(segment
		(start 36.307014 -432.551078)
		(end 36.04514 -432.597052)
		(width 0.1651)
		(layer "In5.Cu")
		(net "PE_TX1_DR10_N")
	)
	(segment
		(start 29.770324 -446.781682)
		(end 29.684218 -447.269362)
		(width 0.1651)
		(layer "In5.Cu")
		(net "PE_TX1_DR10_N")
	)
	(segment
		(start 7.220966 -402.919946)
		(end 7.62 -402.919946)
		(width 0.1651)
		(layer "In5.Cu")
		(net "PE_TX1_DR10_N")
	)
	(segment
		(start 31.991808 -438.713372)
		(end 31.707836 -439.11901)
		(width 0.1651)
		(layer "In5.Cu")
		(net "PE_TX1_DR10_N")
	)
	(segment
		(start 27.686 -450.831966)
		(end 26.898346 -450.831966)
		(width 0.1651)
		(layer "In5.Cu")
		(net "PE_TX1_DR10_N")
	)
	(segment
		(start 29.684218 -447.269362)
		(end 29.46654 -447.422016)
		(width 0.1651)
		(layer "In5.Cu")
		(net "PE_TX1_DR10_N")
	)
	(segment
		(start 29.533088 -448.127374)
		(end 29.446982 -448.615308)
		(width 0.1651)
		(layer "In5.Cu")
		(net "PE_TX1_DR10_N")
	)
	(segment
		(start 42.786046 -411.02661)
		(end 44.55414 -413.552132)
		(width 0.1651)
		(layer "In5.Cu")
		(net "PE_TX1_DR10_N")
	)
	(segment
		(start 29.921454 -445.92367)
		(end 29.703776 -446.07607)
		(width 0.1651)
		(layer "In5.Cu")
		(net "PE_TX1_DR10_N")
	)
	(segment
		(start 31.16199 -439.570876)
		(end 31.207964 -439.83275)
		(width 0.1651)
		(layer "In5.Cu")
		(net "PE_TX1_DR10_N")
	)
	(segment
		(start 7.62 -402.919946)
		(end 12.860274 -403.844252)
		(width 0.1651)
		(layer "In5.Cu")
		(net "PE_TX1_DR10_N")
	)
	(segment
		(start 26.898346 -450.831966)
		(end 26.67 -450.60362)
		(width 0.1651)
		(layer "In5.Cu")
		(net "PE_TX1_DR10_N")
	)
	(segment
		(start 29.295852 -449.47332)
		(end 29.209746 -449.961)
		(width 0.1651)
		(layer "In5.Cu")
		(net "PE_TX1_DR10_N")
	)
	(segment
		(start 29.000704 -450.259958)
		(end 28.35148 -450.714364)
		(width 0.1651)
		(layer "In5.Cu")
		(net "PE_TX1_DR10_N")
	)
	(arc
		(start 43.511724 -422.219374)
		(mid 43.496465 -422.272459)
		(end 43.470068 -422.320974)
		(width 0.1651)
		(layer "In5.Cu")
		(net "PE_TX1_DR10_N")
	)
	(segment
		(start 3.657854 -387.94182)
		(end 3.90525 -387.694424)
		(width 0.174752)
		(layer "F.Cu")
		(net "PE_TX1_DR1_P")
	)
	(segment
		(start 220.58376 -364.142782)
		(end 220.330014 -364.396528)
		(width 0.174752)
		(layer "F.Cu")
		(net "PE_TX1_DR1_P")
	)
	(segment
		(start 6.738366 -387.694424)
		(end 6.992366 -387.948424)
		(width 0.174752)
		(layer "F.Cu")
		(net "PE_TX1_DR1_P")
	)
	(segment
		(start 2.249932 -387.94182)
		(end 3.657854 -387.94182)
		(width 0.174752)
		(layer "F.Cu")
		(net "PE_TX1_DR1_P")
	)
	(segment
		(start 223.132396 -364.390178)
		(end 222.885 -364.142782)
		(width 0.174752)
		(layer "F.Cu")
		(net "PE_TX1_DR1_P")
	)
	(segment
		(start 3.90525 -387.694424)
		(end 6.738366 -387.694424)
		(width 0.174752)
		(layer "F.Cu")
		(net "PE_TX1_DR1_P")
	)
	(segment
		(start 222.885 -364.142782)
		(end 220.58376 -364.142782)
		(width 0.174752)
		(layer "F.Cu")
		(net "PE_TX1_DR1_P")
	)
	(segment
		(start 224.199958 -364.390178)
		(end 223.132396 -364.390178)
		(width 0.174752)
		(layer "F.Cu")
		(net "PE_TX1_DR1_P")
	)
	(via
		(at 220.330014 -364.396528)
		(size 0.508)
		(drill 0.254)
		(layers "F.Cu" "B.Cu")
		(net "PE_TX1_DR1_P")
	)
	(via
		(at 6.992366 -387.948424)
		(size 0.508)
		(drill 0.254)
		(layers "F.Cu" "B.Cu")
		(net "PE_TX1_DR1_P")
	)
	(segment
		(start 7.220966 -387.719824)
		(end 6.992366 -387.948424)
		(width 0.1651)
		(layer "In5.Cu")
		(net "PE_TX1_DR1_P")
	)
	(segment
		(start 218.948 -364.168182)
		(end 196.900038 -379.606302)
		(width 0.1651)
		(layer "In5.Cu")
		(net "PE_TX1_DR1_P")
	)
	(segment
		(start 44.896278 -406.440386)
		(end 23.506684 -402.666962)
		(width 0.1651)
		(layer "In5.Cu")
		(net "PE_TX1_DR1_P")
	)
	(segment
		(start 23.506684 -402.666962)
		(end 14.742668 -396.531338)
		(width 0.1651)
		(layer "In5.Cu")
		(net "PE_TX1_DR1_P")
	)
	(segment
		(start 196.503798 -379.770386)
		(end 45.240194 -406.440386)
		(width 0.1651)
		(layer "In5.Cu")
		(net "PE_TX1_DR1_P")
	)
	(segment
		(start 220.101668 -364.168182)
		(end 218.948 -364.168182)
		(width 0.1651)
		(layer "In5.Cu")
		(net "PE_TX1_DR1_P")
	)
	(segment
		(start 14.742668 -396.531338)
		(end 9.072372 -388.432294)
		(width 0.1651)
		(layer "In5.Cu")
		(net "PE_TX1_DR1_P")
	)
	(segment
		(start 8.201406 -387.82244)
		(end 7.62 -387.719824)
		(width 0.1651)
		(layer "In5.Cu")
		(net "PE_TX1_DR1_P")
	)
	(segment
		(start 7.62 -387.719824)
		(end 7.220966 -387.719824)
		(width 0.1651)
		(layer "In5.Cu")
		(net "PE_TX1_DR1_P")
	)
	(segment
		(start 220.330014 -364.396528)
		(end 220.101668 -364.168182)
		(width 0.1651)
		(layer "In5.Cu")
		(net "PE_TX1_DR1_P")
	)
	(segment
		(start 9.072372 -388.432294)
		(end 8.201406 -387.82244)
		(width 0.1651)
		(layer "In5.Cu")
		(net "PE_TX1_DR1_P")
	)
	(arc
		(start 196.900038 -379.606302)
		(mid 196.710906 -379.710053)
		(end 196.503798 -379.770386)
		(width 0.1651)
		(layer "In5.Cu")
		(net "PE_TX1_DR1_P")
	)
	(arc
		(start 45.240194 -406.440386)
		(mid 45.068236 -406.455424)
		(end 44.896278 -406.440386)
		(width 0.1651)
		(layer "In5.Cu")
		(net "PE_TX1_DR1_P")
	)
	(segment
		(start 3.90525 -387.38937)
		(end 6.73862 -387.38937)
		(width 0.174752)
		(layer "F.Cu")
		(net "PE_TX1_DR1_N")
	)
	(segment
		(start 2.249932 -387.141974)
		(end 3.657854 -387.141974)
		(width 0.174752)
		(layer "F.Cu")
		(net "PE_TX1_DR1_N")
	)
	(segment
		(start 3.657854 -387.141974)
		(end 3.90525 -387.38937)
		(width 0.174752)
		(layer "F.Cu")
		(net "PE_TX1_DR1_N")
	)
	(segment
		(start 222.885 -363.837728)
		(end 220.584014 -363.837728)
		(width 0.174752)
		(layer "F.Cu")
		(net "PE_TX1_DR1_N")
	)
	(segment
		(start 220.584014 -363.837728)
		(end 220.330014 -363.583728)
		(width 0.174752)
		(layer "F.Cu")
		(net "PE_TX1_DR1_N")
	)
	(segment
		(start 223.13265 -363.590078)
		(end 222.885 -363.837728)
		(width 0.174752)
		(layer "F.Cu")
		(net "PE_TX1_DR1_N")
	)
	(segment
		(start 6.73862 -387.38937)
		(end 6.992366 -387.135624)
		(width 0.174752)
		(layer "F.Cu")
		(net "PE_TX1_DR1_N")
	)
	(segment
		(start 224.199958 -363.590078)
		(end 223.13265 -363.590078)
		(width 0.174752)
		(layer "F.Cu")
		(net "PE_TX1_DR1_N")
	)
	(via
		(at 220.330014 -363.583728)
		(size 0.508)
		(drill 0.254)
		(layers "F.Cu" "B.Cu")
		(net "PE_TX1_DR1_N")
	)
	(via
		(at 6.992366 -387.135624)
		(size 0.508)
		(drill 0.254)
		(layers "F.Cu" "B.Cu")
		(net "PE_TX1_DR1_N")
	)
	(segment
		(start 14.998192 -396.275814)
		(end 9.327896 -388.17677)
		(width 0.1651)
		(layer "In5.Cu")
		(net "PE_TX1_DR1_N")
	)
	(segment
		(start 196.442076 -379.42012)
		(end 45.178472 -406.089866)
		(width 0.1651)
		(layer "In5.Cu")
		(net "PE_TX1_DR1_N")
	)
	(segment
		(start 7.220966 -387.364224)
		(end 6.992366 -387.135624)
		(width 0.1651)
		(layer "In5.Cu")
		(net "PE_TX1_DR1_N")
	)
	(segment
		(start 218.835732 -363.812582)
		(end 196.696076 -379.314964)
		(width 0.1651)
		(layer "In5.Cu")
		(net "PE_TX1_DR1_N")
	)
	(segment
		(start 220.10116 -363.812582)
		(end 218.835732 -363.812582)
		(width 0.1651)
		(layer "In5.Cu")
		(net "PE_TX1_DR1_N")
	)
	(segment
		(start 44.958 -406.089866)
		(end 23.64613 -402.330412)
		(width 0.1651)
		(layer "In5.Cu")
		(net "PE_TX1_DR1_N")
	)
	(segment
		(start 220.330014 -363.583728)
		(end 220.10116 -363.812582)
		(width 0.1651)
		(layer "In5.Cu")
		(net "PE_TX1_DR1_N")
	)
	(segment
		(start 8.340852 -387.48589)
		(end 7.651242 -387.364224)
		(width 0.1651)
		(layer "In5.Cu")
		(net "PE_TX1_DR1_N")
	)
	(segment
		(start 23.64613 -402.330412)
		(end 14.998192 -396.275814)
		(width 0.1651)
		(layer "In5.Cu")
		(net "PE_TX1_DR1_N")
	)
	(segment
		(start 9.327896 -388.17677)
		(end 8.340852 -387.48589)
		(width 0.1651)
		(layer "In5.Cu")
		(net "PE_TX1_DR1_N")
	)
	(segment
		(start 7.651242 -387.364224)
		(end 7.220966 -387.364224)
		(width 0.1651)
		(layer "In5.Cu")
		(net "PE_TX1_DR1_N")
	)
	(arc
		(start 196.696076 -379.314964)
		(mid 196.574841 -379.381473)
		(end 196.442076 -379.42012)
		(width 0.1651)
		(layer "In5.Cu")
		(net "PE_TX1_DR1_N")
	)
	(arc
		(start 45.178472 -406.089866)
		(mid 45.068236 -406.099508)
		(end 44.958 -406.089866)
		(width 0.1651)
		(layer "In5.Cu")
		(net "PE_TX1_DR1_N")
	)
	(segment
		(start 3.657854 -415.942018)
		(end 3.905504 -415.694368)
		(width 0.174752)
		(layer "F.Cu")
		(net "PE_TX1_DR0_P")
	)
	(segment
		(start 3.905504 -415.694368)
		(end 6.738112 -415.694368)
		(width 0.174752)
		(layer "F.Cu")
		(net "PE_TX1_DR0_P")
	)
	(segment
		(start 222.885 -467.14283)
		(end 220.58376 -467.14283)
		(width 0.174752)
		(layer "F.Cu")
		(net "PE_TX1_DR0_P")
	)
	(segment
		(start 6.738112 -415.694368)
		(end 6.992366 -415.948622)
		(width 0.174752)
		(layer "F.Cu")
		(net "PE_TX1_DR0_P")
	)
	(segment
		(start 2.249932 -415.942018)
		(end 3.657854 -415.942018)
		(width 0.174752)
		(layer "F.Cu")
		(net "PE_TX1_DR0_P")
	)
	(segment
		(start 220.58376 -467.14283)
		(end 220.330014 -467.396576)
		(width 0.174752)
		(layer "F.Cu")
		(net "PE_TX1_DR0_P")
	)
	(segment
		(start 224.199958 -467.390226)
		(end 223.132396 -467.390226)
		(width 0.174752)
		(layer "F.Cu")
		(net "PE_TX1_DR0_P")
	)
	(segment
		(start 223.132396 -467.390226)
		(end 222.885 -467.14283)
		(width 0.174752)
		(layer "F.Cu")
		(net "PE_TX1_DR0_P")
	)
	(via
		(at 6.992366 -415.948622)
		(size 0.508)
		(drill 0.254)
		(layers "F.Cu" "B.Cu")
		(net "PE_TX1_DR0_P")
	)
	(via
		(at 220.330014 -467.396576)
		(size 0.508)
		(drill 0.254)
		(layers "F.Cu" "B.Cu")
		(net "PE_TX1_DR0_P")
	)
	(segment
		(start 29.674566 -452.25462)
		(end 29.674312 -452.25462)
		(width 0.1651)
		(layer "In5.Cu")
		(net "PE_TX1_DR0_P")
	)
	(segment
		(start 205.539086 -470.055194)
		(end 41.659302 -441.140342)
		(width 0.1651)
		(layer "In5.Cu")
		(net "PE_TX1_DR0_P")
	)
	(segment
		(start 7.220966 -415.720022)
		(end 6.992366 -415.948622)
		(width 0.1651)
		(layer "In5.Cu")
		(net "PE_TX1_DR0_P")
	)
	(segment
		(start 21.168614 -454.341992)
		(end 21.08073 -454.280524)
		(width 0.1651)
		(layer "In5.Cu")
		(net "PE_TX1_DR0_P")
	)
	(segment
		(start 220.330014 -467.396576)
		(end 220.101668 -467.16823)
		(width 0.1651)
		(layer "In5.Cu")
		(net "PE_TX1_DR0_P")
	)
	(segment
		(start 8.140954 -415.945574)
		(end 8.1407 -415.94532)
		(width 0.1651)
		(layer "In5.Cu")
		(net "PE_TX1_DR0_P")
	)
	(segment
		(start 34.792412 -444.9445)
		(end 29.674566 -452.25462)
		(width 0.1651)
		(layer "In5.Cu")
		(net "PE_TX1_DR0_P")
	)
	(segment
		(start 8.1407 -415.94532)
		(end 7.818628 -415.720022)
		(width 0.1651)
		(layer "In5.Cu")
		(net "PE_TX1_DR0_P")
	)
	(segment
		(start 10.860278 -419.83279)
		(end 8.140954 -415.945574)
		(width 0.1651)
		(layer "In5.Cu")
		(net "PE_TX1_DR0_P")
	)
	(segment
		(start 39.65448 -441.494164)
		(end 34.948368 -444.788544)
		(width 0.1651)
		(layer "In5.Cu")
		(net "PE_TX1_DR0_P")
	)
	(segment
		(start 29.674312 -452.25462)
		(end 26.744422 -454.305924)
		(width 0.1651)
		(layer "In5.Cu")
		(net "PE_TX1_DR0_P")
	)
	(segment
		(start 7.818628 -415.720022)
		(end 7.220966 -415.720022)
		(width 0.1651)
		(layer "In5.Cu")
		(net "PE_TX1_DR0_P")
	)
	(segment
		(start 23.255224 -454.921112)
		(end 21.571458 -454.624186)
		(width 0.1651)
		(layer "In5.Cu")
		(net "PE_TX1_DR0_P")
	)
	(segment
		(start 21.571458 -454.624186)
		(end 21.319236 -454.447656)
		(width 0.1651)
		(layer "In5.Cu")
		(net "PE_TX1_DR0_P")
	)
	(segment
		(start 20.069048 -452.836026)
		(end 17.742916 -451.207378)
		(width 0.1651)
		(layer "In5.Cu")
		(net "PE_TX1_DR0_P")
	)
	(segment
		(start 41.659302 -441.140342)
		(end 39.65448 -441.494164)
		(width 0.1651)
		(layer "In5.Cu")
		(net "PE_TX1_DR0_P")
	)
	(segment
		(start 15.938246 -448.629786)
		(end 10.860278 -419.83279)
		(width 0.1651)
		(layer "In5.Cu")
		(net "PE_TX1_DR0_P")
	)
	(segment
		(start 219.116656 -467.16823)
		(end 205.539086 -470.055194)
		(width 0.1651)
		(layer "In5.Cu")
		(net "PE_TX1_DR0_P")
	)
	(segment
		(start 21.319236 -454.447656)
		(end 21.168614 -454.341992)
		(width 0.1651)
		(layer "In5.Cu")
		(net "PE_TX1_DR0_P")
	)
	(segment
		(start 21.08073 -454.280524)
		(end 20.069048 -452.836026)
		(width 0.1651)
		(layer "In5.Cu")
		(net "PE_TX1_DR0_P")
	)
	(segment
		(start 26.744422 -454.305924)
		(end 23.255224 -454.921112)
		(width 0.1651)
		(layer "In5.Cu")
		(net "PE_TX1_DR0_P")
	)
	(segment
		(start 220.101668 -467.16823)
		(end 219.116656 -467.16823)
		(width 0.1651)
		(layer "In5.Cu")
		(net "PE_TX1_DR0_P")
	)
	(segment
		(start 17.742916 -451.207378)
		(end 15.938246 -448.629786)
		(width 0.1651)
		(layer "In5.Cu")
		(net "PE_TX1_DR0_P")
	)
	(arc
		(start 34.948368 -444.788544)
		(mid 34.863567 -444.859699)
		(end 34.792412 -444.9445)
		(width 0.1651)
		(layer "In5.Cu")
		(net "PE_TX1_DR0_P")
	)
	(segment
		(start 222.885 -466.837776)
		(end 220.584014 -466.837776)
		(width 0.174752)
		(layer "F.Cu")
		(net "PE_TX1_DR0_N")
	)
	(segment
		(start 2.249932 -415.141918)
		(end 3.658108 -415.141918)
		(width 0.174752)
		(layer "F.Cu")
		(net "PE_TX1_DR0_N")
	)
	(segment
		(start 3.905504 -415.389314)
		(end 6.738874 -415.389314)
		(width 0.174752)
		(layer "F.Cu")
		(net "PE_TX1_DR0_N")
	)
	(segment
		(start 224.199958 -466.590126)
		(end 223.13265 -466.590126)
		(width 0.174752)
		(layer "F.Cu")
		(net "PE_TX1_DR0_N")
	)
	(segment
		(start 220.584014 -466.837776)
		(end 220.330014 -466.583776)
		(width 0.174752)
		(layer "F.Cu")
		(net "PE_TX1_DR0_N")
	)
	(segment
		(start 3.658108 -415.141918)
		(end 3.905504 -415.389314)
		(width 0.174752)
		(layer "F.Cu")
		(net "PE_TX1_DR0_N")
	)
	(segment
		(start 6.738874 -415.389314)
		(end 6.992366 -415.135822)
		(width 0.174752)
		(layer "F.Cu")
		(net "PE_TX1_DR0_N")
	)
	(segment
		(start 223.13265 -466.590126)
		(end 222.885 -466.837776)
		(width 0.174752)
		(layer "F.Cu")
		(net "PE_TX1_DR0_N")
	)
	(via
		(at 6.992366 -415.135822)
		(size 0.508)
		(drill 0.254)
		(layers "F.Cu" "B.Cu")
		(net "PE_TX1_DR0_N")
	)
	(via
		(at 220.330014 -466.583776)
		(size 0.508)
		(drill 0.254)
		(layers "F.Cu" "B.Cu")
		(net "PE_TX1_DR0_N")
	)
	(segment
		(start 205.532736 -469.692736)
		(end 41.659302 -440.779154)
		(width 0.1651)
		(layer "In5.Cu")
		(net "PE_TX1_DR0_N")
	)
	(segment
		(start 7.930642 -415.364422)
		(end 7.220966 -415.364422)
		(width 0.1651)
		(layer "In5.Cu")
		(net "PE_TX1_DR0_N")
	)
	(segment
		(start 21.710904 -454.287636)
		(end 21.336 -454.025)
		(width 0.1651)
		(layer "In5.Cu")
		(net "PE_TX1_DR0_N")
	)
	(segment
		(start 39.515034 -441.157614)
		(end 34.744406 -444.497206)
		(width 0.1651)
		(layer "In5.Cu")
		(net "PE_TX1_DR0_N")
	)
	(segment
		(start 29.418788 -451.999096)
		(end 26.604976 -453.969374)
		(width 0.1651)
		(layer "In5.Cu")
		(net "PE_TX1_DR0_N")
	)
	(segment
		(start 220.330014 -466.583776)
		(end 220.10116 -466.81263)
		(width 0.1651)
		(layer "In5.Cu")
		(net "PE_TX1_DR0_N")
	)
	(segment
		(start 21.336 -454.025)
		(end 20.324572 -452.580502)
		(width 0.1651)
		(layer "In5.Cu")
		(net "PE_TX1_DR0_N")
	)
	(segment
		(start 11.197082 -419.693344)
		(end 8.39597 -415.689542)
		(width 0.1651)
		(layer "In5.Cu")
		(net "PE_TX1_DR0_N")
	)
	(segment
		(start 23.255224 -454.559924)
		(end 21.710904 -454.287636)
		(width 0.1651)
		(layer "In5.Cu")
		(net "PE_TX1_DR0_N")
	)
	(segment
		(start 34.50082 -444.740538)
		(end 29.419042 -451.999096)
		(width 0.1651)
		(layer "In5.Cu")
		(net "PE_TX1_DR0_N")
	)
	(segment
		(start 20.324572 -452.580502)
		(end 17.99844 -450.951854)
		(width 0.1651)
		(layer "In5.Cu")
		(net "PE_TX1_DR0_N")
	)
	(segment
		(start 8.39597 -415.689542)
		(end 7.930642 -415.364422)
		(width 0.1651)
		(layer "In5.Cu")
		(net "PE_TX1_DR0_N")
	)
	(segment
		(start 16.274796 -448.49034)
		(end 11.197082 -419.693344)
		(width 0.1651)
		(layer "In5.Cu")
		(net "PE_TX1_DR0_N")
	)
	(segment
		(start 17.99844 -450.951854)
		(end 16.274796 -448.49034)
		(width 0.1651)
		(layer "In5.Cu")
		(net "PE_TX1_DR0_N")
	)
	(segment
		(start 219.079064 -466.81263)
		(end 205.532736 -469.692736)
		(width 0.1651)
		(layer "In5.Cu")
		(net "PE_TX1_DR0_N")
	)
	(segment
		(start 41.659302 -440.779154)
		(end 39.515034 -441.157614)
		(width 0.1651)
		(layer "In5.Cu")
		(net "PE_TX1_DR0_N")
	)
	(segment
		(start 26.604976 -453.969374)
		(end 23.255224 -454.559924)
		(width 0.1651)
		(layer "In5.Cu")
		(net "PE_TX1_DR0_N")
	)
	(segment
		(start 34.744406 -444.497206)
		(end 34.744406 -444.496952)
		(width 0.1651)
		(layer "In5.Cu")
		(net "PE_TX1_DR0_N")
	)
	(segment
		(start 7.220966 -415.364422)
		(end 6.992366 -415.135822)
		(width 0.1651)
		(layer "In5.Cu")
		(net "PE_TX1_DR0_N")
	)
	(segment
		(start 220.10116 -466.81263)
		(end 219.079064 -466.81263)
		(width 0.1651)
		(layer "In5.Cu")
		(net "PE_TX1_DR0_N")
	)
	(segment
		(start 29.419042 -451.999096)
		(end 29.418788 -451.999096)
		(width 0.1651)
		(layer "In5.Cu")
		(net "PE_TX1_DR0_N")
	)
	(arc
		(start 34.744406 -444.496952)
		(mid 34.611943 -444.608075)
		(end 34.50082 -444.740538)
		(width 0.1651)
		(layer "In5.Cu")
		(net "PE_TX1_DR0_N")
	)
	(segment
		(start 38.1 -80.189832)
		(end 37.852604 -79.942436)
		(width 0.174752)
		(layer "F.Cu")
		(net "PE_RX4_DR9_P")
	)
	(segment
		(start 37.852604 -79.942436)
		(end 37.13353 -79.942436)
		(width 0.174752)
		(layer "F.Cu")
		(net "PE_RX4_DR9_P")
	)
	(segment
		(start 39.200074 -80.189832)
		(end 38.1 -80.189832)
		(width 0.174752)
		(layer "F.Cu")
		(net "PE_RX4_DR9_P")
	)
	(segment
		(start 37.13353 -79.942436)
		(end 36.72713 -80.348836)
		(width 0.174752)
		(layer "F.Cu")
		(net "PE_RX4_DR9_P")
	)
	(via
		(at 5.08 -195.1482)
		(size 0.508)
		(drill 0.254)
		(layers "F.Cu" "B.Cu")
		(net "PE_RX4_DR9_P")
	)
	(via
		(at 36.72713 -80.348836)
		(size 0.508)
		(drill 0.254)
		(layers "F.Cu" "B.Cu")
		(net "PE_RX4_DR9_P")
	)
	(segment
		(start 3.905504 -194.894454)
		(end 4.826254 -194.894454)
		(width 0.174752)
		(layer "B.Cu")
		(net "PE_RX4_DR9_P")
	)
	(segment
		(start 3.657854 -195.142104)
		(end 3.905504 -194.894454)
		(width 0.174752)
		(layer "B.Cu")
		(net "PE_RX4_DR9_P")
	)
	(segment
		(start 4.826254 -194.894454)
		(end 5.08 -195.1482)
		(width 0.174752)
		(layer "B.Cu")
		(net "PE_RX4_DR9_P")
	)
	(segment
		(start 1.868932 -195.142104)
		(end 3.657854 -195.142104)
		(width 0.174752)
		(layer "B.Cu")
		(net "PE_RX4_DR9_P")
	)
	(segment
		(start 44.664376 -112.637062)
		(end 42.325798 -115.976908)
		(width 0.1651)
		(layer "In2.Cu")
		(net "PE_RX4_DR9_P")
	)
	(segment
		(start 36.72713 -80.348836)
		(end 36.34613 -79.967836)
		(width 0.1651)
		(layer "In2.Cu")
		(net "PE_RX4_DR9_P")
	)
	(segment
		(start 23.19528 -85.43163)
		(end 22.18055 -86.880446)
		(width 0.1651)
		(layer "In2.Cu")
		(net "PE_RX4_DR9_P")
	)
	(segment
		(start 7.224268 -194.919854)
		(end 5.308346 -194.919854)
		(width 0.1651)
		(layer "In2.Cu")
		(net "PE_RX4_DR9_P")
	)
	(segment
		(start 29.66339 -172.12818)
		(end 19.940778 -186.015884)
		(width 0.1651)
		(layer "In2.Cu")
		(net "PE_RX4_DR9_P")
	)
	(segment
		(start 45.13199 -102.951788)
		(end 45.752258 -106.468418)
		(width 0.1651)
		(layer "In2.Cu")
		(net "PE_RX4_DR9_P")
	)
	(segment
		(start 33.196276 -152.09139)
		(end 29.66339 -172.12818)
		(width 0.1651)
		(layer "In2.Cu")
		(net "PE_RX4_DR9_P")
	)
	(segment
		(start 5.308346 -194.919854)
		(end 5.08 -195.1482)
		(width 0.1651)
		(layer "In2.Cu")
		(net "PE_RX4_DR9_P")
	)
	(segment
		(start 43.806872 -101.058726)
		(end 45.13199 -102.951788)
		(width 0.1651)
		(layer "In2.Cu")
		(net "PE_RX4_DR9_P")
	)
	(segment
		(start 21.764752 -89.240106)
		(end 22.405594 -92.873576)
		(width 0.1651)
		(layer "In2.Cu")
		(net "PE_RX4_DR9_P")
	)
	(segment
		(start 23.937976 -95.062294)
		(end 25.498298 -96.154748)
		(width 0.1651)
		(layer "In2.Cu")
		(net "PE_RX4_DR9_P")
	)
	(segment
		(start 42.325798 -115.976908)
		(end 36.883594 -146.8247)
		(width 0.1651)
		(layer "In2.Cu")
		(net "PE_RX4_DR9_P")
	)
	(segment
		(start 22.405594 -92.873576)
		(end 23.937976 -95.062294)
		(width 0.1651)
		(layer "In2.Cu")
		(net "PE_RX4_DR9_P")
	)
	(segment
		(start 19.940778 -186.015884)
		(end 7.224268 -194.919854)
		(width 0.1651)
		(layer "In2.Cu")
		(net "PE_RX4_DR9_P")
	)
	(segment
		(start 36.34613 -79.967836)
		(end 35.429952 -79.967836)
		(width 0.1651)
		(layer "In2.Cu")
		(net "PE_RX4_DR9_P")
	)
	(segment
		(start 22.18055 -86.880446)
		(end 21.764752 -89.240106)
		(width 0.1651)
		(layer "In2.Cu")
		(net "PE_RX4_DR9_P")
	)
	(segment
		(start 25.498298 -96.154748)
		(end 40.609774 -98.820224)
		(width 0.1651)
		(layer "In2.Cu")
		(net "PE_RX4_DR9_P")
	)
	(segment
		(start 45.752258 -106.468418)
		(end 44.664376 -112.637062)
		(width 0.1651)
		(layer "In2.Cu")
		(net "PE_RX4_DR9_P")
	)
	(segment
		(start 35.429952 -79.967836)
		(end 29.50718 -81.01203)
		(width 0.1651)
		(layer "In2.Cu")
		(net "PE_RX4_DR9_P")
	)
	(segment
		(start 29.50718 -81.01203)
		(end 23.19528 -85.43163)
		(width 0.1651)
		(layer "In2.Cu")
		(net "PE_RX4_DR9_P")
	)
	(segment
		(start 36.883594 -146.8247)
		(end 33.196276 -152.09139)
		(width 0.1651)
		(layer "In2.Cu")
		(net "PE_RX4_DR9_P")
	)
	(segment
		(start 40.609774 -98.820224)
		(end 43.806872 -101.058726)
		(width 0.1651)
		(layer "In2.Cu")
		(net "PE_RX4_DR9_P")
	)
	(segment
		(start 38.1 -79.389986)
		(end 37.852604 -79.637382)
		(width 0.174752)
		(layer "F.Cu")
		(net "PE_RX4_DR9_N")
	)
	(segment
		(start 39.200074 -79.389986)
		(end 38.1 -79.389986)
		(width 0.174752)
		(layer "F.Cu")
		(net "PE_RX4_DR9_N")
	)
	(segment
		(start 37.852604 -79.637382)
		(end 37.133276 -79.637382)
		(width 0.174752)
		(layer "F.Cu")
		(net "PE_RX4_DR9_N")
	)
	(segment
		(start 37.133276 -79.637382)
		(end 36.72713 -79.231236)
		(width 0.174752)
		(layer "F.Cu")
		(net "PE_RX4_DR9_N")
	)
	(via
		(at 36.72713 -79.231236)
		(size 0.508)
		(drill 0.254)
		(layers "F.Cu" "B.Cu")
		(net "PE_RX4_DR9_N")
	)
	(via
		(at 5.08 -194.3354)
		(size 0.508)
		(drill 0.254)
		(layers "F.Cu" "B.Cu")
		(net "PE_RX4_DR9_N")
	)
	(segment
		(start 3.905504 -194.5894)
		(end 4.826 -194.5894)
		(width 0.174752)
		(layer "B.Cu")
		(net "PE_RX4_DR9_N")
	)
	(segment
		(start 1.868932 -194.342004)
		(end 3.658108 -194.342004)
		(width 0.174752)
		(layer "B.Cu")
		(net "PE_RX4_DR9_N")
	)
	(segment
		(start 4.826 -194.5894)
		(end 5.08 -194.3354)
		(width 0.174752)
		(layer "B.Cu")
		(net "PE_RX4_DR9_N")
	)
	(segment
		(start 3.658108 -194.342004)
		(end 3.905504 -194.5894)
		(width 0.174752)
		(layer "B.Cu")
		(net "PE_RX4_DR9_N")
	)
	(segment
		(start 43.551348 -101.31425)
		(end 44.79544 -103.091234)
		(width 0.1651)
		(layer "In2.Cu")
		(net "PE_RX4_DR9_N")
	)
	(segment
		(start 23.682452 -95.317818)
		(end 25.358852 -96.491298)
		(width 0.1651)
		(layer "In2.Cu")
		(net "PE_RX4_DR9_N")
	)
	(segment
		(start 41.989248 -115.837462)
		(end 36.547044 -146.685254)
		(width 0.1651)
		(layer "In2.Cu")
		(net "PE_RX4_DR9_N")
	)
	(segment
		(start 19.685254 -185.76036)
		(end 7.112 -194.564254)
		(width 0.1651)
		(layer "In2.Cu")
		(net "PE_RX4_DR9_N")
	)
	(segment
		(start 45.39107 -106.468418)
		(end 44.327826 -112.497616)
		(width 0.1651)
		(layer "In2.Cu")
		(net "PE_RX4_DR9_N")
	)
	(segment
		(start 29.367734 -80.67548)
		(end 22.939756 -85.176106)
		(width 0.1651)
		(layer "In2.Cu")
		(net "PE_RX4_DR9_N")
	)
	(segment
		(start 5.308854 -194.564254)
		(end 5.08 -194.3354)
		(width 0.1651)
		(layer "In2.Cu")
		(net "PE_RX4_DR9_N")
	)
	(segment
		(start 22.939756 -85.176106)
		(end 21.844 -86.741)
		(width 0.1651)
		(layer "In2.Cu")
		(net "PE_RX4_DR9_N")
	)
	(segment
		(start 36.72713 -79.231236)
		(end 36.34613 -79.612236)
		(width 0.1651)
		(layer "In2.Cu")
		(net "PE_RX4_DR9_N")
	)
	(segment
		(start 25.358852 -96.491298)
		(end 40.470328 -99.156774)
		(width 0.1651)
		(layer "In2.Cu")
		(net "PE_RX4_DR9_N")
	)
	(segment
		(start 21.844 -86.741)
		(end 21.403564 -89.239598)
		(width 0.1651)
		(layer "In2.Cu")
		(net "PE_RX4_DR9_N")
	)
	(segment
		(start 40.470328 -99.156774)
		(end 43.551348 -101.31425)
		(width 0.1651)
		(layer "In2.Cu")
		(net "PE_RX4_DR9_N")
	)
	(segment
		(start 32.859726 -151.951944)
		(end 29.32684 -171.988734)
		(width 0.1651)
		(layer "In2.Cu")
		(net "PE_RX4_DR9_N")
	)
	(segment
		(start 44.79544 -103.091234)
		(end 45.39107 -106.468418)
		(width 0.1651)
		(layer "In2.Cu")
		(net "PE_RX4_DR9_N")
	)
	(segment
		(start 21.403564 -89.239598)
		(end 22.069044 -93.01353)
		(width 0.1651)
		(layer "In2.Cu")
		(net "PE_RX4_DR9_N")
	)
	(segment
		(start 29.32684 -171.988734)
		(end 19.685254 -185.76036)
		(width 0.1651)
		(layer "In2.Cu")
		(net "PE_RX4_DR9_N")
	)
	(segment
		(start 36.34613 -79.612236)
		(end 35.39871 -79.612236)
		(width 0.1651)
		(layer "In2.Cu")
		(net "PE_RX4_DR9_N")
	)
	(segment
		(start 44.327826 -112.497616)
		(end 41.989248 -115.837462)
		(width 0.1651)
		(layer "In2.Cu")
		(net "PE_RX4_DR9_N")
	)
	(segment
		(start 35.39871 -79.612236)
		(end 29.367734 -80.67548)
		(width 0.1651)
		(layer "In2.Cu")
		(net "PE_RX4_DR9_N")
	)
	(segment
		(start 22.069044 -93.01353)
		(end 23.682452 -95.317818)
		(width 0.1651)
		(layer "In2.Cu")
		(net "PE_RX4_DR9_N")
	)
	(segment
		(start 7.112 -194.564254)
		(end 5.308854 -194.564254)
		(width 0.1651)
		(layer "In2.Cu")
		(net "PE_RX4_DR9_N")
	)
	(segment
		(start 36.547044 -146.685254)
		(end 32.859726 -151.951944)
		(width 0.1651)
		(layer "In2.Cu")
		(net "PE_RX4_DR9_N")
	)
	(segment
		(start 38.093396 -183.18988)
		(end 37.846 -182.942484)
		(width 0.174752)
		(layer "F.Cu")
		(net "PE_RX4_DR8_P")
	)
	(segment
		(start 37.846 -182.942484)
		(end 37.13353 -182.942484)
		(width 0.174752)
		(layer "F.Cu")
		(net "PE_RX4_DR8_P")
	)
	(segment
		(start 39.200074 -183.18988)
		(end 38.093396 -183.18988)
		(width 0.174752)
		(layer "F.Cu")
		(net "PE_RX4_DR8_P")
	)
	(segment
		(start 37.13353 -182.942484)
		(end 36.72713 -183.348884)
		(width 0.174752)
		(layer "F.Cu")
		(net "PE_RX4_DR8_P")
	)
	(via
		(at 36.72713 -183.348884)
		(size 0.508)
		(drill 0.254)
		(layers "F.Cu" "B.Cu")
		(net "PE_RX4_DR8_P")
	)
	(via
		(at 5.08 -210.348322)
		(size 0.508)
		(drill 0.254)
		(layers "F.Cu" "B.Cu")
		(net "PE_RX4_DR8_P")
	)
	(segment
		(start 3.657854 -210.342226)
		(end 3.905504 -210.094576)
		(width 0.174752)
		(layer "B.Cu")
		(net "PE_RX4_DR8_P")
	)
	(segment
		(start 4.826254 -210.094576)
		(end 5.08 -210.348322)
		(width 0.174752)
		(layer "B.Cu")
		(net "PE_RX4_DR8_P")
	)
	(segment
		(start 3.905504 -210.094576)
		(end 4.826254 -210.094576)
		(width 0.174752)
		(layer "B.Cu")
		(net "PE_RX4_DR8_P")
	)
	(segment
		(start 1.868932 -210.342226)
		(end 3.657854 -210.342226)
		(width 0.174752)
		(layer "B.Cu")
		(net "PE_RX4_DR8_P")
	)
	(segment
		(start 36.34613 -182.967884)
		(end 35.429952 -182.967884)
		(width 0.1651)
		(layer "In2.Cu")
		(net "PE_RX4_DR8_P")
	)
	(segment
		(start 7.781798 -210.001866)
		(end 7.112 -210.119976)
		(width 0.1651)
		(layer "In2.Cu")
		(net "PE_RX4_DR8_P")
	)
	(segment
		(start 9.755632 -207.937862)
		(end 8.818626 -209.275934)
		(width 0.1651)
		(layer "In2.Cu")
		(net "PE_RX4_DR8_P")
	)
	(segment
		(start 8.818626 -209.275934)
		(end 7.781798 -210.001866)
		(width 0.1651)
		(layer "In2.Cu")
		(net "PE_RX4_DR8_P")
	)
	(segment
		(start 35.429952 -182.967884)
		(end 27.923744 -184.29097)
		(width 0.1651)
		(layer "In2.Cu")
		(net "PE_RX4_DR8_P")
	)
	(segment
		(start 5.308346 -210.119976)
		(end 5.08 -210.348322)
		(width 0.1651)
		(layer "In2.Cu")
		(net "PE_RX4_DR8_P")
	)
	(segment
		(start 7.112 -210.119976)
		(end 5.308346 -210.119976)
		(width 0.1651)
		(layer "In2.Cu")
		(net "PE_RX4_DR8_P")
	)
	(segment
		(start 27.923744 -184.29097)
		(end 22.552152 -189.662562)
		(width 0.1651)
		(layer "In2.Cu")
		(net "PE_RX4_DR8_P")
	)
	(segment
		(start 36.72713 -183.348884)
		(end 36.34613 -182.967884)
		(width 0.1651)
		(layer "In2.Cu")
		(net "PE_RX4_DR8_P")
	)
	(segment
		(start 22.552152 -189.662562)
		(end 9.755632 -207.937862)
		(width 0.1651)
		(layer "In2.Cu")
		(net "PE_RX4_DR8_P")
	)
	(segment
		(start 37.133276 -182.63743)
		(end 36.72713 -182.231284)
		(width 0.174752)
		(layer "F.Cu")
		(net "PE_RX4_DR8_N")
	)
	(segment
		(start 37.852604 -182.63743)
		(end 37.133276 -182.63743)
		(width 0.174752)
		(layer "F.Cu")
		(net "PE_RX4_DR8_N")
	)
	(segment
		(start 39.200074 -182.390034)
		(end 38.1 -182.390034)
		(width 0.174752)
		(layer "F.Cu")
		(net "PE_RX4_DR8_N")
	)
	(segment
		(start 38.1 -182.390034)
		(end 37.852604 -182.63743)
		(width 0.174752)
		(layer "F.Cu")
		(net "PE_RX4_DR8_N")
	)
	(via
		(at 36.72713 -182.231284)
		(size 0.508)
		(drill 0.254)
		(layers "F.Cu" "B.Cu")
		(net "PE_RX4_DR8_N")
	)
	(via
		(at 5.08 -209.535522)
		(size 0.508)
		(drill 0.254)
		(layers "F.Cu" "B.Cu")
		(net "PE_RX4_DR8_N")
	)
	(segment
		(start 4.826 -209.789522)
		(end 5.08 -209.535522)
		(width 0.174752)
		(layer "B.Cu")
		(net "PE_RX4_DR8_N")
	)
	(segment
		(start 3.905504 -209.789522)
		(end 4.826 -209.789522)
		(width 0.174752)
		(layer "B.Cu")
		(net "PE_RX4_DR8_N")
	)
	(segment
		(start 3.658108 -209.542126)
		(end 3.905504 -209.789522)
		(width 0.174752)
		(layer "B.Cu")
		(net "PE_RX4_DR8_N")
	)
	(segment
		(start 1.868932 -209.542126)
		(end 3.658108 -209.542126)
		(width 0.174752)
		(layer "B.Cu")
		(net "PE_RX4_DR8_N")
	)
	(segment
		(start 9.464294 -207.7339)
		(end 9.013698 -208.377282)
		(width 0.1651)
		(layer "In2.Cu")
		(net "PE_RX4_DR8_N")
	)
	(segment
		(start 22.278594 -189.4332)
		(end 9.464294 -207.7339)
		(width 0.1651)
		(layer "In2.Cu")
		(net "PE_RX4_DR8_N")
	)
	(segment
		(start 8.563102 -209.02041)
		(end 7.642352 -209.665316)
		(width 0.1651)
		(layer "In2.Cu")
		(net "PE_RX4_DR8_N")
	)
	(segment
		(start 9.013698 -208.377282)
		(end 8.563102 -209.02041)
		(width 0.1651)
		(layer "In2.Cu")
		(net "PE_RX4_DR8_N")
	)
	(segment
		(start 7.080758 -209.764376)
		(end 5.308854 -209.764376)
		(width 0.1651)
		(layer "In2.Cu")
		(net "PE_RX4_DR8_N")
	)
	(segment
		(start 7.502144 -209.689954)
		(end 7.080758 -209.764376)
		(width 0.1651)
		(layer "In2.Cu")
		(net "PE_RX4_DR8_N")
	)
	(segment
		(start 35.39871 -182.612284)
		(end 27.751532 -183.960008)
		(width 0.1651)
		(layer "In2.Cu")
		(net "PE_RX4_DR8_N")
	)
	(segment
		(start 27.751532 -183.960008)
		(end 22.278594 -189.4332)
		(width 0.1651)
		(layer "In2.Cu")
		(net "PE_RX4_DR8_N")
	)
	(segment
		(start 5.308854 -209.764376)
		(end 5.08 -209.535522)
		(width 0.1651)
		(layer "In2.Cu")
		(net "PE_RX4_DR8_N")
	)
	(segment
		(start 36.34613 -182.612284)
		(end 35.39871 -182.612284)
		(width 0.1651)
		(layer "In2.Cu")
		(net "PE_RX4_DR8_N")
	)
	(segment
		(start 36.72713 -182.231284)
		(end 36.34613 -182.612284)
		(width 0.1651)
		(layer "In2.Cu")
		(net "PE_RX4_DR8_N")
	)
	(segment
		(start 7.642352 -209.665316)
		(end 7.502144 -209.689954)
		(width 0.1651)
		(layer "In2.Cu")
		(net "PE_RX4_DR8_N")
	)
	(segment
		(start 37.13353 -285.942532)
		(end 36.72713 -286.348932)
		(width 0.174752)
		(layer "F.Cu")
		(net "PE_RX4_DR7_P")
	)
	(segment
		(start 38.1 -286.189928)
		(end 37.852604 -285.942532)
		(width 0.174752)
		(layer "F.Cu")
		(net "PE_RX4_DR7_P")
	)
	(segment
		(start 37.852604 -285.942532)
		(end 37.13353 -285.942532)
		(width 0.174752)
		(layer "F.Cu")
		(net "PE_RX4_DR7_P")
	)
	(segment
		(start 39.200074 -286.189928)
		(end 38.1 -286.189928)
		(width 0.174752)
		(layer "F.Cu")
		(net "PE_RX4_DR7_P")
	)
	(via
		(at 36.72713 -286.348932)
		(size 0.508)
		(drill 0.254)
		(layers "F.Cu" "B.Cu")
		(net "PE_RX4_DR7_P")
	)
	(via
		(at 5.08 -317.94831)
		(size 0.508)
		(drill 0.254)
		(layers "F.Cu" "B.Cu")
		(net "PE_RX4_DR7_P")
	)
	(segment
		(start 3.657854 -317.942214)
		(end 3.905504 -317.694564)
		(width 0.174752)
		(layer "B.Cu")
		(net "PE_RX4_DR7_P")
	)
	(segment
		(start 1.868932 -317.942214)
		(end 3.657854 -317.942214)
		(width 0.174752)
		(layer "B.Cu")
		(net "PE_RX4_DR7_P")
	)
	(segment
		(start 4.826254 -317.694564)
		(end 5.08 -317.94831)
		(width 0.174752)
		(layer "B.Cu")
		(net "PE_RX4_DR7_P")
	)
	(segment
		(start 3.905504 -317.694564)
		(end 4.826254 -317.694564)
		(width 0.174752)
		(layer "B.Cu")
		(net "PE_RX4_DR7_P")
	)
	(segment
		(start 35.492436 -285.968186)
		(end 33.245298 -286.364426)
		(width 0.1651)
		(layer "In2.Cu")
		(net "PE_RX4_DR7_P")
	)
	(segment
		(start 36.34613 -285.967932)
		(end 35.492436 -285.967932)
		(width 0.1651)
		(layer "In2.Cu")
		(net "PE_RX4_DR7_P")
	)
	(segment
		(start 5.308346 -317.719964)
		(end 5.08 -317.94831)
		(width 0.1651)
		(layer "In2.Cu")
		(net "PE_RX4_DR7_P")
	)
	(segment
		(start 33.245298 -286.364426)
		(end 30.998922 -286.760412)
		(width 0.1651)
		(layer "In2.Cu")
		(net "PE_RX4_DR7_P")
	)
	(segment
		(start 11.084814 -314.452508)
		(end 9.619234 -316.545976)
		(width 0.1651)
		(layer "In2.Cu")
		(net "PE_RX4_DR7_P")
	)
	(segment
		(start 22.635718 -292.616636)
		(end 12.343384 -307.315362)
		(width 0.1651)
		(layer "In2.Cu")
		(net "PE_RX4_DR7_P")
	)
	(segment
		(start 7.112 -317.719964)
		(end 5.308346 -317.719964)
		(width 0.1651)
		(layer "In2.Cu")
		(net "PE_RX4_DR7_P")
	)
	(segment
		(start 35.492436 -285.967932)
		(end 35.492436 -285.968186)
		(width 0.1651)
		(layer "In2.Cu")
		(net "PE_RX4_DR7_P")
	)
	(segment
		(start 36.72713 -286.348932)
		(end 36.34613 -285.967932)
		(width 0.1651)
		(layer "In2.Cu")
		(net "PE_RX4_DR7_P")
	)
	(segment
		(start 9.619234 -316.545976)
		(end 8.22198 -317.52413)
		(width 0.1651)
		(layer "In2.Cu")
		(net "PE_RX4_DR7_P")
	)
	(segment
		(start 8.22198 -317.52413)
		(end 7.112 -317.719964)
		(width 0.1651)
		(layer "In2.Cu")
		(net "PE_RX4_DR7_P")
	)
	(segment
		(start 30.998922 -286.760412)
		(end 22.635718 -292.616636)
		(width 0.1651)
		(layer "In2.Cu")
		(net "PE_RX4_DR7_P")
	)
	(segment
		(start 12.343384 -307.315362)
		(end 11.084814 -314.452508)
		(width 0.1651)
		(layer "In2.Cu")
		(net "PE_RX4_DR7_P")
	)
	(segment
		(start 37.133276 -285.637478)
		(end 36.72713 -285.231332)
		(width 0.174752)
		(layer "F.Cu")
		(net "PE_RX4_DR7_N")
	)
	(segment
		(start 38.1 -285.390082)
		(end 37.852604 -285.637478)
		(width 0.174752)
		(layer "F.Cu")
		(net "PE_RX4_DR7_N")
	)
	(segment
		(start 39.200074 -285.390082)
		(end 38.1 -285.390082)
		(width 0.174752)
		(layer "F.Cu")
		(net "PE_RX4_DR7_N")
	)
	(segment
		(start 37.852604 -285.637478)
		(end 37.133276 -285.637478)
		(width 0.174752)
		(layer "F.Cu")
		(net "PE_RX4_DR7_N")
	)
	(via
		(at 36.72713 -285.231332)
		(size 0.508)
		(drill 0.254)
		(layers "F.Cu" "B.Cu")
		(net "PE_RX4_DR7_N")
	)
	(via
		(at 5.08 -317.13551)
		(size 0.508)
		(drill 0.254)
		(layers "F.Cu" "B.Cu")
		(net "PE_RX4_DR7_N")
	)
	(segment
		(start 3.905504 -317.38951)
		(end 4.826 -317.38951)
		(width 0.174752)
		(layer "B.Cu")
		(net "PE_RX4_DR7_N")
	)
	(segment
		(start 4.826 -317.38951)
		(end 5.08 -317.13551)
		(width 0.174752)
		(layer "B.Cu")
		(net "PE_RX4_DR7_N")
	)
	(segment
		(start 3.658108 -317.142114)
		(end 3.905504 -317.38951)
		(width 0.174752)
		(layer "B.Cu")
		(net "PE_RX4_DR7_N")
	)
	(segment
		(start 1.868932 -317.142114)
		(end 3.658108 -317.142114)
		(width 0.174752)
		(layer "B.Cu")
		(net "PE_RX4_DR7_N")
	)
	(segment
		(start 30.859476 -286.423862)
		(end 22.380194 -292.361112)
		(width 0.1651)
		(layer "In2.Cu")
		(net "PE_RX4_DR7_N")
	)
	(segment
		(start 36.72713 -285.231332)
		(end 36.34613 -285.612332)
		(width 0.1651)
		(layer "In2.Cu")
		(net "PE_RX4_DR7_N")
	)
	(segment
		(start 5.308854 -317.364364)
		(end 5.08 -317.13551)
		(width 0.1651)
		(layer "In2.Cu")
		(net "PE_RX4_DR7_N")
	)
	(segment
		(start 22.380194 -292.361112)
		(end 12.006834 -307.175916)
		(width 0.1651)
		(layer "In2.Cu")
		(net "PE_RX4_DR7_N")
	)
	(segment
		(start 35.461194 -285.612332)
		(end 30.859476 -286.423862)
		(width 0.1651)
		(layer "In2.Cu")
		(net "PE_RX4_DR7_N")
	)
	(segment
		(start 10.748264 -314.313062)
		(end 9.36371 -316.290452)
		(width 0.1651)
		(layer "In2.Cu")
		(net "PE_RX4_DR7_N")
	)
	(segment
		(start 36.34613 -285.612332)
		(end 35.461194 -285.612332)
		(width 0.1651)
		(layer "In2.Cu")
		(net "PE_RX4_DR7_N")
	)
	(segment
		(start 8.082534 -317.18758)
		(end 7.080758 -317.364364)
		(width 0.1651)
		(layer "In2.Cu")
		(net "PE_RX4_DR7_N")
	)
	(segment
		(start 7.080758 -317.364364)
		(end 5.308854 -317.364364)
		(width 0.1651)
		(layer "In2.Cu")
		(net "PE_RX4_DR7_N")
	)
	(segment
		(start 12.006834 -307.175916)
		(end 10.748264 -314.313062)
		(width 0.1651)
		(layer "In2.Cu")
		(net "PE_RX4_DR7_N")
	)
	(segment
		(start 9.36371 -316.290452)
		(end 8.082534 -317.18758)
		(width 0.1651)
		(layer "In2.Cu")
		(net "PE_RX4_DR7_N")
	)
	(segment
		(start 38.1 -389.189976)
		(end 37.852604 -388.94258)
		(width 0.174752)
		(layer "F.Cu")
		(net "PE_RX4_DR6_P")
	)
	(segment
		(start 39.200074 -389.189976)
		(end 38.1 -389.189976)
		(width 0.174752)
		(layer "F.Cu")
		(net "PE_RX4_DR6_P")
	)
	(segment
		(start 37.13353 -388.94258)
		(end 36.72713 -389.34898)
		(width 0.174752)
		(layer "F.Cu")
		(net "PE_RX4_DR6_P")
	)
	(segment
		(start 37.852604 -388.94258)
		(end 37.13353 -388.94258)
		(width 0.174752)
		(layer "F.Cu")
		(net "PE_RX4_DR6_P")
	)
	(via
		(at 36.72713 -389.34898)
		(size 0.508)
		(drill 0.254)
		(layers "F.Cu" "B.Cu")
		(net "PE_RX4_DR6_P")
	)
	(via
		(at 5.08 -358.74833)
		(size 0.508)
		(drill 0.254)
		(layers "F.Cu" "B.Cu")
		(net "PE_RX4_DR6_P")
	)
	(segment
		(start 3.905504 -358.494584)
		(end 4.826254 -358.494584)
		(width 0.174752)
		(layer "B.Cu")
		(net "PE_RX4_DR6_P")
	)
	(segment
		(start 3.657854 -358.742234)
		(end 3.905504 -358.494584)
		(width 0.174752)
		(layer "B.Cu")
		(net "PE_RX4_DR6_P")
	)
	(segment
		(start 1.868932 -358.742234)
		(end 3.657854 -358.742234)
		(width 0.174752)
		(layer "B.Cu")
		(net "PE_RX4_DR6_P")
	)
	(segment
		(start 4.826254 -358.494584)
		(end 5.08 -358.74833)
		(width 0.174752)
		(layer "B.Cu")
		(net "PE_RX4_DR6_P")
	)
	(segment
		(start 7.080758 -358.519984)
		(end 5.308346 -358.519984)
		(width 0.1651)
		(layer "In2.Cu")
		(net "PE_RX4_DR6_P")
	)
	(segment
		(start 25.867106 -387.287262)
		(end 16.995902 -381.075946)
		(width 0.1651)
		(layer "In2.Cu")
		(net "PE_RX4_DR6_P")
	)
	(segment
		(start 16.995902 -381.075946)
		(end 14.990318 -378.210826)
		(width 0.1651)
		(layer "In2.Cu")
		(net "PE_RX4_DR6_P")
	)
	(segment
		(start 7.75081 -358.638094)
		(end 7.080758 -358.519984)
		(width 0.1651)
		(layer "In2.Cu")
		(net "PE_RX4_DR6_P")
	)
	(segment
		(start 5.308346 -358.519984)
		(end 5.08 -358.74833)
		(width 0.1651)
		(layer "In2.Cu")
		(net "PE_RX4_DR6_P")
	)
	(segment
		(start 35.39871 -388.96798)
		(end 25.867106 -387.287262)
		(width 0.1651)
		(layer "In2.Cu")
		(net "PE_RX4_DR6_P")
	)
	(segment
		(start 36.72713 -389.34898)
		(end 36.34613 -388.96798)
		(width 0.1651)
		(layer "In2.Cu")
		(net "PE_RX4_DR6_P")
	)
	(segment
		(start 12.634214 -364.849918)
		(end 8.795512 -359.369868)
		(width 0.1651)
		(layer "In2.Cu")
		(net "PE_RX4_DR6_P")
	)
	(segment
		(start 14.990318 -378.210826)
		(end 12.634214 -364.849918)
		(width 0.1651)
		(layer "In2.Cu")
		(net "PE_RX4_DR6_P")
	)
	(segment
		(start 36.34613 -388.96798)
		(end 35.39871 -388.96798)
		(width 0.1651)
		(layer "In2.Cu")
		(net "PE_RX4_DR6_P")
	)
	(segment
		(start 8.795512 -359.369868)
		(end 7.75081 -358.638094)
		(width 0.1651)
		(layer "In2.Cu")
		(net "PE_RX4_DR6_P")
	)
	(segment
		(start 37.852604 -388.637526)
		(end 37.133276 -388.637526)
		(width 0.174752)
		(layer "F.Cu")
		(net "PE_RX4_DR6_N")
	)
	(segment
		(start 38.1 -388.39013)
		(end 37.852604 -388.637526)
		(width 0.174752)
		(layer "F.Cu")
		(net "PE_RX4_DR6_N")
	)
	(segment
		(start 37.133276 -388.637526)
		(end 36.72713 -388.23138)
		(width 0.174752)
		(layer "F.Cu")
		(net "PE_RX4_DR6_N")
	)
	(segment
		(start 39.200074 -388.39013)
		(end 38.1 -388.39013)
		(width 0.174752)
		(layer "F.Cu")
		(net "PE_RX4_DR6_N")
	)
	(via
		(at 36.72713 -388.23138)
		(size 0.508)
		(drill 0.254)
		(layers "F.Cu" "B.Cu")
		(net "PE_RX4_DR6_N")
	)
	(via
		(at 5.08 -357.93553)
		(size 0.508)
		(drill 0.254)
		(layers "F.Cu" "B.Cu")
		(net "PE_RX4_DR6_N")
	)
	(segment
		(start 4.826 -358.18953)
		(end 5.08 -357.93553)
		(width 0.174752)
		(layer "B.Cu")
		(net "PE_RX4_DR6_N")
	)
	(segment
		(start 1.868932 -357.942134)
		(end 3.658108 -357.942134)
		(width 0.174752)
		(layer "B.Cu")
		(net "PE_RX4_DR6_N")
	)
	(segment
		(start 3.658108 -357.942134)
		(end 3.905504 -358.18953)
		(width 0.174752)
		(layer "B.Cu")
		(net "PE_RX4_DR6_N")
	)
	(segment
		(start 3.905504 -358.18953)
		(end 4.826 -358.18953)
		(width 0.174752)
		(layer "B.Cu")
		(net "PE_RX4_DR6_N")
	)
	(segment
		(start 12.970764 -364.710472)
		(end 9.051036 -359.114344)
		(width 0.1651)
		(layer "In2.Cu")
		(net "PE_RX4_DR6_N")
	)
	(segment
		(start 26.006552 -386.950712)
		(end 17.251426 -380.820422)
		(width 0.1651)
		(layer "In2.Cu")
		(net "PE_RX4_DR6_N")
	)
	(segment
		(start 36.34613 -388.61238)
		(end 35.429952 -388.61238)
		(width 0.1651)
		(layer "In2.Cu")
		(net "PE_RX4_DR6_N")
	)
	(segment
		(start 7.890256 -358.301544)
		(end 7.112 -358.164384)
		(width 0.1651)
		(layer "In2.Cu")
		(net "PE_RX4_DR6_N")
	)
	(segment
		(start 15.326868 -378.07138)
		(end 12.970764 -364.710472)
		(width 0.1651)
		(layer "In2.Cu")
		(net "PE_RX4_DR6_N")
	)
	(segment
		(start 35.429952 -388.61238)
		(end 26.006552 -386.950712)
		(width 0.1651)
		(layer "In2.Cu")
		(net "PE_RX4_DR6_N")
	)
	(segment
		(start 36.72713 -388.23138)
		(end 36.34613 -388.61238)
		(width 0.1651)
		(layer "In2.Cu")
		(net "PE_RX4_DR6_N")
	)
	(segment
		(start 9.051036 -359.114344)
		(end 7.890256 -358.301544)
		(width 0.1651)
		(layer "In2.Cu")
		(net "PE_RX4_DR6_N")
	)
	(segment
		(start 5.308854 -358.164384)
		(end 5.08 -357.93553)
		(width 0.1651)
		(layer "In2.Cu")
		(net "PE_RX4_DR6_N")
	)
	(segment
		(start 7.112 -358.164384)
		(end 5.308854 -358.164384)
		(width 0.1651)
		(layer "In2.Cu")
		(net "PE_RX4_DR6_N")
	)
	(segment
		(start 17.251426 -380.820422)
		(end 15.326868 -378.07138)
		(width 0.1651)
		(layer "In2.Cu")
		(net "PE_RX4_DR6_N")
	)
	(segment
		(start 37.725604 -491.637574)
		(end 37.133276 -491.637574)
		(width 0.174752)
		(layer "F.Cu")
		(net "PE_RX4_DR5_P")
	)
	(segment
		(start 39.200074 -491.390178)
		(end 37.973 -491.390178)
		(width 0.174752)
		(layer "F.Cu")
		(net "PE_RX4_DR5_P")
	)
	(segment
		(start 37.133276 -491.637574)
		(end 36.72713 -491.231428)
		(width 0.174752)
		(layer "F.Cu")
		(net "PE_RX4_DR5_P")
	)
	(segment
		(start 37.973 -491.390178)
		(end 37.725604 -491.637574)
		(width 0.174752)
		(layer "F.Cu")
		(net "PE_RX4_DR5_P")
	)
	(via
		(at 5.08 -444.735204)
		(size 0.508)
		(drill 0.254)
		(layers "F.Cu" "B.Cu")
		(net "PE_RX4_DR5_P")
	)
	(via
		(at 36.72713 -491.231428)
		(size 0.508)
		(drill 0.254)
		(layers "F.Cu" "B.Cu")
		(net "PE_RX4_DR5_P")
	)
	(segment
		(start 1.868932 -444.741808)
		(end 3.658108 -444.741808)
		(width 0.174752)
		(layer "B.Cu")
		(net "PE_RX4_DR5_P")
	)
	(segment
		(start 3.658108 -444.741808)
		(end 3.90525 -444.98895)
		(width 0.174752)
		(layer "B.Cu")
		(net "PE_RX4_DR5_P")
	)
	(segment
		(start 4.826254 -444.98895)
		(end 5.08 -444.735204)
		(width 0.174752)
		(layer "B.Cu")
		(net "PE_RX4_DR5_P")
	)
	(segment
		(start 3.90525 -444.98895)
		(end 4.826254 -444.98895)
		(width 0.174752)
		(layer "B.Cu")
		(net "PE_RX4_DR5_P")
	)
	(segment
		(start 13.51407 -472.043506)
		(end 8.971534 -446.301876)
		(width 0.1651)
		(layer "In2.Cu")
		(net "PE_RX4_DR5_P")
	)
	(segment
		(start 8.427212 -445.524128)
		(end 7.800594 -445.08547)
		(width 0.1651)
		(layer "In2.Cu")
		(net "PE_RX4_DR5_P")
	)
	(segment
		(start 5.308854 -444.964058)
		(end 5.08 -444.735204)
		(width 0.1651)
		(layer "In2.Cu")
		(net "PE_RX4_DR5_P")
	)
	(segment
		(start 7.112 -444.964058)
		(end 5.308854 -444.964058)
		(width 0.1651)
		(layer "In2.Cu")
		(net "PE_RX4_DR5_P")
	)
	(segment
		(start 7.800594 -445.08547)
		(end 7.112 -444.964058)
		(width 0.1651)
		(layer "In2.Cu")
		(net "PE_RX4_DR5_P")
	)
	(segment
		(start 24.381206 -487.56443)
		(end 13.51407 -472.043506)
		(width 0.1651)
		(layer "In2.Cu")
		(net "PE_RX4_DR5_P")
	)
	(segment
		(start 35.429952 -491.612428)
		(end 28.389326 -490.370876)
		(width 0.1651)
		(layer "In2.Cu")
		(net "PE_RX4_DR5_P")
	)
	(segment
		(start 8.971534 -446.301876)
		(end 8.427212 -445.524128)
		(width 0.1651)
		(layer "In2.Cu")
		(net "PE_RX4_DR5_P")
	)
	(segment
		(start 28.389326 -490.370876)
		(end 24.381206 -487.56443)
		(width 0.1651)
		(layer "In2.Cu")
		(net "PE_RX4_DR5_P")
	)
	(segment
		(start 36.34613 -491.612428)
		(end 35.429952 -491.612428)
		(width 0.1651)
		(layer "In2.Cu")
		(net "PE_RX4_DR5_P")
	)
	(segment
		(start 36.72713 -491.231428)
		(end 36.34613 -491.612428)
		(width 0.1651)
		(layer "In2.Cu")
		(net "PE_RX4_DR5_P")
	)
	(segment
		(start 37.725604 -491.942628)
		(end 37.13353 -491.942628)
		(width 0.174752)
		(layer "F.Cu")
		(net "PE_RX4_DR5_N")
	)
	(segment
		(start 37.13353 -491.942628)
		(end 36.72713 -492.349028)
		(width 0.174752)
		(layer "F.Cu")
		(net "PE_RX4_DR5_N")
	)
	(segment
		(start 39.200074 -492.190024)
		(end 37.973 -492.190024)
		(width 0.174752)
		(layer "F.Cu")
		(net "PE_RX4_DR5_N")
	)
	(segment
		(start 37.973 -492.190024)
		(end 37.725604 -491.942628)
		(width 0.174752)
		(layer "F.Cu")
		(net "PE_RX4_DR5_N")
	)
	(via
		(at 36.72713 -492.349028)
		(size 0.508)
		(drill 0.254)
		(layers "F.Cu" "B.Cu")
		(net "PE_RX4_DR5_N")
	)
	(via
		(at 5.08 -445.548004)
		(size 0.508)
		(drill 0.254)
		(layers "F.Cu" "B.Cu")
		(net "PE_RX4_DR5_N")
	)
	(segment
		(start 3.657854 -445.541908)
		(end 3.905758 -445.294004)
		(width 0.174752)
		(layer "B.Cu")
		(net "PE_RX4_DR5_N")
	)
	(segment
		(start 4.826 -445.294004)
		(end 5.08 -445.548004)
		(width 0.174752)
		(layer "B.Cu")
		(net "PE_RX4_DR5_N")
	)
	(segment
		(start 3.905758 -445.294004)
		(end 4.826 -445.294004)
		(width 0.174752)
		(layer "B.Cu")
		(net "PE_RX4_DR5_N")
	)
	(segment
		(start 1.868932 -445.541908)
		(end 3.657854 -445.541908)
		(width 0.174752)
		(layer "B.Cu")
		(net "PE_RX4_DR5_N")
	)
	(segment
		(start 5.308346 -445.319658)
		(end 5.08 -445.548004)
		(width 0.1651)
		(layer "In2.Cu")
		(net "PE_RX4_DR5_N")
	)
	(segment
		(start 8.171942 -445.779906)
		(end 8.171688 -445.779652)
		(width 0.1651)
		(layer "In2.Cu")
		(net "PE_RX4_DR5_N")
	)
	(segment
		(start 36.34613 -491.968028)
		(end 35.39871 -491.968028)
		(width 0.1651)
		(layer "In2.Cu")
		(net "PE_RX4_DR5_N")
	)
	(segment
		(start 24.125682 -487.819954)
		(end 13.17752 -472.182952)
		(width 0.1651)
		(layer "In2.Cu")
		(net "PE_RX4_DR5_N")
	)
	(segment
		(start 13.17752 -472.182952)
		(end 8.634984 -446.441322)
		(width 0.1651)
		(layer "In2.Cu")
		(net "PE_RX4_DR5_N")
	)
	(segment
		(start 36.72713 -492.349028)
		(end 36.34613 -491.968028)
		(width 0.1651)
		(layer "In2.Cu")
		(net "PE_RX4_DR5_N")
	)
	(segment
		(start 7.080758 -445.319658)
		(end 5.308346 -445.319658)
		(width 0.1651)
		(layer "In2.Cu")
		(net "PE_RX4_DR5_N")
	)
	(segment
		(start 35.39871 -491.968028)
		(end 28.24988 -490.707426)
		(width 0.1651)
		(layer "In2.Cu")
		(net "PE_RX4_DR5_N")
	)
	(segment
		(start 28.24988 -490.707426)
		(end 24.125682 -487.819954)
		(width 0.1651)
		(layer "In2.Cu")
		(net "PE_RX4_DR5_N")
	)
	(segment
		(start 7.661148 -445.42202)
		(end 7.080758 -445.319658)
		(width 0.1651)
		(layer "In2.Cu")
		(net "PE_RX4_DR5_N")
	)
	(segment
		(start 8.171688 -445.779652)
		(end 7.661148 -445.42202)
		(width 0.1651)
		(layer "In2.Cu")
		(net "PE_RX4_DR5_N")
	)
	(segment
		(start 8.634984 -446.441322)
		(end 8.171942 -445.779906)
		(width 0.1651)
		(layer "In2.Cu")
		(net "PE_RX4_DR5_N")
	)
	(segment
		(start 222.133414 -79.942436)
		(end 221.727014 -80.348836)
		(width 0.174752)
		(layer "F.Cu")
		(net "PE_RX4_DR4_P")
	)
	(segment
		(start 223.132396 -80.189832)
		(end 222.885 -79.942436)
		(width 0.174752)
		(layer "F.Cu")
		(net "PE_RX4_DR4_P")
	)
	(segment
		(start 224.199958 -80.189832)
		(end 223.132396 -80.189832)
		(width 0.174752)
		(layer "F.Cu")
		(net "PE_RX4_DR4_P")
	)
	(segment
		(start 222.885 -79.942436)
		(end 222.133414 -79.942436)
		(width 0.174752)
		(layer "F.Cu")
		(net "PE_RX4_DR4_P")
	)
	(via
		(at 5.08 -284.348174)
		(size 0.508)
		(drill 0.254)
		(layers "F.Cu" "B.Cu")
		(net "PE_RX4_DR4_P")
	)
	(via
		(at 221.727014 -80.348836)
		(size 0.508)
		(drill 0.254)
		(layers "F.Cu" "B.Cu")
		(net "PE_RX4_DR4_P")
	)
	(segment
		(start 1.868932 -284.342078)
		(end 3.658108 -284.342078)
		(width 0.174752)
		(layer "B.Cu")
		(net "PE_RX4_DR4_P")
	)
	(segment
		(start 4.826508 -284.094682)
		(end 5.08 -284.348174)
		(width 0.174752)
		(layer "B.Cu")
		(net "PE_RX4_DR4_P")
	)
	(segment
		(start 3.658108 -284.342078)
		(end 3.905504 -284.094682)
		(width 0.174752)
		(layer "B.Cu")
		(net "PE_RX4_DR4_P")
	)
	(segment
		(start 3.905504 -284.094682)
		(end 4.826508 -284.094682)
		(width 0.174752)
		(layer "B.Cu")
		(net "PE_RX4_DR4_P")
	)
	(segment
		(start 6.99516 -284.120082)
		(end 10.679176 -283.47035)
		(width 0.1651)
		(layer "In2.Cu")
		(net "PE_RX4_DR4_P")
	)
	(segment
		(start 34.605214 -239.214914)
		(end 89.438734 -160.907984)
		(width 0.1651)
		(layer "In2.Cu")
		(net "PE_RX4_DR4_P")
	)
	(segment
		(start 5.08 -284.348174)
		(end 5.308092 -284.120082)
		(width 0.1651)
		(layer "In2.Cu")
		(net "PE_RX4_DR4_P")
	)
	(segment
		(start 89.438734 -160.907984)
		(end 199.84593 -83.596988)
		(width 0.1651)
		(layer "In2.Cu")
		(net "PE_RX4_DR4_P")
	)
	(segment
		(start 20.66544 -276.478238)
		(end 24.414226 -271.124172)
		(width 0.1651)
		(layer "In2.Cu")
		(net "PE_RX4_DR4_P")
	)
	(segment
		(start 24.414226 -271.124172)
		(end 26.920952 -256.904998)
		(width 0.1651)
		(layer "In2.Cu")
		(net "PE_RX4_DR4_P")
	)
	(segment
		(start 33.021778 -248.19229)
		(end 34.605214 -239.214914)
		(width 0.1651)
		(layer "In2.Cu")
		(net "PE_RX4_DR4_P")
	)
	(segment
		(start 220.429836 -79.967836)
		(end 221.346014 -79.967836)
		(width 0.1651)
		(layer "In2.Cu")
		(net "PE_RX4_DR4_P")
	)
	(segment
		(start 10.679176 -283.47035)
		(end 20.66544 -276.478238)
		(width 0.1651)
		(layer "In2.Cu")
		(net "PE_RX4_DR4_P")
	)
	(segment
		(start 199.84593 -83.596988)
		(end 220.429836 -79.967836)
		(width 0.1651)
		(layer "In2.Cu")
		(net "PE_RX4_DR4_P")
	)
	(segment
		(start 221.346014 -79.967836)
		(end 221.727014 -80.348836)
		(width 0.1651)
		(layer "In2.Cu")
		(net "PE_RX4_DR4_P")
	)
	(segment
		(start 5.308092 -284.120082)
		(end 6.99516 -284.120082)
		(width 0.1651)
		(layer "In2.Cu")
		(net "PE_RX4_DR4_P")
	)
	(segment
		(start 26.920952 -256.904998)
		(end 33.021778 -248.19229)
		(width 0.1651)
		(layer "In2.Cu")
		(net "PE_RX4_DR4_P")
	)
	(segment
		(start 222.13316 -79.637382)
		(end 221.727014 -79.231236)
		(width 0.174752)
		(layer "F.Cu")
		(net "PE_RX4_DR4_N")
	)
	(segment
		(start 224.199958 -79.389986)
		(end 223.139 -79.389986)
		(width 0.174752)
		(layer "F.Cu")
		(net "PE_RX4_DR4_N")
	)
	(segment
		(start 223.139 -79.389986)
		(end 222.891604 -79.637382)
		(width 0.174752)
		(layer "F.Cu")
		(net "PE_RX4_DR4_N")
	)
	(segment
		(start 222.891604 -79.637382)
		(end 222.13316 -79.637382)
		(width 0.174752)
		(layer "F.Cu")
		(net "PE_RX4_DR4_N")
	)
	(via
		(at 5.08 -283.535374)
		(size 0.508)
		(drill 0.254)
		(layers "F.Cu" "B.Cu")
		(net "PE_RX4_DR4_N")
	)
	(via
		(at 221.727014 -79.231236)
		(size 0.508)
		(drill 0.254)
		(layers "F.Cu" "B.Cu")
		(net "PE_RX4_DR4_N")
	)
	(segment
		(start 3.905504 -283.789628)
		(end 4.825746 -283.789628)
		(width 0.174752)
		(layer "B.Cu")
		(net "PE_RX4_DR4_N")
	)
	(segment
		(start 4.825746 -283.789628)
		(end 5.08 -283.535374)
		(width 0.174752)
		(layer "B.Cu")
		(net "PE_RX4_DR4_N")
	)
	(segment
		(start 3.658108 -283.542232)
		(end 3.905504 -283.789628)
		(width 0.174752)
		(layer "B.Cu")
		(net "PE_RX4_DR4_N")
	)
	(segment
		(start 1.868932 -283.542232)
		(end 3.658108 -283.542232)
		(width 0.174752)
		(layer "B.Cu")
		(net "PE_RX4_DR4_N")
	)
	(segment
		(start 220.398594 -79.612236)
		(end 221.346014 -79.612236)
		(width 0.1651)
		(layer "In2.Cu")
		(net "PE_RX4_DR4_N")
	)
	(segment
		(start 89.18321 -160.65246)
		(end 199.706484 -83.260438)
		(width 0.1651)
		(layer "In2.Cu")
		(net "PE_RX4_DR4_N")
	)
	(segment
		(start 5.309108 -283.764482)
		(end 6.963918 -283.764482)
		(width 0.1651)
		(layer "In2.Cu")
		(net "PE_RX4_DR4_N")
	)
	(segment
		(start 10.53973 -283.133546)
		(end 20.410424 -276.222206)
		(width 0.1651)
		(layer "In2.Cu")
		(net "PE_RX4_DR4_N")
	)
	(segment
		(start 20.410424 -276.222206)
		(end 24.077676 -270.984472)
		(width 0.1651)
		(layer "In2.Cu")
		(net "PE_RX4_DR4_N")
	)
	(segment
		(start 221.346014 -79.612236)
		(end 221.727014 -79.231236)
		(width 0.1651)
		(layer "In2.Cu")
		(net "PE_RX4_DR4_N")
	)
	(segment
		(start 199.706484 -83.260438)
		(end 220.398594 -79.612236)
		(width 0.1651)
		(layer "In2.Cu")
		(net "PE_RX4_DR4_N")
	)
	(segment
		(start 26.584402 -256.765552)
		(end 32.685228 -248.052844)
		(width 0.1651)
		(layer "In2.Cu")
		(net "PE_RX4_DR4_N")
	)
	(segment
		(start 34.268664 -239.075468)
		(end 89.18321 -160.65246)
		(width 0.1651)
		(layer "In2.Cu")
		(net "PE_RX4_DR4_N")
	)
	(segment
		(start 6.963918 -283.764482)
		(end 10.53973 -283.133546)
		(width 0.1651)
		(layer "In2.Cu")
		(net "PE_RX4_DR4_N")
	)
	(segment
		(start 5.08 -283.535374)
		(end 5.309108 -283.764482)
		(width 0.1651)
		(layer "In2.Cu")
		(net "PE_RX4_DR4_N")
	)
	(segment
		(start 24.077676 -270.984472)
		(end 26.584402 -256.765552)
		(width 0.1651)
		(layer "In2.Cu")
		(net "PE_RX4_DR4_N")
	)
	(segment
		(start 32.685228 -248.052844)
		(end 34.268664 -239.075468)
		(width 0.1651)
		(layer "In2.Cu")
		(net "PE_RX4_DR4_N")
	)
	(segment
		(start 223.132396 -183.18988)
		(end 222.885 -182.942484)
		(width 0.174752)
		(layer "F.Cu")
		(net "PE_RX4_DR3_P")
	)
	(segment
		(start 224.199958 -183.18988)
		(end 223.132396 -183.18988)
		(width 0.174752)
		(layer "F.Cu")
		(net "PE_RX4_DR3_P")
	)
	(segment
		(start 222.133414 -182.942484)
		(end 221.727014 -183.348884)
		(width 0.174752)
		(layer "F.Cu")
		(net "PE_RX4_DR3_P")
	)
	(segment
		(start 222.885 -182.942484)
		(end 222.133414 -182.942484)
		(width 0.174752)
		(layer "F.Cu")
		(net "PE_RX4_DR3_P")
	)
	(via
		(at 221.727014 -183.348884)
		(size 0.508)
		(drill 0.254)
		(layers "F.Cu" "B.Cu")
		(net "PE_RX4_DR3_P")
	)
	(via
		(at 5.08 -300.348142)
		(size 0.508)
		(drill 0.254)
		(layers "F.Cu" "B.Cu")
		(net "PE_RX4_DR3_P")
	)
	(segment
		(start 3.905504 -300.09465)
		(end 4.826508 -300.09465)
		(width 0.174752)
		(layer "B.Cu")
		(net "PE_RX4_DR3_P")
	)
	(segment
		(start 4.826508 -300.09465)
		(end 5.08 -300.348142)
		(width 0.174752)
		(layer "B.Cu")
		(net "PE_RX4_DR3_P")
	)
	(segment
		(start 3.658108 -300.342046)
		(end 3.905504 -300.09465)
		(width 0.174752)
		(layer "B.Cu")
		(net "PE_RX4_DR3_P")
	)
	(segment
		(start 1.868932 -300.342046)
		(end 3.658108 -300.342046)
		(width 0.174752)
		(layer "B.Cu")
		(net "PE_RX4_DR3_P")
	)
	(segment
		(start 36.838382 -249.890026)
		(end 38.227508 -242.016534)
		(width 0.1651)
		(layer "In2.Cu")
		(net "PE_RX4_DR3_P")
	)
	(segment
		(start 5.308092 -300.12005)
		(end 6.391148 -300.12005)
		(width 0.1651)
		(layer "In2.Cu")
		(net "PE_RX4_DR3_P")
	)
	(segment
		(start 38.227508 -242.016534)
		(end 57.587388 -214.363046)
		(width 0.1651)
		(layer "In2.Cu")
		(net "PE_RX4_DR3_P")
	)
	(segment
		(start 220.167454 -182.967884)
		(end 221.346014 -182.967884)
		(width 0.1651)
		(layer "In2.Cu")
		(net "PE_RX4_DR3_P")
	)
	(segment
		(start 7.701534 -299.889164)
		(end 15.13459 -294.690292)
		(width 0.1651)
		(layer "In2.Cu")
		(net "PE_RX4_DR3_P")
	)
	(segment
		(start 221.346014 -182.967884)
		(end 221.727014 -183.348884)
		(width 0.1651)
		(layer "In2.Cu")
		(net "PE_RX4_DR3_P")
	)
	(segment
		(start 83.57997 -196.162168)
		(end 189.308486 -177.527204)
		(width 0.1651)
		(layer "In2.Cu")
		(net "PE_RX4_DR3_P")
	)
	(segment
		(start 6.391148 -300.12005)
		(end 7.701534 -299.889164)
		(width 0.1651)
		(layer "In2.Cu")
		(net "PE_RX4_DR3_P")
	)
	(segment
		(start 57.587388 -214.363046)
		(end 83.57997 -196.162168)
		(width 0.1651)
		(layer "In2.Cu")
		(net "PE_RX4_DR3_P")
	)
	(segment
		(start 15.13459 -294.690292)
		(end 28.910534 -275.00834)
		(width 0.1651)
		(layer "In2.Cu")
		(net "PE_RX4_DR3_P")
	)
	(segment
		(start 32.16275 -256.566924)
		(end 36.838382 -249.890026)
		(width 0.1651)
		(layer "In2.Cu")
		(net "PE_RX4_DR3_P")
	)
	(segment
		(start 5.08 -300.348142)
		(end 5.308092 -300.12005)
		(width 0.1651)
		(layer "In2.Cu")
		(net "PE_RX4_DR3_P")
	)
	(segment
		(start 28.910534 -275.00834)
		(end 32.16275 -256.566924)
		(width 0.1651)
		(layer "In2.Cu")
		(net "PE_RX4_DR3_P")
	)
	(segment
		(start 189.308486 -177.527204)
		(end 220.167454 -182.967884)
		(width 0.1651)
		(layer "In2.Cu")
		(net "PE_RX4_DR3_P")
	)
	(segment
		(start 224.199958 -182.390034)
		(end 223.139 -182.390034)
		(width 0.174752)
		(layer "F.Cu")
		(net "PE_RX4_DR3_N")
	)
	(segment
		(start 223.139 -182.390034)
		(end 222.891604 -182.63743)
		(width 0.174752)
		(layer "F.Cu")
		(net "PE_RX4_DR3_N")
	)
	(segment
		(start 222.13316 -182.63743)
		(end 221.727014 -182.231284)
		(width 0.174752)
		(layer "F.Cu")
		(net "PE_RX4_DR3_N")
	)
	(segment
		(start 222.891604 -182.63743)
		(end 222.13316 -182.63743)
		(width 0.174752)
		(layer "F.Cu")
		(net "PE_RX4_DR3_N")
	)
	(via
		(at 5.08 -299.535342)
		(size 0.508)
		(drill 0.254)
		(layers "F.Cu" "B.Cu")
		(net "PE_RX4_DR3_N")
	)
	(via
		(at 221.727014 -182.231284)
		(size 0.508)
		(drill 0.254)
		(layers "F.Cu" "B.Cu")
		(net "PE_RX4_DR3_N")
	)
	(segment
		(start 4.825746 -299.789596)
		(end 5.08 -299.535342)
		(width 0.174752)
		(layer "B.Cu")
		(net "PE_RX4_DR3_N")
	)
	(segment
		(start 3.905504 -299.789596)
		(end 4.825746 -299.789596)
		(width 0.174752)
		(layer "B.Cu")
		(net "PE_RX4_DR3_N")
	)
	(segment
		(start 1.868932 -299.5422)
		(end 3.658108 -299.5422)
		(width 0.174752)
		(layer "B.Cu")
		(net "PE_RX4_DR3_N")
	)
	(segment
		(start 3.658108 -299.5422)
		(end 3.905504 -299.789596)
		(width 0.174752)
		(layer "B.Cu")
		(net "PE_RX4_DR3_N")
	)
	(segment
		(start 37.890958 -241.877088)
		(end 57.331864 -214.107522)
		(width 0.1651)
		(layer "In2.Cu")
		(net "PE_RX4_DR3_N")
	)
	(segment
		(start 220.198696 -182.612284)
		(end 221.346014 -182.612284)
		(width 0.1651)
		(layer "In2.Cu")
		(net "PE_RX4_DR3_N")
	)
	(segment
		(start 28.573984 -274.86864)
		(end 31.8262 -256.427478)
		(width 0.1651)
		(layer "In2.Cu")
		(net "PE_RX4_DR3_N")
	)
	(segment
		(start 221.346014 -182.612284)
		(end 221.727014 -182.231284)
		(width 0.1651)
		(layer "In2.Cu")
		(net "PE_RX4_DR3_N")
	)
	(segment
		(start 5.309108 -299.76445)
		(end 6.359906 -299.76445)
		(width 0.1651)
		(layer "In2.Cu")
		(net "PE_RX4_DR3_N")
	)
	(segment
		(start 28.573984 -274.868894)
		(end 28.573984 -274.86864)
		(width 0.1651)
		(layer "In2.Cu")
		(net "PE_RX4_DR3_N")
	)
	(segment
		(start 34.209228 -253.024386)
		(end 36.501832 -249.75058)
		(width 0.1651)
		(layer "In2.Cu")
		(net "PE_RX4_DR3_N")
	)
	(segment
		(start 14.879066 -294.434768)
		(end 28.573984 -274.868894)
		(width 0.1651)
		(layer "In2.Cu")
		(net "PE_RX4_DR3_N")
	)
	(segment
		(start 57.331864 -214.107522)
		(end 83.440524 -195.825618)
		(width 0.1651)
		(layer "In2.Cu")
		(net "PE_RX4_DR3_N")
	)
	(segment
		(start 83.440524 -195.825618)
		(end 189.308486 -177.166016)
		(width 0.1651)
		(layer "In2.Cu")
		(net "PE_RX4_DR3_N")
	)
	(segment
		(start 32.57804 -255.35382)
		(end 34.209228 -253.024386)
		(width 0.1651)
		(layer "In2.Cu")
		(net "PE_RX4_DR3_N")
	)
	(segment
		(start 7.562088 -299.55236)
		(end 14.879066 -294.434768)
		(width 0.1651)
		(layer "In2.Cu")
		(net "PE_RX4_DR3_N")
	)
	(segment
		(start 36.501832 -249.75058)
		(end 37.890958 -241.877088)
		(width 0.1651)
		(layer "In2.Cu")
		(net "PE_RX4_DR3_N")
	)
	(segment
		(start 31.8262 -256.427478)
		(end 32.57804 -255.35382)
		(width 0.1651)
		(layer "In2.Cu")
		(net "PE_RX4_DR3_N")
	)
	(segment
		(start 189.308486 -177.166016)
		(end 220.198696 -182.612284)
		(width 0.1651)
		(layer "In2.Cu")
		(net "PE_RX4_DR3_N")
	)
	(segment
		(start 6.359906 -299.76445)
		(end 7.562088 -299.55236)
		(width 0.1651)
		(layer "In2.Cu")
		(net "PE_RX4_DR3_N")
	)
	(segment
		(start 5.08 -299.535342)
		(end 5.309108 -299.76445)
		(width 0.1651)
		(layer "In2.Cu")
		(net "PE_RX4_DR3_N")
	)
	(segment
		(start 224.199958 -286.189928)
		(end 223.132396 -286.189928)
		(width 0.174752)
		(layer "F.Cu")
		(net "PE_RX4_DR2_P")
	)
	(segment
		(start 222.133414 -285.942532)
		(end 221.727014 -286.348932)
		(width 0.174752)
		(layer "F.Cu")
		(net "PE_RX4_DR2_P")
	)
	(segment
		(start 222.885 -285.942532)
		(end 222.133414 -285.942532)
		(width 0.174752)
		(layer "F.Cu")
		(net "PE_RX4_DR2_P")
	)
	(segment
		(start 223.132396 -286.189928)
		(end 222.885 -285.942532)
		(width 0.174752)
		(layer "F.Cu")
		(net "PE_RX4_DR2_P")
	)
	(via
		(at 221.727014 -286.348932)
		(size 0.508)
		(drill 0.254)
		(layers "F.Cu" "B.Cu")
		(net "PE_RX4_DR2_P")
	)
	(via
		(at 5.08 -330.748132)
		(size 0.508)
		(drill 0.254)
		(layers "F.Cu" "B.Cu")
		(net "PE_RX4_DR2_P")
	)
	(segment
		(start 1.868932 -330.742036)
		(end 3.658108 -330.742036)
		(width 0.174752)
		(layer "B.Cu")
		(net "PE_RX4_DR2_P")
	)
	(segment
		(start 4.826508 -330.49464)
		(end 5.08 -330.748132)
		(width 0.174752)
		(layer "B.Cu")
		(net "PE_RX4_DR2_P")
	)
	(segment
		(start 3.905504 -330.49464)
		(end 4.826508 -330.49464)
		(width 0.174752)
		(layer "B.Cu")
		(net "PE_RX4_DR2_P")
	)
	(segment
		(start 3.658108 -330.742036)
		(end 3.905504 -330.49464)
		(width 0.174752)
		(layer "B.Cu")
		(net "PE_RX4_DR2_P")
	)
	(segment
		(start 221.346014 -285.967932)
		(end 220.398594 -285.967932)
		(width 0.1651)
		(layer "In2.Cu")
		(net "PE_RX4_DR2_P")
	)
	(segment
		(start 21.308314 -304.60315)
		(end 17.598136 -307.200808)
		(width 0.1651)
		(layer "In2.Cu")
		(net "PE_RX4_DR2_P")
	)
	(segment
		(start 17.598136 -307.200808)
		(end 16.60652 -308.617112)
		(width 0.1651)
		(layer "In2.Cu")
		(net "PE_RX4_DR2_P")
	)
	(segment
		(start 11.997944 -327.213722)
		(end 7.480808 -330.37653)
		(width 0.1651)
		(layer "In2.Cu")
		(net "PE_RX4_DR2_P")
	)
	(segment
		(start 67.911218 -290.72332)
		(end 46.383956 -305.796442)
		(width 0.1651)
		(layer "In2.Cu")
		(net "PE_RX4_DR2_P")
	)
	(segment
		(start 46.383956 -305.796442)
		(end 38.864794 -307.122322)
		(width 0.1651)
		(layer "In2.Cu")
		(net "PE_RX4_DR2_P")
	)
	(segment
		(start 157.658562 -274.905216)
		(end 67.911218 -290.72332)
		(width 0.1651)
		(layer "In2.Cu")
		(net "PE_RX4_DR2_P")
	)
	(segment
		(start 5.308092 -330.52004)
		(end 5.08 -330.748132)
		(width 0.1651)
		(layer "In2.Cu")
		(net "PE_RX4_DR2_P")
	)
	(segment
		(start 7.480808 -330.37653)
		(end 6.666484 -330.52004)
		(width 0.1651)
		(layer "In2.Cu")
		(net "PE_RX4_DR2_P")
	)
	(segment
		(start 220.398594 -285.967932)
		(end 157.658562 -274.905216)
		(width 0.1651)
		(layer "In2.Cu")
		(net "PE_RX4_DR2_P")
	)
	(segment
		(start 6.666484 -330.52004)
		(end 5.308092 -330.52004)
		(width 0.1651)
		(layer "In2.Cu")
		(net "PE_RX4_DR2_P")
	)
	(segment
		(start 16.60652 -308.617112)
		(end 13.77442 -324.676516)
		(width 0.1651)
		(layer "In2.Cu")
		(net "PE_RX4_DR2_P")
	)
	(segment
		(start 221.727014 -286.348932)
		(end 221.346014 -285.967932)
		(width 0.1651)
		(layer "In2.Cu")
		(net "PE_RX4_DR2_P")
	)
	(segment
		(start 38.864794 -307.122322)
		(end 22.943312 -304.314606)
		(width 0.1651)
		(layer "In2.Cu")
		(net "PE_RX4_DR2_P")
	)
	(segment
		(start 13.77442 -324.676516)
		(end 11.997944 -327.213722)
		(width 0.1651)
		(layer "In2.Cu")
		(net "PE_RX4_DR2_P")
	)
	(segment
		(start 22.943312 -304.314606)
		(end 21.308314 -304.60315)
		(width 0.1651)
		(layer "In2.Cu")
		(net "PE_RX4_DR2_P")
	)
	(segment
		(start 224.199958 -285.390082)
		(end 223.139 -285.390082)
		(width 0.174752)
		(layer "F.Cu")
		(net "PE_RX4_DR2_N")
	)
	(segment
		(start 223.139 -285.390082)
		(end 222.891604 -285.637478)
		(width 0.174752)
		(layer "F.Cu")
		(net "PE_RX4_DR2_N")
	)
	(segment
		(start 222.13316 -285.637478)
		(end 221.727014 -285.231332)
		(width 0.174752)
		(layer "F.Cu")
		(net "PE_RX4_DR2_N")
	)
	(segment
		(start 222.891604 -285.637478)
		(end 222.13316 -285.637478)
		(width 0.174752)
		(layer "F.Cu")
		(net "PE_RX4_DR2_N")
	)
	(via
		(at 221.727014 -285.231332)
		(size 0.508)
		(drill 0.254)
		(layers "F.Cu" "B.Cu")
		(net "PE_RX4_DR2_N")
	)
	(via
		(at 5.08 -329.935332)
		(size 0.508)
		(drill 0.254)
		(layers "F.Cu" "B.Cu")
		(net "PE_RX4_DR2_N")
	)
	(segment
		(start 1.868932 -329.94219)
		(end 3.658108 -329.94219)
		(width 0.174752)
		(layer "B.Cu")
		(net "PE_RX4_DR2_N")
	)
	(segment
		(start 3.905504 -330.189586)
		(end 4.825746 -330.189586)
		(width 0.174752)
		(layer "B.Cu")
		(net "PE_RX4_DR2_N")
	)
	(segment
		(start 4.825746 -330.189586)
		(end 5.08 -329.935332)
		(width 0.174752)
		(layer "B.Cu")
		(net "PE_RX4_DR2_N")
	)
	(segment
		(start 3.658108 -329.94219)
		(end 3.905504 -330.189586)
		(width 0.174752)
		(layer "B.Cu")
		(net "PE_RX4_DR2_N")
	)
	(segment
		(start 22.943312 -303.953418)
		(end 21.168868 -304.2666)
		(width 0.1651)
		(layer "In2.Cu")
		(net "PE_RX4_DR2_N")
	)
	(segment
		(start 13.43787 -324.53707)
		(end 11.74242 -326.958198)
		(width 0.1651)
		(layer "In2.Cu")
		(net "PE_RX4_DR2_N")
	)
	(segment
		(start 221.727014 -285.231332)
		(end 221.346014 -285.612332)
		(width 0.1651)
		(layer "In2.Cu")
		(net "PE_RX4_DR2_N")
	)
	(segment
		(start 221.346014 -285.612332)
		(end 220.429836 -285.612332)
		(width 0.1651)
		(layer "In2.Cu")
		(net "PE_RX4_DR2_N")
	)
	(segment
		(start 11.74242 -326.958198)
		(end 7.341362 -330.03998)
		(width 0.1651)
		(layer "In2.Cu")
		(net "PE_RX4_DR2_N")
	)
	(segment
		(start 6.635242 -330.16444)
		(end 5.309108 -330.16444)
		(width 0.1651)
		(layer "In2.Cu")
		(net "PE_RX4_DR2_N")
	)
	(segment
		(start 38.864794 -306.761134)
		(end 22.943312 -303.953418)
		(width 0.1651)
		(layer "In2.Cu")
		(net "PE_RX4_DR2_N")
	)
	(segment
		(start 16.26997 -308.477666)
		(end 13.43787 -324.53707)
		(width 0.1651)
		(layer "In2.Cu")
		(net "PE_RX4_DR2_N")
	)
	(segment
		(start 46.24451 -305.459892)
		(end 38.864794 -306.761134)
		(width 0.1651)
		(layer "In2.Cu")
		(net "PE_RX4_DR2_N")
	)
	(segment
		(start 157.658562 -274.544028)
		(end 67.771772 -290.38677)
		(width 0.1651)
		(layer "In2.Cu")
		(net "PE_RX4_DR2_N")
	)
	(segment
		(start 5.309108 -330.16444)
		(end 5.08 -329.935332)
		(width 0.1651)
		(layer "In2.Cu")
		(net "PE_RX4_DR2_N")
	)
	(segment
		(start 67.771772 -290.38677)
		(end 46.24451 -305.459892)
		(width 0.1651)
		(layer "In2.Cu")
		(net "PE_RX4_DR2_N")
	)
	(segment
		(start 220.429836 -285.612332)
		(end 157.658562 -274.544028)
		(width 0.1651)
		(layer "In2.Cu")
		(net "PE_RX4_DR2_N")
	)
	(segment
		(start 21.168868 -304.2666)
		(end 17.342612 -306.945284)
		(width 0.1651)
		(layer "In2.Cu")
		(net "PE_RX4_DR2_N")
	)
	(segment
		(start 17.342612 -306.945284)
		(end 16.26997 -308.477666)
		(width 0.1651)
		(layer "In2.Cu")
		(net "PE_RX4_DR2_N")
	)
	(segment
		(start 7.341362 -330.03998)
		(end 6.635242 -330.16444)
		(width 0.1651)
		(layer "In2.Cu")
		(net "PE_RX4_DR2_N")
	)
	(segment
		(start 24.866854 -14.082522)
		(end 24.267922 -14.082522)
		(width 0.174752)
		(layer "F.Cu")
		(net "PE_RX4_DR14_P")
	)
	(segment
		(start 23.99538 -13.80998)
		(end 22.800056 -13.80998)
		(width 0.174752)
		(layer "F.Cu")
		(net "PE_RX4_DR14_P")
	)
	(segment
		(start 24.267922 -14.082522)
		(end 23.99538 -13.80998)
		(width 0.174752)
		(layer "F.Cu")
		(net "PE_RX4_DR14_P")
	)
	(segment
		(start 25.273 -13.676376)
		(end 24.866854 -14.082522)
		(width 0.174752)
		(layer "F.Cu")
		(net "PE_RX4_DR14_P")
	)
	(via
		(at 25.273 -13.676376)
		(size 0.508)
		(drill 0.254)
		(layers "F.Cu" "B.Cu")
		(net "PE_RX4_DR14_P")
	)
	(via
		(at 5.08 -164.74821)
		(size 0.508)
		(drill 0.254)
		(layers "F.Cu" "B.Cu")
		(net "PE_RX4_DR14_P")
	)
	(segment
		(start 4.826254 -164.494464)
		(end 5.08 -164.74821)
		(width 0.174752)
		(layer "B.Cu")
		(net "PE_RX4_DR14_P")
	)
	(segment
		(start 3.657854 -164.742114)
		(end 3.905504 -164.494464)
		(width 0.174752)
		(layer "B.Cu")
		(net "PE_RX4_DR14_P")
	)
	(segment
		(start 3.905504 -164.494464)
		(end 4.826254 -164.494464)
		(width 0.174752)
		(layer "B.Cu")
		(net "PE_RX4_DR14_P")
	)
	(segment
		(start 1.868932 -164.742114)
		(end 3.657854 -164.742114)
		(width 0.174752)
		(layer "B.Cu")
		(net "PE_RX4_DR14_P")
	)
	(segment
		(start 26.745438 -14.057376)
		(end 28.125928 -14.300708)
		(width 0.1651)
		(layer "In2.Cu")
		(net "PE_RX4_DR14_P")
	)
	(segment
		(start 16.128746 -140.756386)
		(end 12.68603 -160.279588)
		(width 0.1651)
		(layer "In2.Cu")
		(net "PE_RX4_DR14_P")
	)
	(segment
		(start 29.105606 -67.409822)
		(end 18.830036 -82.08518)
		(width 0.1651)
		(layer "In2.Cu")
		(net "PE_RX4_DR14_P")
	)
	(segment
		(start 5.308346 -164.519864)
		(end 5.08 -164.74821)
		(width 0.1651)
		(layer "In2.Cu")
		(net "PE_RX4_DR14_P")
	)
	(segment
		(start 18.830036 -82.08518)
		(end 12.3063 -119.08028)
		(width 0.1651)
		(layer "In2.Cu")
		(net "PE_RX4_DR14_P")
	)
	(segment
		(start 8.917178 -164.20719)
		(end 7.143242 -164.519864)
		(width 0.1651)
		(layer "In2.Cu")
		(net "PE_RX4_DR14_P")
	)
	(segment
		(start 7.143242 -164.519864)
		(end 5.308346 -164.519864)
		(width 0.1651)
		(layer "In2.Cu")
		(net "PE_RX4_DR14_P")
	)
	(segment
		(start 25.654 -14.057376)
		(end 26.745438 -14.057376)
		(width 0.1651)
		(layer "In2.Cu")
		(net "PE_RX4_DR14_P")
	)
	(segment
		(start 25.273 -13.676376)
		(end 25.654 -14.057376)
		(width 0.1651)
		(layer "In2.Cu")
		(net "PE_RX4_DR14_P")
	)
	(segment
		(start 10.916412 -162.807396)
		(end 8.917178 -164.20719)
		(width 0.1651)
		(layer "In2.Cu")
		(net "PE_RX4_DR14_P")
	)
	(segment
		(start 34.196274 -21.654262)
		(end 35.684968 -30.09646)
		(width 0.1651)
		(layer "In2.Cu")
		(net "PE_RX4_DR14_P")
	)
	(segment
		(start 12.3063 -119.08028)
		(end 16.128746 -140.756386)
		(width 0.1651)
		(layer "In2.Cu")
		(net "PE_RX4_DR14_P")
	)
	(segment
		(start 29.933646 -15.56639)
		(end 34.196274 -21.654262)
		(width 0.1651)
		(layer "In2.Cu")
		(net "PE_RX4_DR14_P")
	)
	(segment
		(start 12.68603 -160.279588)
		(end 10.916412 -162.807396)
		(width 0.1651)
		(layer "In2.Cu")
		(net "PE_RX4_DR14_P")
	)
	(segment
		(start 35.684968 -30.09646)
		(end 29.105606 -67.409822)
		(width 0.1651)
		(layer "In2.Cu")
		(net "PE_RX4_DR14_P")
	)
	(segment
		(start 28.125928 -14.300708)
		(end 29.933646 -15.56639)
		(width 0.1651)
		(layer "In2.Cu")
		(net "PE_RX4_DR14_P")
	)
	(segment
		(start 23.985982 -14.609826)
		(end 22.800056 -14.609826)
		(width 0.174752)
		(layer "F.Cu")
		(net "PE_RX4_DR14_N")
	)
	(segment
		(start 24.8666 -14.387576)
		(end 24.208232 -14.387576)
		(width 0.174752)
		(layer "F.Cu")
		(net "PE_RX4_DR14_N")
	)
	(segment
		(start 24.208232 -14.387576)
		(end 23.985982 -14.609826)
		(width 0.174752)
		(layer "F.Cu")
		(net "PE_RX4_DR14_N")
	)
	(segment
		(start 25.273 -14.793976)
		(end 24.8666 -14.387576)
		(width 0.174752)
		(layer "F.Cu")
		(net "PE_RX4_DR14_N")
	)
	(via
		(at 25.273 -14.793976)
		(size 0.508)
		(drill 0.254)
		(layers "F.Cu" "B.Cu")
		(net "PE_RX4_DR14_N")
	)
	(via
		(at 5.08 -163.93541)
		(size 0.508)
		(drill 0.254)
		(layers "F.Cu" "B.Cu")
		(net "PE_RX4_DR14_N")
	)
	(segment
		(start 1.868932 -163.942014)
		(end 3.658108 -163.942014)
		(width 0.174752)
		(layer "B.Cu")
		(net "PE_RX4_DR14_N")
	)
	(segment
		(start 3.658108 -163.942014)
		(end 3.905504 -164.18941)
		(width 0.174752)
		(layer "B.Cu")
		(net "PE_RX4_DR14_N")
	)
	(segment
		(start 3.905504 -164.18941)
		(end 4.826 -164.18941)
		(width 0.174752)
		(layer "B.Cu")
		(net "PE_RX4_DR14_N")
	)
	(segment
		(start 4.826 -164.18941)
		(end 5.08 -163.93541)
		(width 0.174752)
		(layer "B.Cu")
		(net "PE_RX4_DR14_N")
	)
	(segment
		(start 28.769056 -67.270376)
		(end 18.493232 -81.945988)
		(width 0.1651)
		(layer "In2.Cu")
		(net "PE_RX4_DR14_N")
	)
	(segment
		(start 25.654 -14.412976)
		(end 26.714196 -14.412976)
		(width 0.1651)
		(layer "In2.Cu")
		(net "PE_RX4_DR14_N")
	)
	(segment
		(start 31.259526 -18.420842)
		(end 31.572962 -18.868644)
		(width 0.1651)
		(layer "In2.Cu")
		(net "PE_RX4_DR14_N")
	)
	(segment
		(start 32.423354 -20.083272)
		(end 32.695134 -20.13077)
		(width 0.1651)
		(layer "In2.Cu")
		(net "PE_RX4_DR14_N")
	)
	(segment
		(start 12.34948 -160.140142)
		(end 10.660888 -162.551872)
		(width 0.1651)
		(layer "In2.Cu")
		(net "PE_RX4_DR14_N")
	)
	(segment
		(start 30.72257 -17.654016)
		(end 30.99435 -17.701514)
		(width 0.1651)
		(layer "In2.Cu")
		(net "PE_RX4_DR14_N")
	)
	(segment
		(start 34.444178 -25.109678)
		(end 35.32378 -30.096206)
		(width 0.1651)
		(layer "In2.Cu")
		(net "PE_RX4_DR14_N")
	)
	(segment
		(start 7.112 -164.164264)
		(end 5.308854 -164.164264)
		(width 0.1651)
		(layer "In2.Cu")
		(net "PE_RX4_DR14_N")
	)
	(segment
		(start 31.572962 -18.868644)
		(end 31.844742 -18.916142)
		(width 0.1651)
		(layer "In2.Cu")
		(net "PE_RX4_DR14_N")
	)
	(segment
		(start 29.678122 -15.821914)
		(end 30.457394 -16.934688)
		(width 0.1651)
		(layer "In2.Cu")
		(net "PE_RX4_DR14_N")
	)
	(segment
		(start 8.777732 -163.87064)
		(end 7.112 -164.164264)
		(width 0.1651)
		(layer "In2.Cu")
		(net "PE_RX4_DR14_N")
	)
	(segment
		(start 10.660888 -162.551872)
		(end 8.777732 -163.87064)
		(width 0.1651)
		(layer "In2.Cu")
		(net "PE_RX4_DR14_N")
	)
	(segment
		(start 29.229812 -15.50797)
		(end 29.678122 -15.821914)
		(width 0.1651)
		(layer "In2.Cu")
		(net "PE_RX4_DR14_N")
	)
	(segment
		(start 34.276792 -24.158702)
		(end 34.10585 -24.40178)
		(width 0.1651)
		(layer "In2.Cu")
		(net "PE_RX4_DR14_N")
	)
	(segment
		(start 32.96031 -20.850098)
		(end 33.273746 -21.2979)
		(width 0.1651)
		(layer "In2.Cu")
		(net "PE_RX4_DR14_N")
	)
	(segment
		(start 35.32378 -30.096206)
		(end 28.769056 -67.270376)
		(width 0.1651)
		(layer "In2.Cu")
		(net "PE_RX4_DR14_N")
	)
	(segment
		(start 30.457394 -16.934688)
		(end 30.409134 -17.206214)
		(width 0.1651)
		(layer "In2.Cu")
		(net "PE_RX4_DR14_N")
	)
	(segment
		(start 33.859724 -21.793708)
		(end 34.014156 -22.669754)
		(width 0.1651)
		(layer "In2.Cu")
		(net "PE_RX4_DR14_N")
	)
	(segment
		(start 33.00857 -20.578572)
		(end 32.96031 -20.850098)
		(width 0.1651)
		(layer "In2.Cu")
		(net "PE_RX4_DR14_N")
	)
	(segment
		(start 33.273746 -21.2979)
		(end 33.545526 -21.345398)
		(width 0.1651)
		(layer "In2.Cu")
		(net "PE_RX4_DR14_N")
	)
	(segment
		(start 34.2011 -24.940006)
		(end 34.444178 -25.109678)
		(width 0.1651)
		(layer "In2.Cu")
		(net "PE_RX4_DR14_N")
	)
	(segment
		(start 33.545526 -21.345398)
		(end 33.859724 -21.793708)
		(width 0.1651)
		(layer "In2.Cu")
		(net "PE_RX4_DR14_N")
	)
	(segment
		(start 34.014156 -22.669754)
		(end 33.843214 -22.912832)
		(width 0.1651)
		(layer "In2.Cu")
		(net "PE_RX4_DR14_N")
	)
	(segment
		(start 28.983432 -15.551912)
		(end 29.229812 -15.50797)
		(width 0.1651)
		(layer "In2.Cu")
		(net "PE_RX4_DR14_N")
	)
	(segment
		(start 11.945112 -119.08028)
		(end 15.767558 -140.756386)
		(width 0.1651)
		(layer "In2.Cu")
		(net "PE_RX4_DR14_N")
	)
	(segment
		(start 31.844742 -18.916142)
		(end 32.158178 -19.363944)
		(width 0.1651)
		(layer "In2.Cu")
		(net "PE_RX4_DR14_N")
	)
	(segment
		(start 28.492958 -14.992096)
		(end 28.535884 -15.238222)
		(width 0.1651)
		(layer "In2.Cu")
		(net "PE_RX4_DR14_N")
	)
	(segment
		(start 15.767558 -140.756386)
		(end 12.34948 -160.140142)
		(width 0.1651)
		(layer "In2.Cu")
		(net "PE_RX4_DR14_N")
	)
	(segment
		(start 31.307786 -18.149316)
		(end 31.259526 -18.420842)
		(width 0.1651)
		(layer "In2.Cu")
		(net "PE_RX4_DR14_N")
	)
	(segment
		(start 5.308854 -164.164264)
		(end 5.08 -163.93541)
		(width 0.1651)
		(layer "In2.Cu")
		(net "PE_RX4_DR14_N")
	)
	(segment
		(start 30.99435 -17.701514)
		(end 31.307786 -18.149316)
		(width 0.1651)
		(layer "In2.Cu")
		(net "PE_RX4_DR14_N")
	)
	(segment
		(start 32.109918 -19.63547)
		(end 32.423354 -20.083272)
		(width 0.1651)
		(layer "In2.Cu")
		(net "PE_RX4_DR14_N")
	)
	(segment
		(start 33.843214 -22.912832)
		(end 33.938464 -23.451058)
		(width 0.1651)
		(layer "In2.Cu")
		(net "PE_RX4_DR14_N")
	)
	(segment
		(start 34.181542 -23.62073)
		(end 34.276792 -24.158702)
		(width 0.1651)
		(layer "In2.Cu")
		(net "PE_RX4_DR14_N")
	)
	(segment
		(start 32.695134 -20.13077)
		(end 33.00857 -20.578572)
		(width 0.1651)
		(layer "In2.Cu")
		(net "PE_RX4_DR14_N")
	)
	(segment
		(start 26.714196 -14.412976)
		(end 27.986482 -14.637258)
		(width 0.1651)
		(layer "In2.Cu")
		(net "PE_RX4_DR14_N")
	)
	(segment
		(start 25.273 -14.793976)
		(end 25.654 -14.412976)
		(width 0.1651)
		(layer "In2.Cu")
		(net "PE_RX4_DR14_N")
	)
	(segment
		(start 34.10585 -24.40178)
		(end 34.2011 -24.940006)
		(width 0.1651)
		(layer "In2.Cu")
		(net "PE_RX4_DR14_N")
	)
	(segment
		(start 32.158178 -19.363944)
		(end 32.109918 -19.63547)
		(width 0.1651)
		(layer "In2.Cu")
		(net "PE_RX4_DR14_N")
	)
	(segment
		(start 33.938464 -23.451058)
		(end 34.181542 -23.62073)
		(width 0.1651)
		(layer "In2.Cu")
		(net "PE_RX4_DR14_N")
	)
	(segment
		(start 30.409134 -17.206214)
		(end 30.72257 -17.654016)
		(width 0.1651)
		(layer "In2.Cu")
		(net "PE_RX4_DR14_N")
	)
	(segment
		(start 27.986482 -14.637258)
		(end 28.492958 -14.992096)
		(width 0.1651)
		(layer "In2.Cu")
		(net "PE_RX4_DR14_N")
	)
	(segment
		(start 28.535884 -15.238222)
		(end 28.983432 -15.551912)
		(width 0.1651)
		(layer "In2.Cu")
		(net "PE_RX4_DR14_N")
	)
	(segment
		(start 18.493232 -81.945988)
		(end 11.945112 -119.08028)
		(width 0.1651)
		(layer "In2.Cu")
		(net "PE_RX4_DR14_N")
	)
	(segment
		(start 22.800056 -116.810028)
		(end 23.882604 -116.810028)
		(width 0.174752)
		(layer "F.Cu")
		(net "PE_RX4_DR13_P")
	)
	(segment
		(start 24.8666 -117.057424)
		(end 25.273 -116.651024)
		(width 0.174752)
		(layer "F.Cu")
		(net "PE_RX4_DR13_P")
	)
	(segment
		(start 24.26716 -117.057424)
		(end 24.8666 -117.057424)
		(width 0.174752)
		(layer "F.Cu")
		(net "PE_RX4_DR13_P")
	)
	(segment
		(start 23.882604 -116.810028)
		(end 24.26716 -117.057424)
		(width 0.174752)
		(layer "F.Cu")
		(net "PE_RX4_DR13_P")
	)
	(via
		(at 5.08 -177.548286)
		(size 0.508)
		(drill 0.254)
		(layers "F.Cu" "B.Cu")
		(net "PE_RX4_DR13_P")
	)
	(via
		(at 25.273 -116.651024)
		(size 0.508)
		(drill 0.254)
		(layers "F.Cu" "B.Cu")
		(net "PE_RX4_DR13_P")
	)
	(segment
		(start 3.657854 -177.54219)
		(end 3.905504 -177.29454)
		(width 0.174752)
		(layer "B.Cu")
		(net "PE_RX4_DR13_P")
	)
	(segment
		(start 4.826254 -177.29454)
		(end 5.08 -177.548286)
		(width 0.174752)
		(layer "B.Cu")
		(net "PE_RX4_DR13_P")
	)
	(segment
		(start 3.905504 -177.29454)
		(end 4.826254 -177.29454)
		(width 0.174752)
		(layer "B.Cu")
		(net "PE_RX4_DR13_P")
	)
	(segment
		(start 1.868932 -177.54219)
		(end 3.657854 -177.54219)
		(width 0.174752)
		(layer "B.Cu")
		(net "PE_RX4_DR13_P")
	)
	(segment
		(start 27.642058 -117.215666)
		(end 30.294072 -119.071898)
		(width 0.1651)
		(layer "In2.Cu")
		(net "PE_RX4_DR13_P")
	)
	(segment
		(start 29.27985 -150.536148)
		(end 29.250386 -150.704804)
		(width 0.1651)
		(layer "In2.Cu")
		(net "PE_RX4_DR13_P")
	)
	(segment
		(start 19.636486 -175.117252)
		(end 7.143242 -177.31994)
		(width 0.1651)
		(layer "In2.Cu")
		(net "PE_RX4_DR13_P")
	)
	(segment
		(start 32.175196 -146.401536)
		(end 29.27985 -150.536148)
		(width 0.1651)
		(layer "In2.Cu")
		(net "PE_RX4_DR13_P")
	)
	(segment
		(start 29.250386 -150.704804)
		(end 25.81021 -170.210734)
		(width 0.1651)
		(layer "In2.Cu")
		(net "PE_RX4_DR13_P")
	)
	(segment
		(start 25.009348 -171.35475)
		(end 19.636486 -175.117252)
		(width 0.1651)
		(layer "In2.Cu")
		(net "PE_RX4_DR13_P")
	)
	(segment
		(start 5.308346 -177.31994)
		(end 5.08 -177.548286)
		(width 0.1651)
		(layer "In2.Cu")
		(net "PE_RX4_DR13_P")
	)
	(segment
		(start 35.103054 -129.796286)
		(end 32.175196 -146.401536)
		(width 0.1651)
		(layer "In2.Cu")
		(net "PE_RX4_DR13_P")
	)
	(segment
		(start 25.273 -116.651024)
		(end 25.654 -117.032024)
		(width 0.1651)
		(layer "In2.Cu")
		(net "PE_RX4_DR13_P")
	)
	(segment
		(start 25.81021 -170.210734)
		(end 25.009348 -171.35475)
		(width 0.1651)
		(layer "In2.Cu")
		(net "PE_RX4_DR13_P")
	)
	(segment
		(start 30.294072 -119.071898)
		(end 34.193988 -124.641102)
		(width 0.1651)
		(layer "In2.Cu")
		(net "PE_RX4_DR13_P")
	)
	(segment
		(start 34.193988 -124.641102)
		(end 35.103054 -129.796286)
		(width 0.1651)
		(layer "In2.Cu")
		(net "PE_RX4_DR13_P")
	)
	(segment
		(start 7.143242 -177.31994)
		(end 5.308346 -177.31994)
		(width 0.1651)
		(layer "In2.Cu")
		(net "PE_RX4_DR13_P")
	)
	(segment
		(start 25.654 -117.032024)
		(end 26.60142 -117.032024)
		(width 0.1651)
		(layer "In2.Cu")
		(net "PE_RX4_DR13_P")
	)
	(segment
		(start 26.60142 -117.032024)
		(end 27.642058 -117.215666)
		(width 0.1651)
		(layer "In2.Cu")
		(net "PE_RX4_DR13_P")
	)
	(segment
		(start 24.255222 -117.362478)
		(end 24.866854 -117.362478)
		(width 0.174752)
		(layer "F.Cu")
		(net "PE_RX4_DR13_N")
	)
	(segment
		(start 24.866854 -117.362478)
		(end 25.273 -117.768624)
		(width 0.174752)
		(layer "F.Cu")
		(net "PE_RX4_DR13_N")
	)
	(segment
		(start 24.007826 -117.609874)
		(end 24.255222 -117.362478)
		(width 0.174752)
		(layer "F.Cu")
		(net "PE_RX4_DR13_N")
	)
	(segment
		(start 22.800056 -117.609874)
		(end 24.007826 -117.609874)
		(width 0.174752)
		(layer "F.Cu")
		(net "PE_RX4_DR13_N")
	)
	(via
		(at 5.08 -176.735486)
		(size 0.508)
		(drill 0.254)
		(layers "F.Cu" "B.Cu")
		(net "PE_RX4_DR13_N")
	)
	(via
		(at 25.273 -117.768624)
		(size 0.508)
		(drill 0.254)
		(layers "F.Cu" "B.Cu")
		(net "PE_RX4_DR13_N")
	)
	(segment
		(start 1.868932 -176.74209)
		(end 3.658108 -176.74209)
		(width 0.174752)
		(layer "B.Cu")
		(net "PE_RX4_DR13_N")
	)
	(segment
		(start 3.905504 -176.989486)
		(end 4.826 -176.989486)
		(width 0.174752)
		(layer "B.Cu")
		(net "PE_RX4_DR13_N")
	)
	(segment
		(start 3.658108 -176.74209)
		(end 3.905504 -176.989486)
		(width 0.174752)
		(layer "B.Cu")
		(net "PE_RX4_DR13_N")
	)
	(segment
		(start 4.826 -176.989486)
		(end 5.08 -176.735486)
		(width 0.174752)
		(layer "B.Cu")
		(net "PE_RX4_DR13_N")
	)
	(segment
		(start 10.931144 -176.099978)
		(end 10.443464 -176.18583)
		(width 0.1651)
		(layer "In2.Cu")
		(net "PE_RX4_DR13_N")
	)
	(segment
		(start 32.28975 -122.541792)
		(end 32.243522 -122.803666)
		(width 0.1651)
		(layer "In2.Cu")
		(net "PE_RX4_DR13_N")
	)
	(segment
		(start 32.527748 -123.209304)
		(end 32.789368 -123.255532)
		(width 0.1651)
		(layer "In2.Cu")
		(net "PE_RX4_DR13_N")
	)
	(segment
		(start 31.459678 -121.684288)
		(end 31.74365 -122.09018)
		(width 0.1651)
		(layer "In2.Cu")
		(net "PE_RX4_DR13_N")
	)
	(segment
		(start 30.038548 -119.327422)
		(end 31.505652 -121.422668)
		(width 0.1651)
		(layer "In2.Cu")
		(net "PE_RX4_DR13_N")
	)
	(segment
		(start 25.273 -117.768624)
		(end 25.654 -117.387624)
		(width 0.1651)
		(layer "In2.Cu")
		(net "PE_RX4_DR13_N")
	)
	(segment
		(start 28.965144 -118.805452)
		(end 29.371036 -119.089678)
		(width 0.1651)
		(layer "In2.Cu")
		(net "PE_RX4_DR13_N")
	)
	(segment
		(start 32.243522 -122.803666)
		(end 32.527748 -123.209304)
		(width 0.1651)
		(layer "In2.Cu")
		(net "PE_RX4_DR13_N")
	)
	(segment
		(start 7.75208 -176.660556)
		(end 7.599426 -176.878234)
		(width 0.1651)
		(layer "In2.Cu")
		(net "PE_RX4_DR13_N")
	)
	(segment
		(start 31.74365 -122.09018)
		(end 32.005524 -122.136154)
		(width 0.1651)
		(layer "In2.Cu")
		(net "PE_RX4_DR13_N")
	)
	(segment
		(start 7.599426 -176.878234)
		(end 7.111746 -176.96434)
		(width 0.1651)
		(layer "In2.Cu")
		(net "PE_RX4_DR13_N")
	)
	(segment
		(start 10.443464 -176.18583)
		(end 10.291064 -176.403762)
		(width 0.1651)
		(layer "In2.Cu")
		(net "PE_RX4_DR13_N")
	)
	(segment
		(start 32.005524 -122.136154)
		(end 32.28975 -122.541792)
		(width 0.1651)
		(layer "In2.Cu")
		(net "PE_RX4_DR13_N")
	)
	(segment
		(start 33.857438 -124.780548)
		(end 34.741866 -129.796286)
		(width 0.1651)
		(layer "In2.Cu")
		(net "PE_RX4_DR13_N")
	)
	(segment
		(start 32.789368 -123.255532)
		(end 33.073594 -123.66117)
		(width 0.1651)
		(layer "In2.Cu")
		(net "PE_RX4_DR13_N")
	)
	(segment
		(start 33.311592 -124.328682)
		(end 33.573212 -124.37491)
		(width 0.1651)
		(layer "In2.Cu")
		(net "PE_RX4_DR13_N")
	)
	(segment
		(start 11.149076 -176.252378)
		(end 10.931144 -176.099978)
		(width 0.1651)
		(layer "In2.Cu")
		(net "PE_RX4_DR13_N")
	)
	(segment
		(start 26.570178 -117.387624)
		(end 27.502612 -117.552216)
		(width 0.1651)
		(layer "In2.Cu")
		(net "PE_RX4_DR13_N")
	)
	(segment
		(start 33.073594 -123.66117)
		(end 33.027366 -123.923044)
		(width 0.1651)
		(layer "In2.Cu")
		(net "PE_RX4_DR13_N")
	)
	(segment
		(start 31.838646 -146.261836)
		(end 28.9433 -150.396702)
		(width 0.1651)
		(layer "In2.Cu")
		(net "PE_RX4_DR13_N")
	)
	(segment
		(start 28.9433 -150.396702)
		(end 25.47366 -170.071288)
		(width 0.1651)
		(layer "In2.Cu")
		(net "PE_RX4_DR13_N")
	)
	(segment
		(start 29.63291 -119.04345)
		(end 30.038548 -119.327422)
		(width 0.1651)
		(layer "In2.Cu")
		(net "PE_RX4_DR13_N")
	)
	(segment
		(start 33.027366 -123.923044)
		(end 33.311592 -124.328682)
		(width 0.1651)
		(layer "In2.Cu")
		(net "PE_RX4_DR13_N")
	)
	(segment
		(start 10.291064 -176.403762)
		(end 9.80313 -176.489614)
		(width 0.1651)
		(layer "In2.Cu")
		(net "PE_RX4_DR13_N")
	)
	(segment
		(start 9.585452 -176.337214)
		(end 9.097772 -176.42332)
		(width 0.1651)
		(layer "In2.Cu")
		(net "PE_RX4_DR13_N")
	)
	(segment
		(start 28.91917 -118.543832)
		(end 28.965144 -118.805452)
		(width 0.1651)
		(layer "In2.Cu")
		(net "PE_RX4_DR13_N")
	)
	(segment
		(start 8.23976 -176.57445)
		(end 7.75208 -176.660556)
		(width 0.1651)
		(layer "In2.Cu")
		(net "PE_RX4_DR13_N")
	)
	(segment
		(start 19.49704 -174.780702)
		(end 11.149076 -176.252378)
		(width 0.1651)
		(layer "In2.Cu")
		(net "PE_RX4_DR13_N")
	)
	(segment
		(start 9.097772 -176.42332)
		(end 8.945372 -176.640998)
		(width 0.1651)
		(layer "In2.Cu")
		(net "PE_RX4_DR13_N")
	)
	(segment
		(start 34.741866 -129.796286)
		(end 31.838646 -146.261836)
		(width 0.1651)
		(layer "In2.Cu")
		(net "PE_RX4_DR13_N")
	)
	(segment
		(start 31.505652 -121.422668)
		(end 31.459678 -121.684288)
		(width 0.1651)
		(layer "In2.Cu")
		(net "PE_RX4_DR13_N")
	)
	(segment
		(start 9.80313 -176.489614)
		(end 9.585452 -176.337214)
		(width 0.1651)
		(layer "In2.Cu")
		(net "PE_RX4_DR13_N")
	)
	(segment
		(start 27.502612 -117.552216)
		(end 28.91917 -118.543832)
		(width 0.1651)
		(layer "In2.Cu")
		(net "PE_RX4_DR13_N")
	)
	(segment
		(start 25.654 -117.387624)
		(end 26.570178 -117.387624)
		(width 0.1651)
		(layer "In2.Cu")
		(net "PE_RX4_DR13_N")
	)
	(segment
		(start 7.111746 -176.96434)
		(end 5.308854 -176.96434)
		(width 0.1651)
		(layer "In2.Cu")
		(net "PE_RX4_DR13_N")
	)
	(segment
		(start 33.573212 -124.37491)
		(end 33.857438 -124.780548)
		(width 0.1651)
		(layer "In2.Cu")
		(net "PE_RX4_DR13_N")
	)
	(segment
		(start 8.945372 -176.640998)
		(end 8.457438 -176.727104)
		(width 0.1651)
		(layer "In2.Cu")
		(net "PE_RX4_DR13_N")
	)
	(segment
		(start 8.457438 -176.727104)
		(end 8.23976 -176.57445)
		(width 0.1651)
		(layer "In2.Cu")
		(net "PE_RX4_DR13_N")
	)
	(segment
		(start 29.371036 -119.089678)
		(end 29.63291 -119.04345)
		(width 0.1651)
		(layer "In2.Cu")
		(net "PE_RX4_DR13_N")
	)
	(segment
		(start 5.308854 -176.96434)
		(end 5.08 -176.735486)
		(width 0.1651)
		(layer "In2.Cu")
		(net "PE_RX4_DR13_N")
	)
	(segment
		(start 24.753824 -171.099226)
		(end 19.49704 -174.780702)
		(width 0.1651)
		(layer "In2.Cu")
		(net "PE_RX4_DR13_N")
	)
	(segment
		(start 25.47366 -170.071288)
		(end 24.753824 -171.099226)
		(width 0.1651)
		(layer "In2.Cu")
		(net "PE_RX4_DR13_N")
	)
	(segment
		(start 24.8666 -220.057472)
		(end 25.273 -219.651072)
		(width 0.174752)
		(layer "F.Cu")
		(net "PE_RX4_DR12_P")
	)
	(segment
		(start 22.800056 -219.810076)
		(end 23.876 -219.810076)
		(width 0.174752)
		(layer "F.Cu")
		(net "PE_RX4_DR12_P")
	)
	(segment
		(start 24.123396 -220.057472)
		(end 24.8666 -220.057472)
		(width 0.174752)
		(layer "F.Cu")
		(net "PE_RX4_DR12_P")
	)
	(segment
		(start 23.876 -219.810076)
		(end 24.123396 -220.057472)
		(width 0.174752)
		(layer "F.Cu")
		(net "PE_RX4_DR12_P")
	)
	(via
		(at 25.273 -219.651072)
		(size 0.508)
		(drill 0.254)
		(layers "F.Cu" "B.Cu")
		(net "PE_RX4_DR12_P")
	)
	(via
		(at 5.08 -223.148144)
		(size 0.508)
		(drill 0.254)
		(layers "F.Cu" "B.Cu")
		(net "PE_RX4_DR12_P")
	)
	(segment
		(start 4.826508 -222.894652)
		(end 5.08 -223.148144)
		(width 0.174752)
		(layer "B.Cu")
		(net "PE_RX4_DR12_P")
	)
	(segment
		(start 3.905504 -222.894652)
		(end 4.826508 -222.894652)
		(width 0.174752)
		(layer "B.Cu")
		(net "PE_RX4_DR12_P")
	)
	(segment
		(start 3.658108 -223.142048)
		(end 3.905504 -222.894652)
		(width 0.174752)
		(layer "B.Cu")
		(net "PE_RX4_DR12_P")
	)
	(segment
		(start 1.868932 -223.142048)
		(end 3.658108 -223.142048)
		(width 0.174752)
		(layer "B.Cu")
		(net "PE_RX4_DR12_P")
	)
	(segment
		(start 15.46987 -215.214454)
		(end 15.383764 -215.702134)
		(width 0.1651)
		(layer "In2.Cu")
		(net "PE_RX4_DR12_P")
	)
	(segment
		(start 15.858236 -213.010496)
		(end 15.640558 -213.16315)
		(width 0.1651)
		(layer "In2.Cu")
		(net "PE_RX4_DR12_P")
	)
	(segment
		(start 41.624504 -207.527144)
		(end 40.64 -206.121)
		(width 0.1651)
		(layer "In2.Cu")
		(net "PE_RX4_DR12_P")
	)
	(segment
		(start 26.29408 -220.091)
		(end 26.961084 -219.423996)
		(width 0.1651)
		(layer "In2.Cu")
		(net "PE_RX4_DR12_P")
	)
	(segment
		(start 15.146528 -217.047826)
		(end 14.928596 -217.200226)
		(width 0.1651)
		(layer "In2.Cu")
		(net "PE_RX4_DR12_P")
	)
	(segment
		(start 35.795204 -203.830428)
		(end 35.307524 -203.744322)
		(width 0.1651)
		(layer "In2.Cu")
		(net "PE_RX4_DR12_P")
	)
	(segment
		(start 40.64 -206.121)
		(end 37.898324 -204.201268)
		(width 0.1651)
		(layer "In2.Cu")
		(net "PE_RX4_DR12_P")
	)
	(segment
		(start 13.085064 -220.560392)
		(end 10.590276 -222.30715)
		(width 0.1651)
		(layer "In2.Cu")
		(net "PE_RX4_DR12_P")
	)
	(segment
		(start 15.07998 -216.342214)
		(end 15.23238 -216.560146)
		(width 0.1651)
		(layer "In2.Cu")
		(net "PE_RX4_DR12_P")
	)
	(segment
		(start 15.317216 -214.996522)
		(end 15.46987 -215.214454)
		(width 0.1651)
		(layer "In2.Cu")
		(net "PE_RX4_DR12_P")
	)
	(segment
		(start 15.791688 -212.305138)
		(end 15.944342 -212.522816)
		(width 0.1651)
		(layer "In2.Cu")
		(net "PE_RX4_DR12_P")
	)
	(segment
		(start 33.10382 -203.355702)
		(end 22.966426 -201.56805)
		(width 0.1651)
		(layer "In2.Cu")
		(net "PE_RX4_DR12_P")
	)
	(segment
		(start 25.273 -219.651072)
		(end 25.712928 -220.091)
		(width 0.1651)
		(layer "In2.Cu")
		(net "PE_RX4_DR12_P")
	)
	(segment
		(start 35.089846 -203.896976)
		(end 34.602166 -203.81087)
		(width 0.1651)
		(layer "In2.Cu")
		(net "PE_RX4_DR12_P")
	)
	(segment
		(start 14.928596 -217.200226)
		(end 14.7574 -218.171268)
		(width 0.1651)
		(layer "In2.Cu")
		(net "PE_RX4_DR12_P")
	)
	(segment
		(start 36.653216 -203.981812)
		(end 36.435538 -204.134212)
		(width 0.1651)
		(layer "In2.Cu")
		(net "PE_RX4_DR12_P")
	)
	(segment
		(start 28.850082 -217.054176)
		(end 30.979618 -215.562434)
		(width 0.1651)
		(layer "In2.Cu")
		(net "PE_RX4_DR12_P")
	)
	(segment
		(start 15.166086 -215.854534)
		(end 15.07998 -216.342214)
		(width 0.1651)
		(layer "In2.Cu")
		(net "PE_RX4_DR12_P")
	)
	(segment
		(start 33.961832 -203.507086)
		(end 33.7439 -203.659486)
		(width 0.1651)
		(layer "In2.Cu")
		(net "PE_RX4_DR12_P")
	)
	(segment
		(start 35.947858 -204.048106)
		(end 35.795204 -203.830428)
		(width 0.1651)
		(layer "In2.Cu")
		(net "PE_RX4_DR12_P")
	)
	(segment
		(start 15.707106 -213.868762)
		(end 15.621 -214.356442)
		(width 0.1651)
		(layer "In2.Cu")
		(net "PE_RX4_DR12_P")
	)
	(segment
		(start 34.449512 -203.593192)
		(end 33.961832 -203.507086)
		(width 0.1651)
		(layer "In2.Cu")
		(net "PE_RX4_DR12_P")
	)
	(segment
		(start 30.979618 -215.562434)
		(end 38.591236 -214.220044)
		(width 0.1651)
		(layer "In2.Cu")
		(net "PE_RX4_DR12_P")
	)
	(segment
		(start 34.602166 -203.81087)
		(end 34.449512 -203.593192)
		(width 0.1651)
		(layer "In2.Cu")
		(net "PE_RX4_DR12_P")
	)
	(segment
		(start 41.90111 -209.096102)
		(end 41.624504 -207.527144)
		(width 0.1651)
		(layer "In2.Cu")
		(net "PE_RX4_DR12_P")
	)
	(segment
		(start 15.23238 -216.560146)
		(end 15.146528 -217.047826)
		(width 0.1651)
		(layer "In2.Cu")
		(net "PE_RX4_DR12_P")
	)
	(segment
		(start 26.961084 -219.423996)
		(end 28.850082 -217.054176)
		(width 0.1651)
		(layer "In2.Cu")
		(net "PE_RX4_DR12_P")
	)
	(segment
		(start 37.898324 -204.201268)
		(end 36.653216 -203.981812)
		(width 0.1651)
		(layer "In2.Cu")
		(net "PE_RX4_DR12_P")
	)
	(segment
		(start 33.25622 -203.573634)
		(end 33.10382 -203.355702)
		(width 0.1651)
		(layer "In2.Cu")
		(net "PE_RX4_DR12_P")
	)
	(segment
		(start 14.7574 -218.171268)
		(end 13.085064 -220.560392)
		(width 0.1651)
		(layer "In2.Cu")
		(net "PE_RX4_DR12_P")
	)
	(segment
		(start 15.621 -214.356442)
		(end 15.403322 -214.508842)
		(width 0.1651)
		(layer "In2.Cu")
		(net "PE_RX4_DR12_P")
	)
	(segment
		(start 19.023076 -202.87615)
		(end 16.926306 -205.870556)
		(width 0.1651)
		(layer "In2.Cu")
		(net "PE_RX4_DR12_P")
	)
	(segment
		(start 7.112 -222.920052)
		(end 5.308092 -222.920052)
		(width 0.1651)
		(layer "In2.Cu")
		(net "PE_RX4_DR12_P")
	)
	(segment
		(start 41.474898 -211.512658)
		(end 41.90111 -209.096102)
		(width 0.1651)
		(layer "In2.Cu")
		(net "PE_RX4_DR12_P")
	)
	(segment
		(start 25.712928 -220.091)
		(end 26.29408 -220.091)
		(width 0.1651)
		(layer "In2.Cu")
		(net "PE_RX4_DR12_P")
	)
	(segment
		(start 10.590276 -222.30715)
		(end 7.112 -222.920052)
		(width 0.1651)
		(layer "In2.Cu")
		(net "PE_RX4_DR12_P")
	)
	(segment
		(start 33.7439 -203.659486)
		(end 33.25622 -203.573634)
		(width 0.1651)
		(layer "In2.Cu")
		(net "PE_RX4_DR12_P")
	)
	(segment
		(start 22.966426 -201.56805)
		(end 20.193 -202.057)
		(width 0.1651)
		(layer "In2.Cu")
		(net "PE_RX4_DR12_P")
	)
	(segment
		(start 15.383764 -215.702134)
		(end 15.166086 -215.854534)
		(width 0.1651)
		(layer "In2.Cu")
		(net "PE_RX4_DR12_P")
	)
	(segment
		(start 15.944342 -212.522816)
		(end 15.858236 -213.010496)
		(width 0.1651)
		(layer "In2.Cu")
		(net "PE_RX4_DR12_P")
	)
	(segment
		(start 15.554452 -213.65083)
		(end 15.707106 -213.868762)
		(width 0.1651)
		(layer "In2.Cu")
		(net "PE_RX4_DR12_P")
	)
	(segment
		(start 36.435538 -204.134212)
		(end 35.947858 -204.048106)
		(width 0.1651)
		(layer "In2.Cu")
		(net "PE_RX4_DR12_P")
	)
	(segment
		(start 5.308092 -222.920052)
		(end 5.08 -223.148144)
		(width 0.1651)
		(layer "In2.Cu")
		(net "PE_RX4_DR12_P")
	)
	(segment
		(start 15.403322 -214.508842)
		(end 15.317216 -214.996522)
		(width 0.1651)
		(layer "In2.Cu")
		(net "PE_RX4_DR12_P")
	)
	(segment
		(start 38.591236 -214.220044)
		(end 40.529256 -212.86343)
		(width 0.1651)
		(layer "In2.Cu")
		(net "PE_RX4_DR12_P")
	)
	(segment
		(start 16.926306 -205.870556)
		(end 15.791688 -212.305138)
		(width 0.1651)
		(layer "In2.Cu")
		(net "PE_RX4_DR12_P")
	)
	(segment
		(start 15.640558 -213.16315)
		(end 15.554452 -213.65083)
		(width 0.1651)
		(layer "In2.Cu")
		(net "PE_RX4_DR12_P")
	)
	(segment
		(start 20.193 -202.057)
		(end 19.023076 -202.87615)
		(width 0.1651)
		(layer "In2.Cu")
		(net "PE_RX4_DR12_P")
	)
	(segment
		(start 35.307524 -203.744322)
		(end 35.089846 -203.896976)
		(width 0.1651)
		(layer "In2.Cu")
		(net "PE_RX4_DR12_P")
	)
	(segment
		(start 40.529256 -212.86343)
		(end 41.474898 -211.512658)
		(width 0.1651)
		(layer "In2.Cu")
		(net "PE_RX4_DR12_P")
	)
	(segment
		(start 22.800056 -220.609922)
		(end 23.882604 -220.609922)
		(width 0.174752)
		(layer "F.Cu")
		(net "PE_RX4_DR12_N")
	)
	(segment
		(start 24.13 -220.362526)
		(end 24.866854 -220.362526)
		(width 0.174752)
		(layer "F.Cu")
		(net "PE_RX4_DR12_N")
	)
	(segment
		(start 24.866854 -220.362526)
		(end 25.273 -220.768672)
		(width 0.174752)
		(layer "F.Cu")
		(net "PE_RX4_DR12_N")
	)
	(segment
		(start 23.882604 -220.609922)
		(end 24.13 -220.362526)
		(width 0.174752)
		(layer "F.Cu")
		(net "PE_RX4_DR12_N")
	)
	(via
		(at 5.08 -222.335344)
		(size 0.508)
		(drill 0.254)
		(layers "F.Cu" "B.Cu")
		(net "PE_RX4_DR12_N")
	)
	(via
		(at 25.273 -220.768672)
		(size 0.508)
		(drill 0.254)
		(layers "F.Cu" "B.Cu")
		(net "PE_RX4_DR12_N")
	)
	(segment
		(start 1.868932 -222.342202)
		(end 3.658108 -222.342202)
		(width 0.174752)
		(layer "B.Cu")
		(net "PE_RX4_DR12_N")
	)
	(segment
		(start 3.658108 -222.342202)
		(end 3.905504 -222.589598)
		(width 0.174752)
		(layer "B.Cu")
		(net "PE_RX4_DR12_N")
	)
	(segment
		(start 3.905504 -222.589598)
		(end 4.825746 -222.589598)
		(width 0.174752)
		(layer "B.Cu")
		(net "PE_RX4_DR12_N")
	)
	(segment
		(start 4.825746 -222.589598)
		(end 5.08 -222.335344)
		(width 0.174752)
		(layer "B.Cu")
		(net "PE_RX4_DR12_N")
	)
	(segment
		(start 38.03777 -203.864718)
		(end 22.966426 -201.206862)
		(width 0.1651)
		(layer "In2.Cu")
		(net "PE_RX4_DR12_N")
	)
	(segment
		(start 41.811448 -211.652104)
		(end 42.262298 -209.096102)
		(width 0.1651)
		(layer "In2.Cu")
		(net "PE_RX4_DR12_N")
	)
	(segment
		(start 41.961054 -207.387698)
		(end 40.895524 -205.865476)
		(width 0.1651)
		(layer "In2.Cu")
		(net "PE_RX4_DR12_N")
	)
	(segment
		(start 40.895524 -205.865476)
		(end 38.03777 -203.864718)
		(width 0.1651)
		(layer "In2.Cu")
		(net "PE_RX4_DR12_N")
	)
	(segment
		(start 12.82954 -220.304868)
		(end 10.45083 -221.9706)
		(width 0.1651)
		(layer "In2.Cu")
		(net "PE_RX4_DR12_N")
	)
	(segment
		(start 27.226768 -219.661232)
		(end 29.096208 -217.31605)
		(width 0.1651)
		(layer "In2.Cu")
		(net "PE_RX4_DR12_N")
	)
	(segment
		(start 29.096208 -217.31605)
		(end 31.119064 -215.898984)
		(width 0.1651)
		(layer "In2.Cu")
		(net "PE_RX4_DR12_N")
	)
	(segment
		(start 14.42085 -218.031822)
		(end 12.82954 -220.304868)
		(width 0.1651)
		(layer "In2.Cu")
		(net "PE_RX4_DR12_N")
	)
	(segment
		(start 16.589756 -205.73111)
		(end 14.42085 -218.031822)
		(width 0.1651)
		(layer "In2.Cu")
		(net "PE_RX4_DR12_N")
	)
	(segment
		(start 31.119064 -215.898984)
		(end 38.730682 -214.556594)
		(width 0.1651)
		(layer "In2.Cu")
		(net "PE_RX4_DR12_N")
	)
	(segment
		(start 5.309108 -222.564452)
		(end 5.08 -222.335344)
		(width 0.1651)
		(layer "In2.Cu")
		(net "PE_RX4_DR12_N")
	)
	(segment
		(start 7.080758 -222.564452)
		(end 5.309108 -222.564452)
		(width 0.1651)
		(layer "In2.Cu")
		(net "PE_RX4_DR12_N")
	)
	(segment
		(start 42.262298 -209.096102)
		(end 41.961054 -207.387698)
		(width 0.1651)
		(layer "In2.Cu")
		(net "PE_RX4_DR12_N")
	)
	(segment
		(start 25.595072 -220.4466)
		(end 26.4414 -220.4466)
		(width 0.1651)
		(layer "In2.Cu")
		(net "PE_RX4_DR12_N")
	)
	(segment
		(start 38.730682 -214.556594)
		(end 40.78478 -213.118954)
		(width 0.1651)
		(layer "In2.Cu")
		(net "PE_RX4_DR12_N")
	)
	(segment
		(start 26.4414 -220.4466)
		(end 27.226768 -219.661232)
		(width 0.1651)
		(layer "In2.Cu")
		(net "PE_RX4_DR12_N")
	)
	(segment
		(start 22.966426 -201.206862)
		(end 20.053554 -201.72045)
		(width 0.1651)
		(layer "In2.Cu")
		(net "PE_RX4_DR12_N")
	)
	(segment
		(start 10.45083 -221.9706)
		(end 7.080758 -222.564452)
		(width 0.1651)
		(layer "In2.Cu")
		(net "PE_RX4_DR12_N")
	)
	(segment
		(start 40.78478 -213.118954)
		(end 41.811448 -211.652104)
		(width 0.1651)
		(layer "In2.Cu")
		(net "PE_RX4_DR12_N")
	)
	(segment
		(start 25.273 -220.768672)
		(end 25.595072 -220.4466)
		(width 0.1651)
		(layer "In2.Cu")
		(net "PE_RX4_DR12_N")
	)
	(segment
		(start 18.767552 -202.620626)
		(end 16.589756 -205.73111)
		(width 0.1651)
		(layer "In2.Cu")
		(net "PE_RX4_DR12_N")
	)
	(segment
		(start 20.053554 -201.72045)
		(end 18.767552 -202.620626)
		(width 0.1651)
		(layer "In2.Cu")
		(net "PE_RX4_DR12_N")
	)
	(segment
		(start 25.273 -322.65112)
		(end 24.876252 -323.047868)
		(width 0.174752)
		(layer "F.Cu")
		(net "PE_RX4_DR11_P")
	)
	(segment
		(start 24.113744 -323.047868)
		(end 23.876 -322.810124)
		(width 0.174752)
		(layer "F.Cu")
		(net "PE_RX4_DR11_P")
	)
	(segment
		(start 24.876252 -323.047868)
		(end 24.113744 -323.047868)
		(width 0.174752)
		(layer "F.Cu")
		(net "PE_RX4_DR11_P")
	)
	(segment
		(start 23.876 -322.810124)
		(end 22.800056 -322.810124)
		(width 0.174752)
		(layer "F.Cu")
		(net "PE_RX4_DR11_P")
	)
	(via
		(at 5.08 -345.948254)
		(size 0.508)
		(drill 0.254)
		(layers "F.Cu" "B.Cu")
		(net "PE_RX4_DR11_P")
	)
	(via
		(at 25.273 -322.65112)
		(size 0.508)
		(drill 0.254)
		(layers "F.Cu" "B.Cu")
		(net "PE_RX4_DR11_P")
	)
	(segment
		(start 4.00558 -345.694508)
		(end 4.826254 -345.694508)
		(width 0.174752)
		(layer "B.Cu")
		(net "PE_RX4_DR11_P")
	)
	(segment
		(start 3.657854 -345.942158)
		(end 4.00558 -345.694508)
		(width 0.174752)
		(layer "B.Cu")
		(net "PE_RX4_DR11_P")
	)
	(segment
		(start 4.826254 -345.694508)
		(end 5.08 -345.948254)
		(width 0.174752)
		(layer "B.Cu")
		(net "PE_RX4_DR11_P")
	)
	(segment
		(start 1.868932 -345.942158)
		(end 3.657854 -345.942158)
		(width 0.174752)
		(layer "B.Cu")
		(net "PE_RX4_DR11_P")
	)
	(segment
		(start 7.8105 -345.85402)
		(end 7.049516 -345.719908)
		(width 0.1651)
		(layer "In2.Cu")
		(net "PE_RX4_DR11_P")
	)
	(segment
		(start 31.773114 -335.696052)
		(end 30.870398 -340.816692)
		(width 0.1651)
		(layer "In2.Cu")
		(net "PE_RX4_DR11_P")
	)
	(segment
		(start 31.50489 -351.385124)
		(end 31.504636 -351.385124)
		(width 0.1651)
		(layer "In2.Cu")
		(net "PE_RX4_DR11_P")
	)
	(segment
		(start 25.273 -322.65112)
		(end 25.631394 -323.009514)
		(width 0.1651)
		(layer "In2.Cu")
		(net "PE_RX4_DR11_P")
	)
	(segment
		(start 28.190444 -323.654674)
		(end 28.830524 -324.102476)
		(width 0.1651)
		(layer "In2.Cu")
		(net "PE_RX4_DR11_P")
	)
	(segment
		(start 30.870398 -340.816692)
		(end 32.119316 -347.900752)
		(width 0.1651)
		(layer "In2.Cu")
		(net "PE_RX4_DR11_P")
	)
	(segment
		(start 29.426154 -324.953376)
		(end 29.98597 -325.752968)
		(width 0.1651)
		(layer "In2.Cu")
		(net "PE_RX4_DR11_P")
	)
	(segment
		(start 16.558768 -358.793288)
		(end 15.404592 -357.145082)
		(width 0.1651)
		(layer "In2.Cu")
		(net "PE_RX4_DR11_P")
	)
	(segment
		(start 27.537156 -323.19722)
		(end 28.190444 -323.654674)
		(width 0.1651)
		(layer "In2.Cu")
		(net "PE_RX4_DR11_P")
	)
	(segment
		(start 26.473404 -323.009514)
		(end 27.537156 -323.19722)
		(width 0.1651)
		(layer "In2.Cu")
		(net "PE_RX4_DR11_P")
	)
	(segment
		(start 30.031182 -325.817484)
		(end 31.773114 -335.696052)
		(width 0.1651)
		(layer "In2.Cu")
		(net "PE_RX4_DR11_P")
	)
	(segment
		(start 15.404592 -357.145082)
		(end 14.583918 -352.488246)
		(width 0.1651)
		(layer "In2.Cu")
		(net "PE_RX4_DR11_P")
	)
	(segment
		(start 25.631394 -323.009514)
		(end 26.473404 -323.009514)
		(width 0.1651)
		(layer "In2.Cu")
		(net "PE_RX4_DR11_P")
	)
	(segment
		(start 30.885638 -352.270568)
		(end 21.064474 -359.146856)
		(width 0.1651)
		(layer "In2.Cu")
		(net "PE_RX4_DR11_P")
	)
	(segment
		(start 32.119316 -347.900752)
		(end 31.50489 -351.385124)
		(width 0.1651)
		(layer "In2.Cu")
		(net "PE_RX4_DR11_P")
	)
	(segment
		(start 28.830524 -324.102476)
		(end 29.426154 -324.953376)
		(width 0.1651)
		(layer "In2.Cu")
		(net "PE_RX4_DR11_P")
	)
	(segment
		(start 5.308346 -345.719908)
		(end 5.08 -345.948254)
		(width 0.1651)
		(layer "In2.Cu")
		(net "PE_RX4_DR11_P")
	)
	(segment
		(start 29.98597 -325.752968)
		(end 30.031182 -325.817484)
		(width 0.1651)
		(layer "In2.Cu")
		(net "PE_RX4_DR11_P")
	)
	(segment
		(start 11.985752 -348.778322)
		(end 7.8105 -345.85402)
		(width 0.1651)
		(layer "In2.Cu")
		(net "PE_RX4_DR11_P")
	)
	(segment
		(start 17.252696 -359.278682)
		(end 16.558768 -358.793288)
		(width 0.1651)
		(layer "In2.Cu")
		(net "PE_RX4_DR11_P")
	)
	(segment
		(start 21.064474 -359.146856)
		(end 18.784316 -359.548938)
		(width 0.1651)
		(layer "In2.Cu")
		(net "PE_RX4_DR11_P")
	)
	(segment
		(start 14.583918 -352.488246)
		(end 11.985752 -348.778322)
		(width 0.1651)
		(layer "In2.Cu")
		(net "PE_RX4_DR11_P")
	)
	(segment
		(start 18.784316 -359.548938)
		(end 17.252696 -359.278682)
		(width 0.1651)
		(layer "In2.Cu")
		(net "PE_RX4_DR11_P")
	)
	(segment
		(start 31.504636 -351.385124)
		(end 30.885638 -352.270568)
		(width 0.1651)
		(layer "In2.Cu")
		(net "PE_RX4_DR11_P")
	)
	(segment
		(start 7.049516 -345.719908)
		(end 5.308346 -345.719908)
		(width 0.1651)
		(layer "In2.Cu")
		(net "PE_RX4_DR11_P")
	)
	(segment
		(start 23.882604 -323.60997)
		(end 22.800056 -323.60997)
		(width 0.174752)
		(layer "F.Cu")
		(net "PE_RX4_DR11_N")
	)
	(segment
		(start 24.857202 -323.352922)
		(end 24.139652 -323.352922)
		(width 0.174752)
		(layer "F.Cu")
		(net "PE_RX4_DR11_N")
	)
	(segment
		(start 24.139652 -323.352922)
		(end 23.882604 -323.60997)
		(width 0.174752)
		(layer "F.Cu")
		(net "PE_RX4_DR11_N")
	)
	(segment
		(start 25.273 -323.76872)
		(end 24.857202 -323.352922)
		(width 0.174752)
		(layer "F.Cu")
		(net "PE_RX4_DR11_N")
	)
	(via
		(at 5.08 -345.135454)
		(size 0.508)
		(drill 0.254)
		(layers "F.Cu" "B.Cu")
		(net "PE_RX4_DR11_N")
	)
	(via
		(at 25.273 -323.76872)
		(size 0.508)
		(drill 0.254)
		(layers "F.Cu" "B.Cu")
		(net "PE_RX4_DR11_N")
	)
	(segment
		(start 3.899154 -345.389454)
		(end 4.826 -345.389454)
		(width 0.174752)
		(layer "B.Cu")
		(net "PE_RX4_DR11_N")
	)
	(segment
		(start 4.826 -345.389454)
		(end 5.08 -345.135454)
		(width 0.174752)
		(layer "B.Cu")
		(net "PE_RX4_DR11_N")
	)
	(segment
		(start 3.651758 -345.142058)
		(end 3.899154 -345.389454)
		(width 0.174752)
		(layer "B.Cu")
		(net "PE_RX4_DR11_N")
	)
	(segment
		(start 1.868932 -345.142058)
		(end 3.651758 -345.142058)
		(width 0.174752)
		(layer "B.Cu")
		(net "PE_RX4_DR11_N")
	)
	(segment
		(start 26.442162 -323.365114)
		(end 27.39771 -323.53377)
		(width 0.1651)
		(layer "In2.Cu")
		(net "PE_RX4_DR11_N")
	)
	(segment
		(start 28.575 -324.358)
		(end 29.694632 -325.95693)
		(width 0.1651)
		(layer "In2.Cu")
		(net "PE_RX4_DR11_N")
	)
	(segment
		(start 15.507462 -355.679756)
		(end 15.42161 -355.192076)
		(width 0.1651)
		(layer "In2.Cu")
		(net "PE_RX4_DR11_N")
	)
	(segment
		(start 9.619488 -346.686632)
		(end 7.949946 -345.51747)
		(width 0.1651)
		(layer "In2.Cu")
		(net "PE_RX4_DR11_N")
	)
	(segment
		(start 30.10281 -329.354688)
		(end 30.188916 -329.842622)
		(width 0.1651)
		(layer "In2.Cu")
		(net "PE_RX4_DR11_N")
	)
	(segment
		(start 29.951426 -328.496676)
		(end 30.169358 -328.649076)
		(width 0.1651)
		(layer "In2.Cu")
		(net "PE_RX4_DR11_N")
	)
	(segment
		(start 15.65529 -356.517956)
		(end 15.799308 -356.311962)
		(width 0.1651)
		(layer "In2.Cu")
		(net "PE_RX4_DR11_N")
	)
	(segment
		(start 11.37539 -347.69933)
		(end 10.969498 -347.415104)
		(width 0.1651)
		(layer "In2.Cu")
		(net "PE_RX4_DR11_N")
	)
	(segment
		(start 5.308854 -345.364308)
		(end 5.08 -345.135454)
		(width 0.1651)
		(layer "In2.Cu")
		(net "PE_RX4_DR11_N")
	)
	(segment
		(start 25.676606 -323.365114)
		(end 26.442162 -323.365114)
		(width 0.1651)
		(layer "In2.Cu")
		(net "PE_RX4_DR11_N")
	)
	(segment
		(start 31.411926 -335.696052)
		(end 30.50921 -340.816692)
		(width 0.1651)
		(layer "In2.Cu")
		(net "PE_RX4_DR11_N")
	)
	(segment
		(start 25.273 -323.76872)
		(end 25.676606 -323.365114)
		(width 0.1651)
		(layer "In2.Cu")
		(net "PE_RX4_DR11_N")
	)
	(segment
		(start 31.758128 -347.900752)
		(end 31.168086 -351.245678)
		(width 0.1651)
		(layer "In2.Cu")
		(net "PE_RX4_DR11_N")
	)
	(segment
		(start 30.169358 -328.649076)
		(end 30.25521 -329.13701)
		(width 0.1651)
		(layer "In2.Cu")
		(net "PE_RX4_DR11_N")
	)
	(segment
		(start 30.406594 -329.995022)
		(end 31.411926 -335.696052)
		(width 0.1651)
		(layer "In2.Cu")
		(net "PE_RX4_DR11_N")
	)
	(segment
		(start 10.316464 -347.174566)
		(end 10.272776 -346.92717)
		(width 0.1651)
		(layer "In2.Cu")
		(net "PE_RX4_DR11_N")
	)
	(segment
		(start 12.241276 -348.522798)
		(end 11.419078 -347.94698)
		(width 0.1651)
		(layer "In2.Cu")
		(net "PE_RX4_DR11_N")
	)
	(segment
		(start 29.694632 -325.957692)
		(end 29.780738 -326.445372)
		(width 0.1651)
		(layer "In2.Cu")
		(net "PE_RX4_DR11_N")
	)
	(segment
		(start 10.722102 -347.458792)
		(end 10.316464 -347.174566)
		(width 0.1651)
		(layer "In2.Cu")
		(net "PE_RX4_DR11_N")
	)
	(segment
		(start 15.479776 -354.498148)
		(end 15.273782 -354.353876)
		(width 0.1651)
		(layer "In2.Cu")
		(net "PE_RX4_DR11_N")
	)
	(segment
		(start 30.017974 -327.791318)
		(end 29.865574 -328.008996)
		(width 0.1651)
		(layer "In2.Cu")
		(net "PE_RX4_DR11_N")
	)
	(segment
		(start 17.392142 -358.942132)
		(end 16.814292 -358.537764)
		(width 0.1651)
		(layer "In2.Cu")
		(net "PE_RX4_DR11_N")
	)
	(segment
		(start 15.42161 -355.192076)
		(end 15.565628 -354.986082)
		(width 0.1651)
		(layer "In2.Cu")
		(net "PE_RX4_DR11_N")
	)
	(segment
		(start 30.25521 -329.13701)
		(end 30.10281 -329.354688)
		(width 0.1651)
		(layer "In2.Cu")
		(net "PE_RX4_DR11_N")
	)
	(segment
		(start 10.969498 -347.415104)
		(end 10.722102 -347.458792)
		(width 0.1651)
		(layer "In2.Cu")
		(net "PE_RX4_DR11_N")
	)
	(segment
		(start 7.949946 -345.51747)
		(end 7.080758 -345.364308)
		(width 0.1651)
		(layer "In2.Cu")
		(net "PE_RX4_DR11_N")
	)
	(segment
		(start 30.629606 -352.015298)
		(end 30.629352 -352.015806)
		(width 0.1651)
		(layer "In2.Cu")
		(net "PE_RX4_DR11_N")
	)
	(segment
		(start 30.50921 -340.816692)
		(end 31.758128 -347.900752)
		(width 0.1651)
		(layer "In2.Cu")
		(net "PE_RX4_DR11_N")
	)
	(segment
		(start 29.865574 -328.008996)
		(end 29.951426 -328.496676)
		(width 0.1651)
		(layer "In2.Cu")
		(net "PE_RX4_DR11_N")
	)
	(segment
		(start 27.39771 -323.53377)
		(end 28.575 -324.358)
		(width 0.1651)
		(layer "In2.Cu")
		(net "PE_RX4_DR11_N")
	)
	(segment
		(start 30.629352 -352.015806)
		(end 20.925028 -358.810306)
		(width 0.1651)
		(layer "In2.Cu")
		(net "PE_RX4_DR11_N")
	)
	(segment
		(start 7.080758 -345.364308)
		(end 5.308854 -345.364308)
		(width 0.1651)
		(layer "In2.Cu")
		(net "PE_RX4_DR11_N")
	)
	(segment
		(start 29.931868 -327.303384)
		(end 30.017974 -327.791318)
		(width 0.1651)
		(layer "In2.Cu")
		(net "PE_RX4_DR11_N")
	)
	(segment
		(start 15.799308 -356.311962)
		(end 15.713456 -355.824028)
		(width 0.1651)
		(layer "In2.Cu")
		(net "PE_RX4_DR11_N")
	)
	(segment
		(start 29.628084 -326.663304)
		(end 29.71419 -327.150984)
		(width 0.1651)
		(layer "In2.Cu")
		(net "PE_RX4_DR11_N")
	)
	(segment
		(start 15.713456 -355.824028)
		(end 15.507462 -355.679756)
		(width 0.1651)
		(layer "In2.Cu")
		(net "PE_RX4_DR11_N")
	)
	(segment
		(start 14.920468 -352.3488)
		(end 12.241276 -348.522798)
		(width 0.1651)
		(layer "In2.Cu")
		(net "PE_RX4_DR11_N")
	)
	(segment
		(start 29.71419 -327.150984)
		(end 29.931868 -327.303384)
		(width 0.1651)
		(layer "In2.Cu")
		(net "PE_RX4_DR11_N")
	)
	(segment
		(start 31.168086 -351.245678)
		(end 30.629606 -352.015298)
		(width 0.1651)
		(layer "In2.Cu")
		(net "PE_RX4_DR11_N")
	)
	(segment
		(start 30.188916 -329.842622)
		(end 30.406594 -329.995022)
		(width 0.1651)
		(layer "In2.Cu")
		(net "PE_RX4_DR11_N")
	)
	(segment
		(start 20.925028 -358.810306)
		(end 18.784316 -359.18775)
		(width 0.1651)
		(layer "In2.Cu")
		(net "PE_RX4_DR11_N")
	)
	(segment
		(start 15.273782 -354.353876)
		(end 14.920468 -352.3488)
		(width 0.1651)
		(layer "In2.Cu")
		(net "PE_RX4_DR11_N")
	)
	(segment
		(start 9.867138 -346.642944)
		(end 9.619488 -346.686632)
		(width 0.1651)
		(layer "In2.Cu")
		(net "PE_RX4_DR11_N")
	)
	(segment
		(start 11.419078 -347.94698)
		(end 11.37539 -347.69933)
		(width 0.1651)
		(layer "In2.Cu")
		(net "PE_RX4_DR11_N")
	)
	(segment
		(start 29.780738 -326.445372)
		(end 29.628084 -326.663304)
		(width 0.1651)
		(layer "In2.Cu")
		(net "PE_RX4_DR11_N")
	)
	(segment
		(start 16.814292 -358.537764)
		(end 15.741142 -357.005636)
		(width 0.1651)
		(layer "In2.Cu")
		(net "PE_RX4_DR11_N")
	)
	(segment
		(start 10.272776 -346.92717)
		(end 9.867138 -346.642944)
		(width 0.1651)
		(layer "In2.Cu")
		(net "PE_RX4_DR11_N")
	)
	(segment
		(start 15.565628 -354.986082)
		(end 15.479776 -354.498148)
		(width 0.1651)
		(layer "In2.Cu")
		(net "PE_RX4_DR11_N")
	)
	(segment
		(start 15.741142 -357.005636)
		(end 15.65529 -356.517956)
		(width 0.1651)
		(layer "In2.Cu")
		(net "PE_RX4_DR11_N")
	)
	(segment
		(start 18.784316 -359.18775)
		(end 17.392142 -358.942132)
		(width 0.1651)
		(layer "In2.Cu")
		(net "PE_RX4_DR11_N")
	)
	(segment
		(start 29.694632 -325.95693)
		(end 29.694632 -325.957692)
		(width 0.1651)
		(layer "In2.Cu")
		(net "PE_RX4_DR11_N")
	)
	(segment
		(start 22.800056 -426.610018)
		(end 23.858982 -426.610018)
		(width 0.174752)
		(layer "F.Cu")
		(net "PE_RX4_DR10_P")
	)
	(segment
		(start 24.106378 -426.362622)
		(end 24.866854 -426.362622)
		(width 0.174752)
		(layer "F.Cu")
		(net "PE_RX4_DR10_P")
	)
	(segment
		(start 23.858982 -426.610018)
		(end 24.106378 -426.362622)
		(width 0.174752)
		(layer "F.Cu")
		(net "PE_RX4_DR10_P")
	)
	(segment
		(start 24.866854 -426.362622)
		(end 25.273 -426.768768)
		(width 0.174752)
		(layer "F.Cu")
		(net "PE_RX4_DR10_P")
	)
	(via
		(at 5.08 -413.535114)
		(size 0.508)
		(drill 0.254)
		(layers "F.Cu" "B.Cu")
		(net "PE_RX4_DR10_P")
	)
	(via
		(at 25.273 -426.768768)
		(size 0.508)
		(drill 0.254)
		(layers "F.Cu" "B.Cu")
		(net "PE_RX4_DR10_P")
	)
	(segment
		(start 3.90525 -413.789368)
		(end 4.825746 -413.789368)
		(width 0.174752)
		(layer "B.Cu")
		(net "PE_RX4_DR10_P")
	)
	(segment
		(start 4.825746 -413.789368)
		(end 5.08 -413.535114)
		(width 0.174752)
		(layer "B.Cu")
		(net "PE_RX4_DR10_P")
	)
	(segment
		(start 1.868932 -413.541972)
		(end 3.657854 -413.541972)
		(width 0.174752)
		(layer "B.Cu")
		(net "PE_RX4_DR10_P")
	)
	(segment
		(start 3.657854 -413.541972)
		(end 3.90525 -413.789368)
		(width 0.174752)
		(layer "B.Cu")
		(net "PE_RX4_DR10_P")
	)
	(segment
		(start 41.164764 -413.333184)
		(end 40.579294 -412.923228)
		(width 0.1651)
		(layer "In2.Cu")
		(net "PE_RX4_DR10_P")
	)
	(segment
		(start 41.529254 -418.473128)
		(end 42.054272 -415.49574)
		(width 0.1651)
		(layer "In2.Cu")
		(net "PE_RX4_DR10_P")
	)
	(segment
		(start 32.497522 -422.926002)
		(end 38.984682 -421.504618)
		(width 0.1651)
		(layer "In2.Cu")
		(net "PE_RX4_DR10_P")
	)
	(segment
		(start 40.579294 -412.923228)
		(end 39.993824 -412.513526)
		(width 0.1651)
		(layer "In2.Cu")
		(net "PE_RX4_DR10_P")
	)
	(segment
		(start 41.471342 -418.799518)
		(end 41.529 -418.473128)
		(width 0.1651)
		(layer "In2.Cu")
		(net "PE_RX4_DR10_P")
	)
	(segment
		(start 42.054526 -415.16046)
		(end 41.947592 -414.554416)
		(width 0.1651)
		(layer "In2.Cu")
		(net "PE_RX4_DR10_P")
	)
	(segment
		(start 39.203884 -421.408352)
		(end 40.146732 -420.748206)
		(width 0.1651)
		(layer "In2.Cu")
		(net "PE_RX4_DR10_P")
	)
	(segment
		(start 19.194526 -410.438854)
		(end 14.22908 -412.497778)
		(width 0.1651)
		(layer "In2.Cu")
		(net "PE_RX4_DR10_P")
	)
	(segment
		(start 27.034236 -426.282358)
		(end 27.135074 -426.241972)
		(width 0.1651)
		(layer "In2.Cu")
		(net "PE_RX4_DR10_P")
	)
	(segment
		(start 26.203656 -426.461174)
		(end 26.929334 -426.3136)
		(width 0.1651)
		(layer "In2.Cu")
		(net "PE_RX4_DR10_P")
	)
	(segment
		(start 39.785544 -412.427166)
		(end 23.923244 -409.629864)
		(width 0.1651)
		(layer "In2.Cu")
		(net "PE_RX4_DR10_P")
	)
	(segment
		(start 23.711408 -409.629864)
		(end 19.304 -410.40685)
		(width 0.1651)
		(layer "In2.Cu")
		(net "PE_RX4_DR10_P")
	)
	(segment
		(start 19.19478 -410.4386)
		(end 19.194526 -410.438854)
		(width 0.1651)
		(layer "In2.Cu")
		(net "PE_RX4_DR10_P")
	)
	(segment
		(start 14.175994 -412.513272)
		(end 14.17574 -412.513526)
		(width 0.1651)
		(layer "In2.Cu")
		(net "PE_RX4_DR10_P")
	)
	(segment
		(start 41.787826 -414.169098)
		(end 41.292526 -413.460946)
		(width 0.1651)
		(layer "In2.Cu")
		(net "PE_RX4_DR10_P")
	)
	(segment
		(start 41.529 -418.473128)
		(end 41.529254 -418.473128)
		(width 0.1651)
		(layer "In2.Cu")
		(net "PE_RX4_DR10_P")
	)
	(segment
		(start 5.309108 -413.764222)
		(end 5.08 -413.535114)
		(width 0.1651)
		(layer "In2.Cu")
		(net "PE_RX4_DR10_P")
	)
	(segment
		(start 25.273 -426.768768)
		(end 25.568402 -426.473366)
		(width 0.1651)
		(layer "In2.Cu")
		(net "PE_RX4_DR10_P")
	)
	(segment
		(start 40.383968 -420.51097)
		(end 41.311576 -419.185598)
		(width 0.1651)
		(layer "In2.Cu")
		(net "PE_RX4_DR10_P")
	)
	(segment
		(start 14.17574 -412.513526)
		(end 7.080758 -413.764222)
		(width 0.1651)
		(layer "In2.Cu")
		(net "PE_RX4_DR10_P")
	)
	(segment
		(start 27.23261 -426.192188)
		(end 32.30372 -423.005504)
		(width 0.1651)
		(layer "In2.Cu")
		(net "PE_RX4_DR10_P")
	)
	(segment
		(start 25.568402 -426.473366)
		(end 26.082244 -426.473366)
		(width 0.1651)
		(layer "In2.Cu")
		(net "PE_RX4_DR10_P")
	)
	(segment
		(start 7.080758 -413.764222)
		(end 5.309108 -413.764222)
		(width 0.1651)
		(layer "In2.Cu")
		(net "PE_RX4_DR10_P")
	)
	(arc
		(start 23.923244 -409.629864)
		(mid 23.817326 -409.620594)
		(end 23.711408 -409.629864)
		(width 0.1651)
		(layer "In2.Cu")
		(net "PE_RX4_DR10_P")
	)
	(arc
		(start 27.135074 -426.241972)
		(mid 27.184959 -426.219269)
		(end 27.23261 -426.192188)
		(width 0.1651)
		(layer "In2.Cu")
		(net "PE_RX4_DR10_P")
	)
	(arc
		(start 14.22908 -412.497778)
		(mid 14.202959 -412.506971)
		(end 14.175994 -412.513272)
		(width 0.1651)
		(layer "In2.Cu")
		(net "PE_RX4_DR10_P")
	)
	(arc
		(start 41.947592 -414.554416)
		(mid 41.888756 -414.353032)
		(end 41.787826 -414.169098)
		(width 0.1651)
		(layer "In2.Cu")
		(net "PE_RX4_DR10_P")
	)
	(arc
		(start 26.082244 -426.473366)
		(mid 26.143254 -426.470305)
		(end 26.203656 -426.461174)
		(width 0.1651)
		(layer "In2.Cu")
		(net "PE_RX4_DR10_P")
	)
	(arc
		(start 41.292526 -413.460946)
		(mid 41.234229 -413.391481)
		(end 41.164764 -413.333184)
		(width 0.1651)
		(layer "In2.Cu")
		(net "PE_RX4_DR10_P")
	)
	(arc
		(start 26.929334 -426.3136)
		(mid 26.982485 -426.300331)
		(end 27.034236 -426.282358)
		(width 0.1651)
		(layer "In2.Cu")
		(net "PE_RX4_DR10_P")
	)
	(arc
		(start 40.146732 -420.748206)
		(mid 40.275737 -420.639975)
		(end 40.383968 -420.51097)
		(width 0.1651)
		(layer "In2.Cu")
		(net "PE_RX4_DR10_P")
	)
	(arc
		(start 42.054272 -415.49574)
		(mid 42.069075 -415.32811)
		(end 42.054526 -415.16046)
		(width 0.1651)
		(layer "In2.Cu")
		(net "PE_RX4_DR10_P")
	)
	(arc
		(start 32.30372 -423.005504)
		(mid 32.397179 -422.957361)
		(end 32.497522 -422.926002)
		(width 0.1651)
		(layer "In2.Cu")
		(net "PE_RX4_DR10_P")
	)
	(arc
		(start 38.984682 -421.504618)
		(mid 39.099048 -421.467339)
		(end 39.203884 -421.408352)
		(width 0.1651)
		(layer "In2.Cu")
		(net "PE_RX4_DR10_P")
	)
	(arc
		(start 41.311576 -419.185598)
		(mid 41.412609 -419.001309)
		(end 41.471342 -418.799518)
		(width 0.1651)
		(layer "In2.Cu")
		(net "PE_RX4_DR10_P")
	)
	(arc
		(start 19.304 -410.40685)
		(mid 19.248523 -410.41974)
		(end 19.19478 -410.4386)
		(width 0.1651)
		(layer "In2.Cu")
		(net "PE_RX4_DR10_P")
	)
	(arc
		(start 39.993824 -412.513526)
		(mid 39.894419 -412.458922)
		(end 39.785544 -412.427166)
		(width 0.1651)
		(layer "In2.Cu")
		(net "PE_RX4_DR10_P")
	)
	(segment
		(start 22.800056 -425.810172)
		(end 23.882604 -425.810172)
		(width 0.174752)
		(layer "F.Cu")
		(net "PE_RX4_DR10_N")
	)
	(segment
		(start 24.8666 -426.057568)
		(end 25.273 -425.651168)
		(width 0.174752)
		(layer "F.Cu")
		(net "PE_RX4_DR10_N")
	)
	(segment
		(start 23.882604 -425.810172)
		(end 24.13 -426.057568)
		(width 0.174752)
		(layer "F.Cu")
		(net "PE_RX4_DR10_N")
	)
	(segment
		(start 24.13 -426.057568)
		(end 24.8666 -426.057568)
		(width 0.174752)
		(layer "F.Cu")
		(net "PE_RX4_DR10_N")
	)
	(via
		(at 25.273 -425.651168)
		(size 0.508)
		(drill 0.254)
		(layers "F.Cu" "B.Cu")
		(net "PE_RX4_DR10_N")
	)
	(via
		(at 5.08 -414.347914)
		(size 0.508)
		(drill 0.254)
		(layers "F.Cu" "B.Cu")
		(net "PE_RX4_DR10_N")
	)
	(segment
		(start 4.826508 -414.094422)
		(end 5.08 -414.347914)
		(width 0.174752)
		(layer "B.Cu")
		(net "PE_RX4_DR10_N")
	)
	(segment
		(start 3.657854 -414.341818)
		(end 3.90525 -414.094422)
		(width 0.174752)
		(layer "B.Cu")
		(net "PE_RX4_DR10_N")
	)
	(segment
		(start 1.868932 -414.341818)
		(end 3.657854 -414.341818)
		(width 0.174752)
		(layer "B.Cu")
		(net "PE_RX4_DR10_N")
	)
	(segment
		(start 3.90525 -414.094422)
		(end 4.826508 -414.094422)
		(width 0.174752)
		(layer "B.Cu")
		(net "PE_RX4_DR10_N")
	)
	(segment
		(start 26.13279 -426.112686)
		(end 26.858722 -425.964858)
		(width 0.1651)
		(layer "In2.Cu")
		(net "PE_RX4_DR10_N")
	)
	(segment
		(start 35.583114 -421.7035)
		(end 35.794696 -421.839136)
		(width 0.1651)
		(layer "In2.Cu")
		(net "PE_RX4_DR10_N")
	)
	(segment
		(start 41.383966 -417.247324)
		(end 41.470072 -416.75939)
		(width 0.1651)
		(layer "In2.Cu")
		(net "PE_RX4_DR10_N")
	)
	(segment
		(start 38.999922 -421.117014)
		(end 39.94277 -420.456868)
		(width 0.1651)
		(layer "In2.Cu")
		(net "PE_RX4_DR10_N")
	)
	(segment
		(start 36.414202 -421.521636)
		(end 36.898072 -421.415464)
		(width 0.1651)
		(layer "In2.Cu")
		(net "PE_RX4_DR10_N")
	)
	(segment
		(start 41.496488 -414.37306)
		(end 41.001188 -413.664908)
		(width 0.1651)
		(layer "In2.Cu")
		(net "PE_RX4_DR10_N")
	)
	(segment
		(start 36.898072 -421.415464)
		(end 37.109654 -421.5511)
		(width 0.1651)
		(layer "In2.Cu")
		(net "PE_RX4_DR10_N")
	)
	(segment
		(start 35.099244 -421.809672)
		(end 35.583114 -421.7035)
		(width 0.1651)
		(layer "In2.Cu")
		(net "PE_RX4_DR10_N")
	)
	(segment
		(start 14.237462 -412.863792)
		(end 7.112 -414.119822)
		(width 0.1651)
		(layer "In2.Cu")
		(net "PE_RX4_DR10_N")
	)
	(segment
		(start 26.902156 -425.951904)
		(end 27.002486 -425.911772)
		(width 0.1651)
		(layer "In2.Cu")
		(net "PE_RX4_DR10_N")
	)
	(segment
		(start 30.55493 -423.684192)
		(end 30.974284 -423.42054)
		(width 0.1651)
		(layer "In2.Cu")
		(net "PE_RX4_DR10_N")
	)
	(segment
		(start 40.09263 -420.307008)
		(end 41.020238 -418.981636)
		(width 0.1651)
		(layer "In2.Cu")
		(net "PE_RX4_DR10_N")
	)
	(segment
		(start 41.6179 -415.921444)
		(end 41.704006 -415.433764)
		(width 0.1651)
		(layer "In2.Cu")
		(net "PE_RX4_DR10_N")
	)
	(segment
		(start 27.043126 -425.891198)
		(end 27.043126 -425.890944)
		(width 0.1651)
		(layer "In2.Cu")
		(net "PE_RX4_DR10_N")
	)
	(segment
		(start 40.960802 -413.624522)
		(end 39.789862 -412.804864)
		(width 0.1651)
		(layer "In2.Cu")
		(net "PE_RX4_DR10_N")
	)
	(segment
		(start 37.72916 -421.2336)
		(end 38.21303 -421.127428)
		(width 0.1651)
		(layer "In2.Cu")
		(net "PE_RX4_DR10_N")
	)
	(segment
		(start 5.308092 -414.119822)
		(end 5.08 -414.347914)
		(width 0.1651)
		(layer "In2.Cu")
		(net "PE_RX4_DR10_N")
	)
	(segment
		(start 41.236138 -418.08527)
		(end 41.09212 -417.879276)
		(width 0.1651)
		(layer "In2.Cu")
		(net "PE_RX4_DR10_N")
	)
	(segment
		(start 27.043126 -425.890944)
		(end 29.834332 -424.13682)
		(width 0.1651)
		(layer "In2.Cu")
		(net "PE_RX4_DR10_N")
	)
	(segment
		(start 38.424612 -421.263064)
		(end 38.908482 -421.157146)
		(width 0.1651)
		(layer "In2.Cu")
		(net "PE_RX4_DR10_N")
	)
	(segment
		(start 31.030418 -423.17543)
		(end 31.449772 -422.911778)
		(width 0.1651)
		(layer "In2.Cu")
		(net "PE_RX4_DR10_N")
	)
	(segment
		(start 31.694882 -422.967912)
		(end 32.114236 -422.70426)
		(width 0.1651)
		(layer "In2.Cu")
		(net "PE_RX4_DR10_N")
	)
	(segment
		(start 31.449772 -422.911778)
		(end 31.694882 -422.967912)
		(width 0.1651)
		(layer "In2.Cu")
		(net "PE_RX4_DR10_N")
	)
	(segment
		(start 39.723822 -412.777432)
		(end 23.861522 -409.98013)
		(width 0.1651)
		(layer "In2.Cu")
		(net "PE_RX4_DR10_N")
	)
	(segment
		(start 35.794696 -421.839136)
		(end 36.278566 -421.733218)
		(width 0.1651)
		(layer "In2.Cu")
		(net "PE_RX4_DR10_N")
	)
	(segment
		(start 41.09212 -417.879276)
		(end 41.177972 -417.391342)
		(width 0.1651)
		(layer "In2.Cu")
		(net "PE_RX4_DR10_N")
	)
	(segment
		(start 34.963608 -422.021254)
		(end 35.099244 -421.809672)
		(width 0.1651)
		(layer "In2.Cu")
		(net "PE_RX4_DR10_N")
	)
	(segment
		(start 37.109654 -421.5511)
		(end 37.593524 -421.445182)
		(width 0.1651)
		(layer "In2.Cu")
		(net "PE_RX4_DR10_N")
	)
	(segment
		(start 30.974284 -423.42054)
		(end 31.030418 -423.17543)
		(width 0.1651)
		(layer "In2.Cu")
		(net "PE_RX4_DR10_N")
	)
	(segment
		(start 37.593524 -421.445182)
		(end 37.72916 -421.2336)
		(width 0.1651)
		(layer "In2.Cu")
		(net "PE_RX4_DR10_N")
	)
	(segment
		(start 29.834586 -424.13682)
		(end 29.890466 -423.89171)
		(width 0.1651)
		(layer "In2.Cu")
		(net "PE_RX4_DR10_N")
	)
	(segment
		(start 41.121076 -418.737796)
		(end 41.236138 -418.08527)
		(width 0.1651)
		(layer "In2.Cu")
		(net "PE_RX4_DR10_N")
	)
	(segment
		(start 7.112 -414.119822)
		(end 5.308092 -414.119822)
		(width 0.1651)
		(layer "In2.Cu")
		(net "PE_RX4_DR10_N")
	)
	(segment
		(start 25.273 -425.651168)
		(end 25.739598 -426.117766)
		(width 0.1651)
		(layer "In2.Cu")
		(net "PE_RX4_DR10_N")
	)
	(segment
		(start 36.278566 -421.733218)
		(end 36.414202 -421.521636)
		(width 0.1651)
		(layer "In2.Cu")
		(net "PE_RX4_DR10_N")
	)
	(segment
		(start 30.30982 -423.628058)
		(end 30.55493 -423.684192)
		(width 0.1651)
		(layer "In2.Cu")
		(net "PE_RX4_DR10_N")
	)
	(segment
		(start 29.834332 -424.13682)
		(end 29.834586 -424.13682)
		(width 0.1651)
		(layer "In2.Cu")
		(net "PE_RX4_DR10_N")
	)
	(segment
		(start 41.411906 -416.065716)
		(end 41.6179 -415.921444)
		(width 0.1651)
		(layer "In2.Cu")
		(net "PE_RX4_DR10_N")
	)
	(segment
		(start 41.470072 -416.75939)
		(end 41.3258 -416.553396)
		(width 0.1651)
		(layer "In2.Cu")
		(net "PE_RX4_DR10_N")
	)
	(segment
		(start 41.3258 -416.553396)
		(end 41.411906 -416.065716)
		(width 0.1651)
		(layer "In2.Cu")
		(net "PE_RX4_DR10_N")
	)
	(segment
		(start 29.890466 -423.89171)
		(end 30.30982 -423.628058)
		(width 0.1651)
		(layer "In2.Cu")
		(net "PE_RX4_DR10_N")
	)
	(segment
		(start 19.330924 -410.767276)
		(end 14.365224 -412.826454)
		(width 0.1651)
		(layer "In2.Cu")
		(net "PE_RX4_DR10_N")
	)
	(segment
		(start 41.177972 -417.391342)
		(end 41.383966 -417.247324)
		(width 0.1651)
		(layer "In2.Cu")
		(net "PE_RX4_DR10_N")
	)
	(segment
		(start 23.773384 -409.98013)
		(end 19.365468 -410.757116)
		(width 0.1651)
		(layer "In2.Cu")
		(net "PE_RX4_DR10_N")
	)
	(segment
		(start 32.421322 -422.57853)
		(end 34.963608 -422.021254)
		(width 0.1651)
		(layer "In2.Cu")
		(net "PE_RX4_DR10_N")
	)
	(segment
		(start 32.421068 -422.57853)
		(end 32.421322 -422.57853)
		(width 0.1651)
		(layer "In2.Cu")
		(net "PE_RX4_DR10_N")
	)
	(segment
		(start 41.70426 -415.221928)
		(end 41.597326 -414.616392)
		(width 0.1651)
		(layer "In2.Cu")
		(net "PE_RX4_DR10_N")
	)
	(segment
		(start 25.739598 -426.117766)
		(end 26.082244 -426.117766)
		(width 0.1651)
		(layer "In2.Cu")
		(net "PE_RX4_DR10_N")
	)
	(segment
		(start 38.21303 -421.127428)
		(end 38.424612 -421.263064)
		(width 0.1651)
		(layer "In2.Cu")
		(net "PE_RX4_DR10_N")
	)
	(arc
		(start 32.114236 -422.70426)
		(mid 32.262209 -422.628108)
		(end 32.421068 -422.57853)
		(width 0.1651)
		(layer "In2.Cu")
		(net "PE_RX4_DR10_N")
	)
	(arc
		(start 27.002486 -425.911772)
		(mid 27.023266 -425.902394)
		(end 27.043126 -425.891198)
		(width 0.1651)
		(layer "In2.Cu")
		(net "PE_RX4_DR10_N")
	)
	(arc
		(start 39.789862 -412.804864)
		(mid 39.75834 -412.787549)
		(end 39.723822 -412.777432)
		(width 0.1651)
		(layer "In2.Cu")
		(net "PE_RX4_DR10_N")
	)
	(arc
		(start 41.704006 -415.433764)
		(mid 41.713412 -415.327856)
		(end 41.70426 -415.221928)
		(width 0.1651)
		(layer "In2.Cu")
		(net "PE_RX4_DR10_N")
	)
	(arc
		(start 41.001188 -413.664908)
		(mid 40.982755 -413.642955)
		(end 40.960802 -413.624522)
		(width 0.1651)
		(layer "In2.Cu")
		(net "PE_RX4_DR10_N")
	)
	(arc
		(start 38.908482 -421.157146)
		(mid 38.956196 -421.141622)
		(end 38.999922 -421.117014)
		(width 0.1651)
		(layer "In2.Cu")
		(net "PE_RX4_DR10_N")
	)
	(arc
		(start 41.597326 -414.616392)
		(mid 41.560207 -414.489214)
		(end 41.496488 -414.37306)
		(width 0.1651)
		(layer "In2.Cu")
		(net "PE_RX4_DR10_N")
	)
	(arc
		(start 14.365224 -412.826454)
		(mid 14.302368 -412.848631)
		(end 14.237462 -412.863792)
		(width 0.1651)
		(layer "In2.Cu")
		(net "PE_RX4_DR10_N")
	)
	(arc
		(start 26.858722 -425.964858)
		(mid 26.880728 -425.95935)
		(end 26.902156 -425.951904)
		(width 0.1651)
		(layer "In2.Cu")
		(net "PE_RX4_DR10_N")
	)
	(arc
		(start 39.94277 -420.456868)
		(mid 40.024263 -420.388501)
		(end 40.09263 -420.307008)
		(width 0.1651)
		(layer "In2.Cu")
		(net "PE_RX4_DR10_N")
	)
	(arc
		(start 41.020238 -418.981636)
		(mid 41.083983 -418.86523)
		(end 41.121076 -418.737796)
		(width 0.1651)
		(layer "In2.Cu")
		(net "PE_RX4_DR10_N")
	)
	(arc
		(start 23.861522 -409.98013)
		(mid 23.817455 -409.9763)
		(end 23.773384 -409.98013)
		(width 0.1651)
		(layer "In2.Cu")
		(net "PE_RX4_DR10_N")
	)
	(arc
		(start 19.365468 -410.757116)
		(mid 19.347917 -410.761249)
		(end 19.330924 -410.767276)
		(width 0.1651)
		(layer "In2.Cu")
		(net "PE_RX4_DR10_N")
	)
	(arc
		(start 26.082244 -426.117766)
		(mid 26.107644 -426.116493)
		(end 26.13279 -426.112686)
		(width 0.1651)
		(layer "In2.Cu")
		(net "PE_RX4_DR10_N")
	)
	(segment
		(start 222.133414 -388.94258)
		(end 221.727014 -389.34898)
		(width 0.174752)
		(layer "F.Cu")
		(net "PE_RX4_DR1_P")
	)
	(segment
		(start 224.199958 -389.189976)
		(end 223.132396 -389.189976)
		(width 0.174752)
		(layer "F.Cu")
		(net "PE_RX4_DR1_P")
	)
	(segment
		(start 222.885 -388.94258)
		(end 222.133414 -388.94258)
		(width 0.174752)
		(layer "F.Cu")
		(net "PE_RX4_DR1_P")
	)
	(segment
		(start 223.132396 -389.189976)
		(end 222.885 -388.94258)
		(width 0.174752)
		(layer "F.Cu")
		(net "PE_RX4_DR1_P")
	)
	(via
		(at 5.08 -399.148046)
		(size 0.508)
		(drill 0.254)
		(layers "F.Cu" "B.Cu")
		(net "PE_RX4_DR1_P")
	)
	(via
		(at 221.727014 -389.34898)
		(size 0.508)
		(drill 0.254)
		(layers "F.Cu" "B.Cu")
		(net "PE_RX4_DR1_P")
	)
	(segment
		(start 3.905504 -398.8943)
		(end 4.826254 -398.8943)
		(width 0.174752)
		(layer "B.Cu")
		(net "PE_RX4_DR1_P")
	)
	(segment
		(start 4.826254 -398.8943)
		(end 5.08 -399.148046)
		(width 0.174752)
		(layer "B.Cu")
		(net "PE_RX4_DR1_P")
	)
	(segment
		(start 3.657854 -399.14195)
		(end 3.905504 -398.8943)
		(width 0.174752)
		(layer "B.Cu")
		(net "PE_RX4_DR1_P")
	)
	(segment
		(start 1.868932 -399.14195)
		(end 3.657854 -399.14195)
		(width 0.174752)
		(layer "B.Cu")
		(net "PE_RX4_DR1_P")
	)
	(segment
		(start 45.153326 -409.136342)
		(end 189.871096 -383.624074)
		(width 0.1651)
		(layer "In2.Cu")
		(net "PE_RX4_DR1_P")
	)
	(segment
		(start 7.080758 -398.9197)
		(end 11.970258 -399.781776)
		(width 0.1651)
		(layer "In2.Cu")
		(net "PE_RX4_DR1_P")
	)
	(segment
		(start 221.346014 -388.96798)
		(end 221.727014 -389.34898)
		(width 0.1651)
		(layer "In2.Cu")
		(net "PE_RX4_DR1_P")
	)
	(segment
		(start 11.970258 -399.781776)
		(end 18.772124 -404.54453)
		(width 0.1651)
		(layer "In2.Cu")
		(net "PE_RX4_DR1_P")
	)
	(segment
		(start 190.091568 -383.624074)
		(end 220.398594 -388.96798)
		(width 0.1651)
		(layer "In2.Cu")
		(net "PE_RX4_DR1_P")
	)
	(segment
		(start 18.772124 -404.54453)
		(end 44.809156 -409.136342)
		(width 0.1651)
		(layer "In2.Cu")
		(net "PE_RX4_DR1_P")
	)
	(segment
		(start 5.308346 -398.9197)
		(end 7.080758 -398.9197)
		(width 0.1651)
		(layer "In2.Cu")
		(net "PE_RX4_DR1_P")
	)
	(segment
		(start 220.398594 -388.96798)
		(end 221.346014 -388.96798)
		(width 0.1651)
		(layer "In2.Cu")
		(net "PE_RX4_DR1_P")
	)
	(segment
		(start 5.08 -399.148046)
		(end 5.308346 -398.9197)
		(width 0.1651)
		(layer "In2.Cu")
		(net "PE_RX4_DR1_P")
	)
	(arc
		(start 189.871096 -383.624074)
		(mid 189.981332 -383.614432)
		(end 190.091568 -383.624074)
		(width 0.1651)
		(layer "In2.Cu")
		(net "PE_RX4_DR1_P")
	)
	(arc
		(start 44.809156 -409.136342)
		(mid 44.981243 -409.151425)
		(end 45.153326 -409.136342)
		(width 0.1651)
		(layer "In2.Cu")
		(net "PE_RX4_DR1_P")
	)
	(segment
		(start 222.13316 -388.637526)
		(end 221.727014 -388.23138)
		(width 0.174752)
		(layer "F.Cu")
		(net "PE_RX4_DR1_N")
	)
	(segment
		(start 224.199958 -388.39013)
		(end 223.139 -388.39013)
		(width 0.174752)
		(layer "F.Cu")
		(net "PE_RX4_DR1_N")
	)
	(segment
		(start 223.139 -388.39013)
		(end 222.891604 -388.637526)
		(width 0.174752)
		(layer "F.Cu")
		(net "PE_RX4_DR1_N")
	)
	(segment
		(start 222.891604 -388.637526)
		(end 222.13316 -388.637526)
		(width 0.174752)
		(layer "F.Cu")
		(net "PE_RX4_DR1_N")
	)
	(via
		(at 221.727014 -388.23138)
		(size 0.508)
		(drill 0.254)
		(layers "F.Cu" "B.Cu")
		(net "PE_RX4_DR1_N")
	)
	(via
		(at 5.08 -398.335246)
		(size 0.508)
		(drill 0.254)
		(layers "F.Cu" "B.Cu")
		(net "PE_RX4_DR1_N")
	)
	(segment
		(start 3.905504 -398.589246)
		(end 4.826 -398.589246)
		(width 0.174752)
		(layer "B.Cu")
		(net "PE_RX4_DR1_N")
	)
	(segment
		(start 1.868932 -398.34185)
		(end 3.658108 -398.34185)
		(width 0.174752)
		(layer "B.Cu")
		(net "PE_RX4_DR1_N")
	)
	(segment
		(start 3.658108 -398.34185)
		(end 3.905504 -398.589246)
		(width 0.174752)
		(layer "B.Cu")
		(net "PE_RX4_DR1_N")
	)
	(segment
		(start 4.826 -398.589246)
		(end 5.08 -398.335246)
		(width 0.174752)
		(layer "B.Cu")
		(net "PE_RX4_DR1_N")
	)
	(segment
		(start 190.152782 -383.273554)
		(end 220.429836 -388.61238)
		(width 0.1651)
		(layer "In2.Cu")
		(net "PE_RX4_DR1_N")
	)
	(segment
		(start 221.346014 -388.61238)
		(end 221.727014 -388.23138)
		(width 0.1651)
		(layer "In2.Cu")
		(net "PE_RX4_DR1_N")
	)
	(segment
		(start 12.109704 -399.445226)
		(end 18.91157 -404.20798)
		(width 0.1651)
		(layer "In2.Cu")
		(net "PE_RX4_DR1_N")
	)
	(segment
		(start 45.091604 -408.786076)
		(end 189.808866 -383.273554)
		(width 0.1651)
		(layer "In2.Cu")
		(net "PE_RX4_DR1_N")
	)
	(segment
		(start 18.91157 -404.20798)
		(end 44.870878 -408.786076)
		(width 0.1651)
		(layer "In2.Cu")
		(net "PE_RX4_DR1_N")
	)
	(segment
		(start 5.308854 -398.5641)
		(end 7.112 -398.5641)
		(width 0.1651)
		(layer "In2.Cu")
		(net "PE_RX4_DR1_N")
	)
	(segment
		(start 5.08 -398.335246)
		(end 5.308854 -398.5641)
		(width 0.1651)
		(layer "In2.Cu")
		(net "PE_RX4_DR1_N")
	)
	(segment
		(start 7.112 -398.5641)
		(end 12.109704 -399.445226)
		(width 0.1651)
		(layer "In2.Cu")
		(net "PE_RX4_DR1_N")
	)
	(segment
		(start 220.429836 -388.61238)
		(end 221.346014 -388.61238)
		(width 0.1651)
		(layer "In2.Cu")
		(net "PE_RX4_DR1_N")
	)
	(arc
		(start 44.870878 -408.786076)
		(mid 44.981243 -408.795762)
		(end 45.091604 -408.786076)
		(width 0.1651)
		(layer "In2.Cu")
		(net "PE_RX4_DR1_N")
	)
	(arc
		(start 189.808866 -383.273554)
		(mid 189.980824 -383.258516)
		(end 190.152782 -383.273554)
		(width 0.1651)
		(layer "In2.Cu")
		(net "PE_RX4_DR1_N")
	)
	(segment
		(start 222.891604 -491.942628)
		(end 222.133414 -491.942628)
		(width 0.174752)
		(layer "F.Cu")
		(net "PE_RX4_DR0_P")
	)
	(segment
		(start 224.199958 -492.190024)
		(end 223.139 -492.190024)
		(width 0.174752)
		(layer "F.Cu")
		(net "PE_RX4_DR0_P")
	)
	(segment
		(start 222.133414 -491.942628)
		(end 221.727014 -492.349028)
		(width 0.174752)
		(layer "F.Cu")
		(net "PE_RX4_DR0_P")
	)
	(segment
		(start 223.139 -492.190024)
		(end 222.891604 -491.942628)
		(width 0.174752)
		(layer "F.Cu")
		(net "PE_RX4_DR0_P")
	)
	(via
		(at 5.08 -430.347882)
		(size 0.508)
		(drill 0.254)
		(layers "F.Cu" "B.Cu")
		(net "PE_RX4_DR0_P")
	)
	(via
		(at 221.727014 -492.349028)
		(size 0.508)
		(drill 0.254)
		(layers "F.Cu" "B.Cu")
		(net "PE_RX4_DR0_P")
	)
	(segment
		(start 3.90525 -430.09439)
		(end 4.826508 -430.09439)
		(width 0.174752)
		(layer "B.Cu")
		(net "PE_RX4_DR0_P")
	)
	(segment
		(start 3.657854 -430.341786)
		(end 3.90525 -430.09439)
		(width 0.174752)
		(layer "B.Cu")
		(net "PE_RX4_DR0_P")
	)
	(segment
		(start 4.826508 -430.09439)
		(end 5.08 -430.347882)
		(width 0.174752)
		(layer "B.Cu")
		(net "PE_RX4_DR0_P")
	)
	(segment
		(start 1.868932 -430.341786)
		(end 3.657854 -430.341786)
		(width 0.174752)
		(layer "B.Cu")
		(net "PE_RX4_DR0_P")
	)
	(segment
		(start 9.93013 -431.34788)
		(end 8.545322 -430.377854)
		(width 0.1651)
		(layer "In2.Cu")
		(net "PE_RX4_DR0_P")
	)
	(segment
		(start 221.346014 -491.968028)
		(end 220.364304 -491.968028)
		(width 0.1651)
		(layer "In2.Cu")
		(net "PE_RX4_DR0_P")
	)
	(segment
		(start 188.656468 -470.268046)
		(end 41.86301 -444.371984)
		(width 0.1651)
		(layer "In2.Cu")
		(net "PE_RX4_DR0_P")
	)
	(segment
		(start 24.115522 -462.531714)
		(end 24.021796 -462.583276)
		(width 0.1651)
		(layer "In2.Cu")
		(net "PE_RX4_DR0_P")
	)
	(segment
		(start 16.889476 -462.027524)
		(end 15.041626 -459.38821)
		(width 0.1651)
		(layer "In2.Cu")
		(net "PE_RX4_DR0_P")
	)
	(segment
		(start 41.86301 -444.371984)
		(end 40.489886 -444.6143)
		(width 0.1651)
		(layer "In2.Cu")
		(net "PE_RX4_DR0_P")
	)
	(segment
		(start 24.021034 -462.583784)
		(end 23.986998 -462.602326)
		(width 0.1651)
		(layer "In2.Cu")
		(net "PE_RX4_DR0_P")
	)
	(segment
		(start 7.080758 -430.119536)
		(end 5.308346 -430.119536)
		(width 0.1651)
		(layer "In2.Cu")
		(net "PE_RX4_DR0_P")
	)
	(segment
		(start 36.936426 -447.148712)
		(end 28.131262 -459.720188)
		(width 0.1651)
		(layer "In2.Cu")
		(net "PE_RX4_DR0_P")
	)
	(segment
		(start 8.545322 -430.377854)
		(end 7.080758 -430.119536)
		(width 0.1651)
		(layer "In2.Cu")
		(net "PE_RX4_DR0_P")
	)
	(segment
		(start 23.986998 -462.602326)
		(end 23.843996 -462.643982)
		(width 0.1651)
		(layer "In2.Cu")
		(net "PE_RX4_DR0_P")
	)
	(segment
		(start 220.364304 -491.968028)
		(end 219.437458 -491.80496)
		(width 0.1651)
		(layer "In2.Cu")
		(net "PE_RX4_DR0_P")
	)
	(segment
		(start 5.308346 -430.119536)
		(end 5.08 -430.347882)
		(width 0.1651)
		(layer "In2.Cu")
		(net "PE_RX4_DR0_P")
	)
	(segment
		(start 40.489886 -444.6143)
		(end 37.092382 -446.992756)
		(width 0.1651)
		(layer "In2.Cu")
		(net "PE_RX4_DR0_P")
	)
	(segment
		(start 221.727014 -492.349028)
		(end 221.346014 -491.968028)
		(width 0.1651)
		(layer "In2.Cu")
		(net "PE_RX4_DR0_P")
	)
	(segment
		(start 219.437458 -491.80496)
		(end 188.656468 -470.268046)
		(width 0.1651)
		(layer "In2.Cu")
		(net "PE_RX4_DR0_P")
	)
	(segment
		(start 10.153142 -431.666396)
		(end 9.93013 -431.34788)
		(width 0.1651)
		(layer "In2.Cu")
		(net "PE_RX4_DR0_P")
	)
	(segment
		(start 17.951704 -462.770982)
		(end 16.889476 -462.027524)
		(width 0.1651)
		(layer "In2.Cu")
		(net "PE_RX4_DR0_P")
	)
	(segment
		(start 20.537932 -463.227166)
		(end 17.951704 -462.770982)
		(width 0.1651)
		(layer "In2.Cu")
		(net "PE_RX4_DR0_P")
	)
	(segment
		(start 28.131262 -459.720188)
		(end 24.115522 -462.531714)
		(width 0.1651)
		(layer "In2.Cu")
		(net "PE_RX4_DR0_P")
	)
	(segment
		(start 23.843996 -462.643982)
		(end 20.537932 -463.227166)
		(width 0.1651)
		(layer "In2.Cu")
		(net "PE_RX4_DR0_P")
	)
	(segment
		(start 24.021796 -462.583276)
		(end 24.021034 -462.583784)
		(width 0.1651)
		(layer "In2.Cu")
		(net "PE_RX4_DR0_P")
	)
	(segment
		(start 15.041626 -459.38821)
		(end 10.153142 -431.666396)
		(width 0.1651)
		(layer "In2.Cu")
		(net "PE_RX4_DR0_P")
	)
	(arc
		(start 37.092382 -446.992756)
		(mid 37.007581 -447.063911)
		(end 36.936426 -447.148712)
		(width 0.1651)
		(layer "In2.Cu")
		(net "PE_RX4_DR0_P")
	)
	(segment
		(start 224.199958 -491.390178)
		(end 223.139 -491.390178)
		(width 0.174752)
		(layer "F.Cu")
		(net "PE_RX4_DR0_N")
	)
	(segment
		(start 223.139 -491.390178)
		(end 222.891604 -491.637574)
		(width 0.174752)
		(layer "F.Cu")
		(net "PE_RX4_DR0_N")
	)
	(segment
		(start 222.891604 -491.637574)
		(end 222.13316 -491.637574)
		(width 0.174752)
		(layer "F.Cu")
		(net "PE_RX4_DR0_N")
	)
	(segment
		(start 222.13316 -491.637574)
		(end 221.727014 -491.231428)
		(width 0.174752)
		(layer "F.Cu")
		(net "PE_RX4_DR0_N")
	)
	(via
		(at 5.08 -429.535082)
		(size 0.508)
		(drill 0.254)
		(layers "F.Cu" "B.Cu")
		(net "PE_RX4_DR0_N")
	)
	(via
		(at 221.727014 -491.231428)
		(size 0.508)
		(drill 0.254)
		(layers "F.Cu" "B.Cu")
		(net "PE_RX4_DR0_N")
	)
	(segment
		(start 3.657854 -429.54194)
		(end 3.90525 -429.789336)
		(width 0.174752)
		(layer "B.Cu")
		(net "PE_RX4_DR0_N")
	)
	(segment
		(start 3.90525 -429.789336)
		(end 4.825746 -429.789336)
		(width 0.174752)
		(layer "B.Cu")
		(net "PE_RX4_DR0_N")
	)
	(segment
		(start 1.868932 -429.54194)
		(end 3.657854 -429.54194)
		(width 0.174752)
		(layer "B.Cu")
		(net "PE_RX4_DR0_N")
	)
	(segment
		(start 4.825746 -429.789336)
		(end 5.08 -429.535082)
		(width 0.174752)
		(layer "B.Cu")
		(net "PE_RX4_DR0_N")
	)
	(segment
		(start 27.875738 -459.464664)
		(end 23.927308 -462.228946)
		(width 0.1651)
		(layer "In2.Cu")
		(net "PE_RX4_DR0_N")
	)
	(segment
		(start 5.308854 -429.763936)
		(end 5.08 -429.535082)
		(width 0.1651)
		(layer "In2.Cu")
		(net "PE_RX4_DR0_N")
	)
	(segment
		(start 20.537932 -462.865978)
		(end 18.09115 -462.434178)
		(width 0.1651)
		(layer "In2.Cu")
		(net "PE_RX4_DR0_N")
	)
	(segment
		(start 36.88842 -446.701418)
		(end 36.888166 -446.701418)
		(width 0.1651)
		(layer "In2.Cu")
		(net "PE_RX4_DR0_N")
	)
	(segment
		(start 188.796168 -469.931496)
		(end 41.862756 -444.010542)
		(width 0.1651)
		(layer "In2.Cu")
		(net "PE_RX4_DR0_N")
	)
	(segment
		(start 36.644834 -446.944496)
		(end 27.875738 -459.464664)
		(width 0.1651)
		(layer "In2.Cu")
		(net "PE_RX4_DR0_N")
	)
	(segment
		(start 23.76297 -462.297018)
		(end 20.537932 -462.865978)
		(width 0.1651)
		(layer "In2.Cu")
		(net "PE_RX4_DR0_N")
	)
	(segment
		(start 8.684768 -430.041304)
		(end 7.112 -429.763936)
		(width 0.1651)
		(layer "In2.Cu")
		(net "PE_RX4_DR0_N")
	)
	(segment
		(start 18.09115 -462.434178)
		(end 17.145 -461.772)
		(width 0.1651)
		(layer "In2.Cu")
		(net "PE_RX4_DR0_N")
	)
	(segment
		(start 23.927308 -462.228946)
		(end 23.927562 -462.2292)
		(width 0.1651)
		(layer "In2.Cu")
		(net "PE_RX4_DR0_N")
	)
	(segment
		(start 40.350948 -444.277496)
		(end 40.35044 -444.27775)
		(width 0.1651)
		(layer "In2.Cu")
		(net "PE_RX4_DR0_N")
	)
	(segment
		(start 221.727014 -491.231428)
		(end 221.346014 -491.612428)
		(width 0.1651)
		(layer "In2.Cu")
		(net "PE_RX4_DR0_N")
	)
	(segment
		(start 23.850092 -462.271618)
		(end 23.76297 -462.297018)
		(width 0.1651)
		(layer "In2.Cu")
		(net "PE_RX4_DR0_N")
	)
	(segment
		(start 40.35044 -444.27775)
		(end 36.88842 -446.701418)
		(width 0.1651)
		(layer "In2.Cu")
		(net "PE_RX4_DR0_N")
	)
	(segment
		(start 23.849838 -462.271618)
		(end 23.850092 -462.271618)
		(width 0.1651)
		(layer "In2.Cu")
		(net "PE_RX4_DR0_N")
	)
	(segment
		(start 23.889208 -462.250028)
		(end 23.8506 -462.27111)
		(width 0.1651)
		(layer "In2.Cu")
		(net "PE_RX4_DR0_N")
	)
	(segment
		(start 17.145 -461.772)
		(end 15.378176 -459.248764)
		(width 0.1651)
		(layer "In2.Cu")
		(net "PE_RX4_DR0_N")
	)
	(segment
		(start 220.395546 -491.612428)
		(end 219.576904 -491.468156)
		(width 0.1651)
		(layer "In2.Cu")
		(net "PE_RX4_DR0_N")
	)
	(segment
		(start 23.8506 -462.27111)
		(end 23.849838 -462.271618)
		(width 0.1651)
		(layer "In2.Cu")
		(net "PE_RX4_DR0_N")
	)
	(segment
		(start 221.346014 -491.612428)
		(end 220.395546 -491.612428)
		(width 0.1651)
		(layer "In2.Cu")
		(net "PE_RX4_DR0_N")
	)
	(segment
		(start 41.862756 -444.010542)
		(end 40.350948 -444.277496)
		(width 0.1651)
		(layer "In2.Cu")
		(net "PE_RX4_DR0_N")
	)
	(segment
		(start 23.927562 -462.2292)
		(end 23.889208 -462.250028)
		(width 0.1651)
		(layer "In2.Cu")
		(net "PE_RX4_DR0_N")
	)
	(segment
		(start 10.489692 -431.526442)
		(end 10.185654 -431.092356)
		(width 0.1651)
		(layer "In2.Cu")
		(net "PE_RX4_DR0_N")
	)
	(segment
		(start 15.378176 -459.248764)
		(end 10.489692 -431.526442)
		(width 0.1651)
		(layer "In2.Cu")
		(net "PE_RX4_DR0_N")
	)
	(segment
		(start 219.576904 -491.468156)
		(end 188.796168 -469.931496)
		(width 0.1651)
		(layer "In2.Cu")
		(net "PE_RX4_DR0_N")
	)
	(segment
		(start 10.185654 -431.092356)
		(end 8.684768 -430.041304)
		(width 0.1651)
		(layer "In2.Cu")
		(net "PE_RX4_DR0_N")
	)
	(segment
		(start 7.112 -429.763936)
		(end 5.308854 -429.763936)
		(width 0.1651)
		(layer "In2.Cu")
		(net "PE_RX4_DR0_N")
	)
	(arc
		(start 36.888166 -446.701418)
		(mid 36.755879 -446.812324)
		(end 36.644834 -446.944496)
		(width 0.1651)
		(layer "In2.Cu")
		(net "PE_RX4_DR0_N")
	)
	(segment
		(start 39.200074 -75.389994)
		(end 38.1 -75.389994)
		(width 0.174752)
		(layer "F.Cu")
		(net "PE_RX3_DR9_P")
	)
	(segment
		(start 37.133276 -75.142598)
		(end 36.72713 -75.548744)
		(width 0.174752)
		(layer "F.Cu")
		(net "PE_RX3_DR9_P")
	)
	(segment
		(start 37.852604 -75.142598)
		(end 37.133276 -75.142598)
		(width 0.174752)
		(layer "F.Cu")
		(net "PE_RX3_DR9_P")
	)
	(segment
		(start 38.1 -75.389994)
		(end 37.852604 -75.142598)
		(width 0.174752)
		(layer "F.Cu")
		(net "PE_RX3_DR9_P")
	)
	(via
		(at 5.08 -191.948308)
		(size 0.508)
		(drill 0.254)
		(layers "F.Cu" "B.Cu")
		(net "PE_RX3_DR9_P")
	)
	(via
		(at 36.72713 -75.548744)
		(size 0.508)
		(drill 0.254)
		(layers "F.Cu" "B.Cu")
		(net "PE_RX3_DR9_P")
	)
	(segment
		(start 3.657854 -191.942212)
		(end 3.905504 -191.694562)
		(width 0.174752)
		(layer "B.Cu")
		(net "PE_RX3_DR9_P")
	)
	(segment
		(start 1.868932 -191.942212)
		(end 3.657854 -191.942212)
		(width 0.174752)
		(layer "B.Cu")
		(net "PE_RX3_DR9_P")
	)
	(segment
		(start 3.905504 -191.694562)
		(end 4.826254 -191.694562)
		(width 0.174752)
		(layer "B.Cu")
		(net "PE_RX3_DR9_P")
	)
	(segment
		(start 4.826254 -191.694562)
		(end 5.08 -191.948308)
		(width 0.174752)
		(layer "B.Cu")
		(net "PE_RX3_DR9_P")
	)
	(segment
		(start 7.224268 -191.719962)
		(end 21.889974 -181.451504)
		(width 0.1651)
		(layer "In2.Cu")
		(net "PE_RX3_DR9_P")
	)
	(segment
		(start 43.079416 -101.743002)
		(end 40.294306 -99.793298)
		(width 0.1651)
		(layer "In2.Cu")
		(net "PE_RX3_DR9_P")
	)
	(segment
		(start 32.282892 -151.763222)
		(end 35.919156 -146.568414)
		(width 0.1651)
		(layer "In2.Cu")
		(net "PE_RX3_DR9_P")
	)
	(segment
		(start 23.205948 -95.667322)
		(end 21.546566 -93.297756)
		(width 0.1651)
		(layer "In2.Cu")
		(net "PE_RX3_DR9_P")
	)
	(segment
		(start 41.396158 -115.690142)
		(end 43.666664 -112.447324)
		(width 0.1651)
		(layer "In2.Cu")
		(net "PE_RX3_DR9_P")
	)
	(segment
		(start 29.640276 -76.498704)
		(end 31.035498 -75.927966)
		(width 0.1651)
		(layer "In2.Cu")
		(net "PE_RX3_DR9_P")
	)
	(segment
		(start 35.919156 -146.568414)
		(end 41.396158 -115.690142)
		(width 0.1651)
		(layer "In2.Cu")
		(net "PE_RX3_DR9_P")
	)
	(segment
		(start 28.785058 -171.604432)
		(end 32.282892 -151.763222)
		(width 0.1651)
		(layer "In2.Cu")
		(net "PE_RX3_DR9_P")
	)
	(segment
		(start 21.546566 -93.297756)
		(end 20.816062 -89.155016)
		(width 0.1651)
		(layer "In2.Cu")
		(net "PE_RX3_DR9_P")
	)
	(segment
		(start 40.294306 -99.793298)
		(end 25.333452 -97.157032)
		(width 0.1651)
		(layer "In2.Cu")
		(net "PE_RX3_DR9_P")
	)
	(segment
		(start 43.666664 -112.447324)
		(end 44.747434 -106.320336)
		(width 0.1651)
		(layer "In2.Cu")
		(net "PE_RX3_DR9_P")
	)
	(segment
		(start 44.23029 -103.387144)
		(end 43.079416 -101.743002)
		(width 0.1651)
		(layer "In2.Cu")
		(net "PE_RX3_DR9_P")
	)
	(segment
		(start 5.08 -191.948308)
		(end 5.308346 -191.719962)
		(width 0.1651)
		(layer "In2.Cu")
		(net "PE_RX3_DR9_P")
	)
	(segment
		(start 26.99893 -78.348332)
		(end 29.640276 -76.498704)
		(width 0.1651)
		(layer "In2.Cu")
		(net "PE_RX3_DR9_P")
	)
	(segment
		(start 25.333452 -97.157032)
		(end 23.205948 -95.667322)
		(width 0.1651)
		(layer "In2.Cu")
		(net "PE_RX3_DR9_P")
	)
	(segment
		(start 35.345116 -75.167998)
		(end 36.346384 -75.167998)
		(width 0.1651)
		(layer "In2.Cu")
		(net "PE_RX3_DR9_P")
	)
	(segment
		(start 5.308346 -191.719962)
		(end 7.224268 -191.719962)
		(width 0.1651)
		(layer "In2.Cu")
		(net "PE_RX3_DR9_P")
	)
	(segment
		(start 44.747434 -106.320336)
		(end 44.23029 -103.387144)
		(width 0.1651)
		(layer "In2.Cu")
		(net "PE_RX3_DR9_P")
	)
	(segment
		(start 36.346384 -75.167998)
		(end 36.72713 -75.548744)
		(width 0.1651)
		(layer "In2.Cu")
		(net "PE_RX3_DR9_P")
	)
	(segment
		(start 31.035498 -75.927966)
		(end 35.345116 -75.167998)
		(width 0.1651)
		(layer "In2.Cu")
		(net "PE_RX3_DR9_P")
	)
	(segment
		(start 21.889974 -181.451504)
		(end 28.785058 -171.604432)
		(width 0.1651)
		(layer "In2.Cu")
		(net "PE_RX3_DR9_P")
	)
	(segment
		(start 25.644602 -79.70266)
		(end 26.99893 -78.348332)
		(width 0.1651)
		(layer "In2.Cu")
		(net "PE_RX3_DR9_P")
	)
	(segment
		(start 20.816062 -89.155016)
		(end 21.41855 -85.737446)
		(width 0.1651)
		(layer "In2.Cu")
		(net "PE_RX3_DR9_P")
	)
	(segment
		(start 21.41855 -85.737446)
		(end 25.644602 -79.70266)
		(width 0.1651)
		(layer "In2.Cu")
		(net "PE_RX3_DR9_P")
	)
	(segment
		(start 37.846 -74.837544)
		(end 37.13353 -74.837544)
		(width 0.174752)
		(layer "F.Cu")
		(net "PE_RX3_DR9_N")
	)
	(segment
		(start 39.200074 -74.589894)
		(end 38.09365 -74.589894)
		(width 0.174752)
		(layer "F.Cu")
		(net "PE_RX3_DR9_N")
	)
	(segment
		(start 38.09365 -74.589894)
		(end 37.846 -74.837544)
		(width 0.174752)
		(layer "F.Cu")
		(net "PE_RX3_DR9_N")
	)
	(segment
		(start 37.13353 -74.837544)
		(end 36.72713 -74.431144)
		(width 0.174752)
		(layer "F.Cu")
		(net "PE_RX3_DR9_N")
	)
	(via
		(at 36.72713 -74.431144)
		(size 0.508)
		(drill 0.254)
		(layers "F.Cu" "B.Cu")
		(net "PE_RX3_DR9_N")
	)
	(via
		(at 5.08 -191.135508)
		(size 0.508)
		(drill 0.254)
		(layers "F.Cu" "B.Cu")
		(net "PE_RX3_DR9_N")
	)
	(segment
		(start 4.826 -191.389508)
		(end 5.08 -191.135508)
		(width 0.174752)
		(layer "B.Cu")
		(net "PE_RX3_DR9_N")
	)
	(segment
		(start 3.658108 -191.142112)
		(end 3.905504 -191.389508)
		(width 0.174752)
		(layer "B.Cu")
		(net "PE_RX3_DR9_N")
	)
	(segment
		(start 1.868932 -191.142112)
		(end 3.658108 -191.142112)
		(width 0.174752)
		(layer "B.Cu")
		(net "PE_RX3_DR9_N")
	)
	(segment
		(start 3.905504 -191.389508)
		(end 4.826 -191.389508)
		(width 0.174752)
		(layer "B.Cu")
		(net "PE_RX3_DR9_N")
	)
	(segment
		(start 20.465542 -89.093294)
		(end 21.082 -85.598)
		(width 0.1651)
		(layer "In2.Cu")
		(net "PE_RX3_DR9_N")
	)
	(segment
		(start 5.308854 -191.364362)
		(end 7.112 -191.364362)
		(width 0.1651)
		(layer "In2.Cu")
		(net "PE_RX3_DR9_N")
	)
	(segment
		(start 28.448508 -171.464986)
		(end 31.946342 -151.623776)
		(width 0.1651)
		(layer "In2.Cu")
		(net "PE_RX3_DR9_N")
	)
	(segment
		(start 43.330114 -112.307878)
		(end 44.386246 -106.320336)
		(width 0.1651)
		(layer "In2.Cu")
		(net "PE_RX3_DR9_N")
	)
	(segment
		(start 44.386246 -106.320336)
		(end 43.89374 -103.52659)
		(width 0.1651)
		(layer "In2.Cu")
		(net "PE_RX3_DR9_N")
	)
	(segment
		(start 7.112 -191.364362)
		(end 21.63445 -181.19598)
		(width 0.1651)
		(layer "In2.Cu")
		(net "PE_RX3_DR9_N")
	)
	(segment
		(start 20.454874 -89.155016)
		(end 20.465542 -89.093294)
		(width 0.1651)
		(layer "In2.Cu")
		(net "PE_RX3_DR9_N")
	)
	(segment
		(start 29.468826 -76.184506)
		(end 30.936184 -75.584304)
		(width 0.1651)
		(layer "In2.Cu")
		(net "PE_RX3_DR9_N")
	)
	(segment
		(start 40.15486 -100.129848)
		(end 25.194006 -97.493582)
		(width 0.1651)
		(layer "In2.Cu")
		(net "PE_RX3_DR9_N")
	)
	(segment
		(start 41.059608 -115.550696)
		(end 43.330114 -112.307878)
		(width 0.1651)
		(layer "In2.Cu")
		(net "PE_RX3_DR9_N")
	)
	(segment
		(start 21.082 -85.598)
		(end 25.371044 -79.473298)
		(width 0.1651)
		(layer "In2.Cu")
		(net "PE_RX3_DR9_N")
	)
	(segment
		(start 36.345876 -74.812398)
		(end 36.72713 -74.431144)
		(width 0.1651)
		(layer "In2.Cu")
		(net "PE_RX3_DR9_N")
	)
	(segment
		(start 43.89374 -103.52659)
		(end 42.823892 -101.998526)
		(width 0.1651)
		(layer "In2.Cu")
		(net "PE_RX3_DR9_N")
	)
	(segment
		(start 22.950424 -95.922846)
		(end 21.210016 -93.437202)
		(width 0.1651)
		(layer "In2.Cu")
		(net "PE_RX3_DR9_N")
	)
	(segment
		(start 31.946342 -151.623776)
		(end 35.582606 -146.428968)
		(width 0.1651)
		(layer "In2.Cu")
		(net "PE_RX3_DR9_N")
	)
	(segment
		(start 30.936184 -75.584304)
		(end 33.128458 -75.197716)
		(width 0.1651)
		(layer "In2.Cu")
		(net "PE_RX3_DR9_N")
	)
	(segment
		(start 21.63445 -181.19598)
		(end 28.448508 -171.464986)
		(width 0.1651)
		(layer "In2.Cu")
		(net "PE_RX3_DR9_N")
	)
	(segment
		(start 21.210016 -93.437202)
		(end 20.454874 -89.155016)
		(width 0.1651)
		(layer "In2.Cu")
		(net "PE_RX3_DR9_N")
	)
	(segment
		(start 25.194006 -97.493582)
		(end 22.950424 -95.922846)
		(width 0.1651)
		(layer "In2.Cu")
		(net "PE_RX3_DR9_N")
	)
	(segment
		(start 25.371044 -79.473298)
		(end 26.769568 -78.074774)
		(width 0.1651)
		(layer "In2.Cu")
		(net "PE_RX3_DR9_N")
	)
	(segment
		(start 5.08 -191.135508)
		(end 5.308854 -191.364362)
		(width 0.1651)
		(layer "In2.Cu")
		(net "PE_RX3_DR9_N")
	)
	(segment
		(start 42.823892 -101.998526)
		(end 40.15486 -100.129848)
		(width 0.1651)
		(layer "In2.Cu")
		(net "PE_RX3_DR9_N")
	)
	(segment
		(start 35.582606 -146.428968)
		(end 41.059608 -115.550696)
		(width 0.1651)
		(layer "In2.Cu")
		(net "PE_RX3_DR9_N")
	)
	(segment
		(start 33.128458 -75.197716)
		(end 35.313874 -74.812398)
		(width 0.1651)
		(layer "In2.Cu")
		(net "PE_RX3_DR9_N")
	)
	(segment
		(start 35.313874 -74.812398)
		(end 36.345876 -74.812398)
		(width 0.1651)
		(layer "In2.Cu")
		(net "PE_RX3_DR9_N")
	)
	(segment
		(start 26.769568 -78.074774)
		(end 29.468826 -76.184506)
		(width 0.1651)
		(layer "In2.Cu")
		(net "PE_RX3_DR9_N")
	)
	(segment
		(start 39.200074 -178.390042)
		(end 38.1 -178.390042)
		(width 0.174752)
		(layer "F.Cu")
		(net "PE_RX3_DR8_P")
	)
	(segment
		(start 37.852604 -178.142646)
		(end 37.133276 -178.142646)
		(width 0.174752)
		(layer "F.Cu")
		(net "PE_RX3_DR8_P")
	)
	(segment
		(start 37.133276 -178.142646)
		(end 36.72713 -178.548792)
		(width 0.174752)
		(layer "F.Cu")
		(net "PE_RX3_DR8_P")
	)
	(segment
		(start 38.1 -178.390042)
		(end 37.852604 -178.142646)
		(width 0.174752)
		(layer "F.Cu")
		(net "PE_RX3_DR8_P")
	)
	(via
		(at 5.08 -207.148176)
		(size 0.508)
		(drill 0.254)
		(layers "F.Cu" "B.Cu")
		(net "PE_RX3_DR8_P")
	)
	(via
		(at 36.72713 -178.548792)
		(size 0.508)
		(drill 0.254)
		(layers "F.Cu" "B.Cu")
		(net "PE_RX3_DR8_P")
	)
	(segment
		(start 3.658108 -207.14208)
		(end 3.905504 -206.894684)
		(width 0.174752)
		(layer "B.Cu")
		(net "PE_RX3_DR8_P")
	)
	(segment
		(start 4.826508 -206.894684)
		(end 5.08 -207.148176)
		(width 0.174752)
		(layer "B.Cu")
		(net "PE_RX3_DR8_P")
	)
	(segment
		(start 1.868932 -207.14208)
		(end 3.658108 -207.14208)
		(width 0.174752)
		(layer "B.Cu")
		(net "PE_RX3_DR8_P")
	)
	(segment
		(start 3.905504 -206.894684)
		(end 4.826508 -206.894684)
		(width 0.174752)
		(layer "B.Cu")
		(net "PE_RX3_DR8_P")
	)
	(segment
		(start 36.346384 -178.168046)
		(end 36.72713 -178.548792)
		(width 0.1651)
		(layer "In2.Cu")
		(net "PE_RX3_DR8_P")
	)
	(segment
		(start 34.027872 -178.400202)
		(end 34.149284 -178.378866)
		(width 0.1651)
		(layer "In2.Cu")
		(net "PE_RX3_DR8_P")
	)
	(segment
		(start 27.23261 -181.152546)
		(end 30.200346 -179.074572)
		(width 0.1651)
		(layer "In2.Cu")
		(net "PE_RX3_DR8_P")
	)
	(segment
		(start 30.200346 -179.074572)
		(end 32.357314 -178.694588)
		(width 0.1651)
		(layer "In2.Cu")
		(net "PE_RX3_DR8_P")
	)
	(segment
		(start 5.08 -207.148176)
		(end 5.308092 -206.920084)
		(width 0.1651)
		(layer "In2.Cu")
		(net "PE_RX3_DR8_P")
	)
	(segment
		(start 10.799572 -204.621892)
		(end 27.23261 -181.152546)
		(width 0.1651)
		(layer "In2.Cu")
		(net "PE_RX3_DR8_P")
	)
	(segment
		(start 34.149284 -178.378866)
		(end 35.345116 -178.168046)
		(width 0.1651)
		(layer "In2.Cu")
		(net "PE_RX3_DR8_P")
	)
	(segment
		(start 7.654544 -206.824326)
		(end 10.799572 -204.621892)
		(width 0.1651)
		(layer "In2.Cu")
		(net "PE_RX3_DR8_P")
	)
	(segment
		(start 7.112 -206.920084)
		(end 7.654544 -206.824326)
		(width 0.1651)
		(layer "In2.Cu")
		(net "PE_RX3_DR8_P")
	)
	(segment
		(start 35.345116 -178.168046)
		(end 36.346384 -178.168046)
		(width 0.1651)
		(layer "In2.Cu")
		(net "PE_RX3_DR8_P")
	)
	(segment
		(start 5.308092 -206.920084)
		(end 7.112 -206.920084)
		(width 0.1651)
		(layer "In2.Cu")
		(net "PE_RX3_DR8_P")
	)
	(segment
		(start 32.357314 -178.694588)
		(end 34.027872 -178.400202)
		(width 0.1651)
		(layer "In2.Cu")
		(net "PE_RX3_DR8_P")
	)
	(segment
		(start 39.200074 -177.589942)
		(end 38.1 -177.589942)
		(width 0.174752)
		(layer "F.Cu")
		(net "PE_RX3_DR8_N")
	)
	(segment
		(start 37.13353 -177.837592)
		(end 36.72713 -177.431192)
		(width 0.174752)
		(layer "F.Cu")
		(net "PE_RX3_DR8_N")
	)
	(segment
		(start 38.1 -177.589942)
		(end 37.85235 -177.837592)
		(width 0.174752)
		(layer "F.Cu")
		(net "PE_RX3_DR8_N")
	)
	(segment
		(start 37.85235 -177.837592)
		(end 37.13353 -177.837592)
		(width 0.174752)
		(layer "F.Cu")
		(net "PE_RX3_DR8_N")
	)
	(via
		(at 5.08 -206.335376)
		(size 0.508)
		(drill 0.254)
		(layers "F.Cu" "B.Cu")
		(net "PE_RX3_DR8_N")
	)
	(via
		(at 36.72713 -177.431192)
		(size 0.508)
		(drill 0.254)
		(layers "F.Cu" "B.Cu")
		(net "PE_RX3_DR8_N")
	)
	(segment
		(start 3.658108 -206.342234)
		(end 3.905504 -206.58963)
		(width 0.174752)
		(layer "B.Cu")
		(net "PE_RX3_DR8_N")
	)
	(segment
		(start 3.905504 -206.58963)
		(end 4.825746 -206.58963)
		(width 0.174752)
		(layer "B.Cu")
		(net "PE_RX3_DR8_N")
	)
	(segment
		(start 4.825746 -206.58963)
		(end 5.08 -206.335376)
		(width 0.174752)
		(layer "B.Cu")
		(net "PE_RX3_DR8_N")
	)
	(segment
		(start 1.868932 -206.342234)
		(end 3.658108 -206.342234)
		(width 0.174752)
		(layer "B.Cu")
		(net "PE_RX3_DR8_N")
	)
	(segment
		(start 5.08 -206.335376)
		(end 5.309108 -206.564484)
		(width 0.1651)
		(layer "In2.Cu")
		(net "PE_RX3_DR8_N")
	)
	(segment
		(start 35.313874 -177.812446)
		(end 36.345876 -177.812446)
		(width 0.1651)
		(layer "In2.Cu")
		(net "PE_RX3_DR8_N")
	)
	(segment
		(start 30.0609 -178.738022)
		(end 32.295592 -178.344322)
		(width 0.1651)
		(layer "In2.Cu")
		(net "PE_RX3_DR8_N")
	)
	(segment
		(start 32.295592 -178.344322)
		(end 34.087562 -178.0286)
		(width 0.1651)
		(layer "In2.Cu")
		(net "PE_RX3_DR8_N")
	)
	(segment
		(start 7.515098 -206.487776)
		(end 10.543794 -204.366876)
		(width 0.1651)
		(layer "In2.Cu")
		(net "PE_RX3_DR8_N")
	)
	(segment
		(start 36.345876 -177.812446)
		(end 36.72713 -177.431192)
		(width 0.1651)
		(layer "In2.Cu")
		(net "PE_RX3_DR8_N")
	)
	(segment
		(start 10.543794 -204.366876)
		(end 26.977086 -180.897022)
		(width 0.1651)
		(layer "In2.Cu")
		(net "PE_RX3_DR8_N")
	)
	(segment
		(start 34.087562 -178.0286)
		(end 35.313874 -177.812446)
		(width 0.1651)
		(layer "In2.Cu")
		(net "PE_RX3_DR8_N")
	)
	(segment
		(start 5.309108 -206.564484)
		(end 7.080758 -206.564484)
		(width 0.1651)
		(layer "In2.Cu")
		(net "PE_RX3_DR8_N")
	)
	(segment
		(start 7.080758 -206.564484)
		(end 7.515098 -206.487776)
		(width 0.1651)
		(layer "In2.Cu")
		(net "PE_RX3_DR8_N")
	)
	(segment
		(start 26.977086 -180.897022)
		(end 30.0609 -178.738022)
		(width 0.1651)
		(layer "In2.Cu")
		(net "PE_RX3_DR8_N")
	)
	(segment
		(start 39.200074 -281.39009)
		(end 38.1 -281.39009)
		(width 0.174752)
		(layer "F.Cu")
		(net "PE_RX3_DR7_P")
	)
	(segment
		(start 37.133276 -281.142694)
		(end 36.72713 -281.54884)
		(width 0.174752)
		(layer "F.Cu")
		(net "PE_RX3_DR7_P")
	)
	(segment
		(start 38.1 -281.39009)
		(end 37.852604 -281.142694)
		(width 0.174752)
		(layer "F.Cu")
		(net "PE_RX3_DR7_P")
	)
	(segment
		(start 37.852604 -281.142694)
		(end 37.133276 -281.142694)
		(width 0.174752)
		(layer "F.Cu")
		(net "PE_RX3_DR7_P")
	)
	(via
		(at 36.72713 -281.54884)
		(size 0.508)
		(drill 0.254)
		(layers "F.Cu" "B.Cu")
		(net "PE_RX3_DR7_P")
	)
	(via
		(at 5.08 -309.948326)
		(size 0.508)
		(drill 0.254)
		(layers "F.Cu" "B.Cu")
		(net "PE_RX3_DR7_P")
	)
	(segment
		(start 1.868932 -309.94223)
		(end 3.657854 -309.94223)
		(width 0.174752)
		(layer "B.Cu")
		(net "PE_RX3_DR7_P")
	)
	(segment
		(start 3.905504 -309.69458)
		(end 4.826254 -309.69458)
		(width 0.174752)
		(layer "B.Cu")
		(net "PE_RX3_DR7_P")
	)
	(segment
		(start 3.657854 -309.94223)
		(end 3.905504 -309.69458)
		(width 0.174752)
		(layer "B.Cu")
		(net "PE_RX3_DR7_P")
	)
	(segment
		(start 4.826254 -309.69458)
		(end 5.08 -309.948326)
		(width 0.174752)
		(layer "B.Cu")
		(net "PE_RX3_DR7_P")
	)
	(segment
		(start 8.586724 -309.459884)
		(end 7.112 -309.71998)
		(width 0.1651)
		(layer "In2.Cu")
		(net "PE_RX3_DR7_P")
	)
	(segment
		(start 24.843232 -287.604708)
		(end 10.45845 -308.149498)
		(width 0.1651)
		(layer "In2.Cu")
		(net "PE_RX3_DR7_P")
	)
	(segment
		(start 10.45845 -308.149498)
		(end 8.586724 -309.459884)
		(width 0.1651)
		(layer "In2.Cu")
		(net "PE_RX3_DR7_P")
	)
	(segment
		(start 7.112 -309.71998)
		(end 5.308346 -309.71998)
		(width 0.1651)
		(layer "In2.Cu")
		(net "PE_RX3_DR7_P")
	)
	(segment
		(start 33.583118 -281.484324)
		(end 24.843232 -287.604708)
		(width 0.1651)
		(layer "In2.Cu")
		(net "PE_RX3_DR7_P")
	)
	(segment
		(start 36.346384 -281.168094)
		(end 35.376358 -281.168094)
		(width 0.1651)
		(layer "In2.Cu")
		(net "PE_RX3_DR7_P")
	)
	(segment
		(start 35.376358 -281.168094)
		(end 33.583118 -281.484324)
		(width 0.1651)
		(layer "In2.Cu")
		(net "PE_RX3_DR7_P")
	)
	(segment
		(start 36.72713 -281.54884)
		(end 36.346384 -281.168094)
		(width 0.1651)
		(layer "In2.Cu")
		(net "PE_RX3_DR7_P")
	)
	(segment
		(start 5.308346 -309.71998)
		(end 5.08 -309.948326)
		(width 0.1651)
		(layer "In2.Cu")
		(net "PE_RX3_DR7_P")
	)
	(segment
		(start 37.85235 -280.83764)
		(end 37.13353 -280.83764)
		(width 0.174752)
		(layer "F.Cu")
		(net "PE_RX3_DR7_N")
	)
	(segment
		(start 39.200074 -280.58999)
		(end 38.1 -280.58999)
		(width 0.174752)
		(layer "F.Cu")
		(net "PE_RX3_DR7_N")
	)
	(segment
		(start 37.13353 -280.83764)
		(end 36.72713 -280.43124)
		(width 0.174752)
		(layer "F.Cu")
		(net "PE_RX3_DR7_N")
	)
	(segment
		(start 38.1 -280.58999)
		(end 37.85235 -280.83764)
		(width 0.174752)
		(layer "F.Cu")
		(net "PE_RX3_DR7_N")
	)
	(via
		(at 5.08 -309.135526)
		(size 0.508)
		(drill 0.254)
		(layers "F.Cu" "B.Cu")
		(net "PE_RX3_DR7_N")
	)
	(via
		(at 36.72713 -280.43124)
		(size 0.508)
		(drill 0.254)
		(layers "F.Cu" "B.Cu")
		(net "PE_RX3_DR7_N")
	)
	(segment
		(start 3.905504 -309.389526)
		(end 4.826 -309.389526)
		(width 0.174752)
		(layer "B.Cu")
		(net "PE_RX3_DR7_N")
	)
	(segment
		(start 1.868932 -309.14213)
		(end 3.658108 -309.14213)
		(width 0.174752)
		(layer "B.Cu")
		(net "PE_RX3_DR7_N")
	)
	(segment
		(start 3.658108 -309.14213)
		(end 3.905504 -309.389526)
		(width 0.174752)
		(layer "B.Cu")
		(net "PE_RX3_DR7_N")
	)
	(segment
		(start 4.826 -309.389526)
		(end 5.08 -309.135526)
		(width 0.174752)
		(layer "B.Cu")
		(net "PE_RX3_DR7_N")
	)
	(segment
		(start 33.443672 -281.147774)
		(end 24.587708 -287.349184)
		(width 0.1651)
		(layer "In2.Cu")
		(net "PE_RX3_DR7_N")
	)
	(segment
		(start 5.308854 -309.36438)
		(end 5.08 -309.135526)
		(width 0.1651)
		(layer "In2.Cu")
		(net "PE_RX3_DR7_N")
	)
	(segment
		(start 8.447278 -309.123334)
		(end 7.080758 -309.36438)
		(width 0.1651)
		(layer "In2.Cu")
		(net "PE_RX3_DR7_N")
	)
	(segment
		(start 7.080758 -309.36438)
		(end 5.308854 -309.36438)
		(width 0.1651)
		(layer "In2.Cu")
		(net "PE_RX3_DR7_N")
	)
	(segment
		(start 36.72713 -280.43124)
		(end 36.345876 -280.812494)
		(width 0.1651)
		(layer "In2.Cu")
		(net "PE_RX3_DR7_N")
	)
	(segment
		(start 10.202926 -307.893974)
		(end 8.447278 -309.123334)
		(width 0.1651)
		(layer "In2.Cu")
		(net "PE_RX3_DR7_N")
	)
	(segment
		(start 36.345876 -280.812494)
		(end 35.345116 -280.812494)
		(width 0.1651)
		(layer "In2.Cu")
		(net "PE_RX3_DR7_N")
	)
	(segment
		(start 24.587708 -287.349184)
		(end 10.202926 -307.893974)
		(width 0.1651)
		(layer "In2.Cu")
		(net "PE_RX3_DR7_N")
	)
	(segment
		(start 35.345116 -280.812494)
		(end 33.443672 -281.147774)
		(width 0.1651)
		(layer "In2.Cu")
		(net "PE_RX3_DR7_N")
	)
	(segment
		(start 38.1 -384.390138)
		(end 37.852604 -384.142742)
		(width 0.174752)
		(layer "F.Cu")
		(net "PE_RX3_DR6_P")
	)
	(segment
		(start 39.200074 -384.390138)
		(end 38.1 -384.390138)
		(width 0.174752)
		(layer "F.Cu")
		(net "PE_RX3_DR6_P")
	)
	(segment
		(start 37.852604 -384.142742)
		(end 37.133276 -384.142742)
		(width 0.174752)
		(layer "F.Cu")
		(net "PE_RX3_DR6_P")
	)
	(segment
		(start 37.133276 -384.142742)
		(end 36.72713 -384.548888)
		(width 0.174752)
		(layer "F.Cu")
		(net "PE_RX3_DR6_P")
	)
	(via
		(at 5.08 -355.548184)
		(size 0.508)
		(drill 0.254)
		(layers "F.Cu" "B.Cu")
		(net "PE_RX3_DR6_P")
	)
	(via
		(at 36.72713 -384.548888)
		(size 0.508)
		(drill 0.254)
		(layers "F.Cu" "B.Cu")
		(net "PE_RX3_DR6_P")
	)
	(segment
		(start 4.826254 -355.294438)
		(end 5.08 -355.548184)
		(width 0.174752)
		(layer "B.Cu")
		(net "PE_RX3_DR6_P")
	)
	(segment
		(start 3.657854 -355.542088)
		(end 3.905504 -355.294438)
		(width 0.174752)
		(layer "B.Cu")
		(net "PE_RX3_DR6_P")
	)
	(segment
		(start 1.868932 -355.542088)
		(end 3.657854 -355.542088)
		(width 0.174752)
		(layer "B.Cu")
		(net "PE_RX3_DR6_P")
	)
	(segment
		(start 3.905504 -355.294438)
		(end 4.826254 -355.294438)
		(width 0.174752)
		(layer "B.Cu")
		(net "PE_RX3_DR6_P")
	)
	(segment
		(start 12.483338 -358.450388)
		(end 11.555476 -357.125524)
		(width 0.1651)
		(layer "In2.Cu")
		(net "PE_RX3_DR6_P")
	)
	(segment
		(start 17.585944 -380.294896)
		(end 15.916402 -377.909836)
		(width 0.1651)
		(layer "In2.Cu")
		(net "PE_RX3_DR6_P")
	)
	(segment
		(start 35.313874 -384.168142)
		(end 34.087308 -383.951988)
		(width 0.1651)
		(layer "In2.Cu")
		(net "PE_RX3_DR6_P")
	)
	(segment
		(start 32.154622 -384.292856)
		(end 20.31365 -382.204468)
		(width 0.1651)
		(layer "In2.Cu")
		(net "PE_RX3_DR6_P")
	)
	(segment
		(start 34.087308 -383.951988)
		(end 32.154622 -384.292856)
		(width 0.1651)
		(layer "In2.Cu")
		(net "PE_RX3_DR6_P")
	)
	(segment
		(start 11.555476 -357.125524)
		(end 9.615932 -355.767132)
		(width 0.1651)
		(layer "In2.Cu")
		(net "PE_RX3_DR6_P")
	)
	(segment
		(start 36.72713 -384.548888)
		(end 36.346384 -384.168142)
		(width 0.1651)
		(layer "In2.Cu")
		(net "PE_RX3_DR6_P")
	)
	(segment
		(start 36.346384 -384.168142)
		(end 35.313874 -384.168142)
		(width 0.1651)
		(layer "In2.Cu")
		(net "PE_RX3_DR6_P")
	)
	(segment
		(start 9.615932 -355.767132)
		(end 7.080758 -355.319838)
		(width 0.1651)
		(layer "In2.Cu")
		(net "PE_RX3_DR6_P")
	)
	(segment
		(start 5.308346 -355.319838)
		(end 5.08 -355.548184)
		(width 0.1651)
		(layer "In2.Cu")
		(net "PE_RX3_DR6_P")
	)
	(segment
		(start 20.31365 -382.204468)
		(end 17.585944 -380.294896)
		(width 0.1651)
		(layer "In2.Cu")
		(net "PE_RX3_DR6_P")
	)
	(segment
		(start 15.916402 -377.909836)
		(end 12.483338 -358.450388)
		(width 0.1651)
		(layer "In2.Cu")
		(net "PE_RX3_DR6_P")
	)
	(segment
		(start 7.080758 -355.319838)
		(end 5.308346 -355.319838)
		(width 0.1651)
		(layer "In2.Cu")
		(net "PE_RX3_DR6_P")
	)
	(segment
		(start 38.1 -383.590038)
		(end 37.85235 -383.837688)
		(width 0.174752)
		(layer "F.Cu")
		(net "PE_RX3_DR6_N")
	)
	(segment
		(start 37.13353 -383.837688)
		(end 36.72713 -383.431288)
		(width 0.174752)
		(layer "F.Cu")
		(net "PE_RX3_DR6_N")
	)
	(segment
		(start 37.85235 -383.837688)
		(end 37.13353 -383.837688)
		(width 0.174752)
		(layer "F.Cu")
		(net "PE_RX3_DR6_N")
	)
	(segment
		(start 39.200074 -383.590038)
		(end 38.1 -383.590038)
		(width 0.174752)
		(layer "F.Cu")
		(net "PE_RX3_DR6_N")
	)
	(via
		(at 36.72713 -383.431288)
		(size 0.508)
		(drill 0.254)
		(layers "F.Cu" "B.Cu")
		(net "PE_RX3_DR6_N")
	)
	(via
		(at 5.08 -354.735384)
		(size 0.508)
		(drill 0.254)
		(layers "F.Cu" "B.Cu")
		(net "PE_RX3_DR6_N")
	)
	(segment
		(start 4.826 -354.989384)
		(end 5.08 -354.735384)
		(width 0.174752)
		(layer "B.Cu")
		(net "PE_RX3_DR6_N")
	)
	(segment
		(start 3.658108 -354.741988)
		(end 3.905504 -354.989384)
		(width 0.174752)
		(layer "B.Cu")
		(net "PE_RX3_DR6_N")
	)
	(segment
		(start 3.905504 -354.989384)
		(end 4.826 -354.989384)
		(width 0.174752)
		(layer "B.Cu")
		(net "PE_RX3_DR6_N")
	)
	(segment
		(start 1.868932 -354.741988)
		(end 3.658108 -354.741988)
		(width 0.174752)
		(layer "B.Cu")
		(net "PE_RX3_DR6_N")
	)
	(segment
		(start 11.811 -356.87)
		(end 9.755378 -355.430582)
		(width 0.1651)
		(layer "In2.Cu")
		(net "PE_RX3_DR6_N")
	)
	(segment
		(start 36.72713 -383.431288)
		(end 36.345876 -383.812542)
		(width 0.1651)
		(layer "In2.Cu")
		(net "PE_RX3_DR6_N")
	)
	(segment
		(start 9.755378 -355.430582)
		(end 7.112 -354.964238)
		(width 0.1651)
		(layer "In2.Cu")
		(net "PE_RX3_DR6_N")
	)
	(segment
		(start 34.087308 -383.5908)
		(end 32.154622 -383.931668)
		(width 0.1651)
		(layer "In2.Cu")
		(net "PE_RX3_DR6_N")
	)
	(segment
		(start 36.345876 -383.812542)
		(end 35.345116 -383.812542)
		(width 0.1651)
		(layer "In2.Cu")
		(net "PE_RX3_DR6_N")
	)
	(segment
		(start 7.112 -354.964238)
		(end 5.308854 -354.964238)
		(width 0.1651)
		(layer "In2.Cu")
		(net "PE_RX3_DR6_N")
	)
	(segment
		(start 16.252952 -377.77039)
		(end 12.819888 -358.310942)
		(width 0.1651)
		(layer "In2.Cu")
		(net "PE_RX3_DR6_N")
	)
	(segment
		(start 35.345116 -383.812542)
		(end 34.087308 -383.5908)
		(width 0.1651)
		(layer "In2.Cu")
		(net "PE_RX3_DR6_N")
	)
	(segment
		(start 20.453096 -381.867918)
		(end 17.841468 -380.039372)
		(width 0.1651)
		(layer "In2.Cu")
		(net "PE_RX3_DR6_N")
	)
	(segment
		(start 5.308854 -354.964238)
		(end 5.08 -354.735384)
		(width 0.1651)
		(layer "In2.Cu")
		(net "PE_RX3_DR6_N")
	)
	(segment
		(start 32.154622 -383.931668)
		(end 20.453096 -381.867918)
		(width 0.1651)
		(layer "In2.Cu")
		(net "PE_RX3_DR6_N")
	)
	(segment
		(start 17.841468 -380.039372)
		(end 16.252952 -377.77039)
		(width 0.1651)
		(layer "In2.Cu")
		(net "PE_RX3_DR6_N")
	)
	(segment
		(start 12.819888 -358.310942)
		(end 11.811 -356.87)
		(width 0.1651)
		(layer "In2.Cu")
		(net "PE_RX3_DR6_N")
	)
	(segment
		(start 39.200074 -486.590086)
		(end 37.973 -486.590086)
		(width 0.174752)
		(layer "F.Cu")
		(net "PE_RX3_DR5_P")
	)
	(segment
		(start 37.973 -486.590086)
		(end 37.72535 -486.837736)
		(width 0.174752)
		(layer "F.Cu")
		(net "PE_RX3_DR5_P")
	)
	(segment
		(start 37.13353 -486.837736)
		(end 36.72713 -486.431336)
		(width 0.174752)
		(layer "F.Cu")
		(net "PE_RX3_DR5_P")
	)
	(segment
		(start 37.72535 -486.837736)
		(end 37.13353 -486.837736)
		(width 0.174752)
		(layer "F.Cu")
		(net "PE_RX3_DR5_P")
	)
	(via
		(at 36.72713 -486.431336)
		(size 0.508)
		(drill 0.254)
		(layers "F.Cu" "B.Cu")
		(net "PE_RX3_DR5_P")
	)
	(via
		(at 5.08 -441.535312)
		(size 0.508)
		(drill 0.254)
		(layers "F.Cu" "B.Cu")
		(net "PE_RX3_DR5_P")
	)
	(segment
		(start 3.657854 -441.541916)
		(end 3.905504 -441.789566)
		(width 0.174752)
		(layer "B.Cu")
		(net "PE_RX3_DR5_P")
	)
	(segment
		(start 1.868932 -441.541916)
		(end 3.657854 -441.541916)
		(width 0.174752)
		(layer "B.Cu")
		(net "PE_RX3_DR5_P")
	)
	(segment
		(start 4.825746 -441.789566)
		(end 5.08 -441.535312)
		(width 0.174752)
		(layer "B.Cu")
		(net "PE_RX3_DR5_P")
	)
	(segment
		(start 3.905504 -441.789566)
		(end 4.825746 -441.789566)
		(width 0.174752)
		(layer "B.Cu")
		(net "PE_RX3_DR5_P")
	)
	(segment
		(start 9.483852 -443.82182)
		(end 8.439912 -442.331094)
		(width 0.1651)
		(layer "In2.Cu")
		(net "PE_RX3_DR5_P")
	)
	(segment
		(start 14.387068 -471.64117)
		(end 9.483852 -443.82182)
		(width 0.1651)
		(layer "In2.Cu")
		(net "PE_RX3_DR5_P")
	)
	(segment
		(start 36.345876 -486.81259)
		(end 35.345116 -486.81259)
		(width 0.1651)
		(layer "In2.Cu")
		(net "PE_RX3_DR5_P")
	)
	(segment
		(start 8.439912 -442.331094)
		(end 7.804658 -441.88634)
		(width 0.1651)
		(layer "In2.Cu")
		(net "PE_RX3_DR5_P")
	)
	(segment
		(start 35.345116 -486.81259)
		(end 26.869644 -485.318054)
		(width 0.1651)
		(layer "In2.Cu")
		(net "PE_RX3_DR5_P")
	)
	(segment
		(start 7.804658 -441.88634)
		(end 7.112 -441.764166)
		(width 0.1651)
		(layer "In2.Cu")
		(net "PE_RX3_DR5_P")
	)
	(segment
		(start 21.168868 -481.326444)
		(end 14.387068 -471.64117)
		(width 0.1651)
		(layer "In2.Cu")
		(net "PE_RX3_DR5_P")
	)
	(segment
		(start 26.869644 -485.318054)
		(end 21.168868 -481.326444)
		(width 0.1651)
		(layer "In2.Cu")
		(net "PE_RX3_DR5_P")
	)
	(segment
		(start 5.308854 -441.764166)
		(end 5.08 -441.535312)
		(width 0.1651)
		(layer "In2.Cu")
		(net "PE_RX3_DR5_P")
	)
	(segment
		(start 36.72713 -486.431336)
		(end 36.345876 -486.81259)
		(width 0.1651)
		(layer "In2.Cu")
		(net "PE_RX3_DR5_P")
	)
	(segment
		(start 7.112 -441.764166)
		(end 5.308854 -441.764166)
		(width 0.1651)
		(layer "In2.Cu")
		(net "PE_RX3_DR5_P")
	)
	(segment
		(start 37.133276 -487.14279)
		(end 36.72713 -487.548936)
		(width 0.174752)
		(layer "F.Cu")
		(net "PE_RX3_DR5_N")
	)
	(segment
		(start 37.725604 -487.14279)
		(end 37.133276 -487.14279)
		(width 0.174752)
		(layer "F.Cu")
		(net "PE_RX3_DR5_N")
	)
	(segment
		(start 39.200074 -487.390186)
		(end 37.973 -487.390186)
		(width 0.174752)
		(layer "F.Cu")
		(net "PE_RX3_DR5_N")
	)
	(segment
		(start 37.973 -487.390186)
		(end 37.725604 -487.14279)
		(width 0.174752)
		(layer "F.Cu")
		(net "PE_RX3_DR5_N")
	)
	(via
		(at 5.08 -442.348112)
		(size 0.508)
		(drill 0.254)
		(layers "F.Cu" "B.Cu")
		(net "PE_RX3_DR5_N")
	)
	(via
		(at 36.72713 -487.548936)
		(size 0.508)
		(drill 0.254)
		(layers "F.Cu" "B.Cu")
		(net "PE_RX3_DR5_N")
	)
	(segment
		(start 3.905504 -442.09462)
		(end 4.826508 -442.09462)
		(width 0.174752)
		(layer "B.Cu")
		(net "PE_RX3_DR5_N")
	)
	(segment
		(start 4.826508 -442.09462)
		(end 5.08 -442.348112)
		(width 0.174752)
		(layer "B.Cu")
		(net "PE_RX3_DR5_N")
	)
	(segment
		(start 3.658108 -442.342016)
		(end 3.905504 -442.09462)
		(width 0.174752)
		(layer "B.Cu")
		(net "PE_RX3_DR5_N")
	)
	(segment
		(start 1.868932 -442.342016)
		(end 3.658108 -442.342016)
		(width 0.174752)
		(layer "B.Cu")
		(net "PE_RX3_DR5_N")
	)
	(segment
		(start 36.72713 -487.548936)
		(end 36.346384 -487.16819)
		(width 0.1651)
		(layer "In2.Cu")
		(net "PE_RX3_DR5_N")
	)
	(segment
		(start 35.313874 -487.16819)
		(end 26.730198 -485.654604)
		(width 0.1651)
		(layer "In2.Cu")
		(net "PE_RX3_DR5_N")
	)
	(segment
		(start 36.346384 -487.16819)
		(end 35.313874 -487.16819)
		(width 0.1651)
		(layer "In2.Cu")
		(net "PE_RX3_DR5_N")
	)
	(segment
		(start 7.665212 -442.22289)
		(end 7.080758 -442.119766)
		(width 0.1651)
		(layer "In2.Cu")
		(net "PE_RX3_DR5_N")
	)
	(segment
		(start 20.913344 -481.581968)
		(end 14.050518 -471.780616)
		(width 0.1651)
		(layer "In2.Cu")
		(net "PE_RX3_DR5_N")
	)
	(segment
		(start 26.730198 -485.654604)
		(end 20.913344 -481.581968)
		(width 0.1651)
		(layer "In2.Cu")
		(net "PE_RX3_DR5_N")
	)
	(segment
		(start 9.147302 -443.961266)
		(end 8.184388 -442.586618)
		(width 0.1651)
		(layer "In2.Cu")
		(net "PE_RX3_DR5_N")
	)
	(segment
		(start 5.308346 -442.119766)
		(end 5.08 -442.348112)
		(width 0.1651)
		(layer "In2.Cu")
		(net "PE_RX3_DR5_N")
	)
	(segment
		(start 14.050518 -471.780616)
		(end 9.147302 -443.961266)
		(width 0.1651)
		(layer "In2.Cu")
		(net "PE_RX3_DR5_N")
	)
	(segment
		(start 8.184388 -442.586618)
		(end 7.665212 -442.22289)
		(width 0.1651)
		(layer "In2.Cu")
		(net "PE_RX3_DR5_N")
	)
	(segment
		(start 7.080758 -442.119766)
		(end 5.308346 -442.119766)
		(width 0.1651)
		(layer "In2.Cu")
		(net "PE_RX3_DR5_N")
	)
	(segment
		(start 222.885 -75.142598)
		(end 222.13316 -75.142598)
		(width 0.174752)
		(layer "F.Cu")
		(net "PE_RX3_DR4_P")
	)
	(segment
		(start 222.13316 -75.142598)
		(end 221.727014 -75.548744)
		(width 0.174752)
		(layer "F.Cu")
		(net "PE_RX3_DR4_P")
	)
	(segment
		(start 224.199958 -75.389994)
		(end 223.132396 -75.389994)
		(width 0.174752)
		(layer "F.Cu")
		(net "PE_RX3_DR4_P")
	)
	(segment
		(start 223.132396 -75.389994)
		(end 222.885 -75.142598)
		(width 0.174752)
		(layer "F.Cu")
		(net "PE_RX3_DR4_P")
	)
	(via
		(at 5.08 -281.148282)
		(size 0.508)
		(drill 0.254)
		(layers "F.Cu" "B.Cu")
		(net "PE_RX3_DR4_P")
	)
	(via
		(at 221.727014 -75.548744)
		(size 0.508)
		(drill 0.254)
		(layers "F.Cu" "B.Cu")
		(net "PE_RX3_DR4_P")
	)
	(segment
		(start 1.868932 -281.142186)
		(end 3.657854 -281.142186)
		(width 0.174752)
		(layer "B.Cu")
		(net "PE_RX3_DR4_P")
	)
	(segment
		(start 4.826254 -280.894536)
		(end 5.08 -281.148282)
		(width 0.174752)
		(layer "B.Cu")
		(net "PE_RX3_DR4_P")
	)
	(segment
		(start 3.657854 -281.142186)
		(end 3.905504 -280.894536)
		(width 0.174752)
		(layer "B.Cu")
		(net "PE_RX3_DR4_P")
	)
	(segment
		(start 3.905504 -280.894536)
		(end 4.826254 -280.894536)
		(width 0.174752)
		(layer "B.Cu")
		(net "PE_RX3_DR4_P")
	)
	(segment
		(start 221.727014 -75.548744)
		(end 221.346268 -75.167998)
		(width 0.1651)
		(layer "In2.Cu")
		(net "PE_RX3_DR4_P")
	)
	(segment
		(start 7.143242 -280.919936)
		(end 5.308346 -280.919936)
		(width 0.1651)
		(layer "In2.Cu")
		(net "PE_RX3_DR4_P")
	)
	(segment
		(start 220.345 -75.167998)
		(end 206.732886 -77.568552)
		(width 0.1651)
		(layer "In2.Cu")
		(net "PE_RX3_DR4_P")
	)
	(segment
		(start 23.647654 -269.997936)
		(end 21.919692 -272.4658)
		(width 0.1651)
		(layer "In2.Cu")
		(net "PE_RX3_DR4_P")
	)
	(segment
		(start 10.754614 -280.283158)
		(end 7.143242 -280.919936)
		(width 0.1651)
		(layer "In2.Cu")
		(net "PE_RX3_DR4_P")
	)
	(segment
		(start 221.346268 -75.167998)
		(end 220.345 -75.167998)
		(width 0.1651)
		(layer "In2.Cu")
		(net "PE_RX3_DR4_P")
	)
	(segment
		(start 26.025856 -256.515108)
		(end 23.647654 -269.997936)
		(width 0.1651)
		(layer "In2.Cu")
		(net "PE_RX3_DR4_P")
	)
	(segment
		(start 33.612074 -239.042448)
		(end 32.04718 -247.915176)
		(width 0.1651)
		(layer "In2.Cu")
		(net "PE_RX3_DR4_P")
	)
	(segment
		(start 32.04718 -247.915176)
		(end 26.025856 -256.515108)
		(width 0.1651)
		(layer "In2.Cu")
		(net "PE_RX3_DR4_P")
	)
	(segment
		(start 21.919692 -272.4658)
		(end 10.754614 -280.283158)
		(width 0.1651)
		(layer "In2.Cu")
		(net "PE_RX3_DR4_P")
	)
	(segment
		(start 206.732886 -77.568552)
		(end 88.909398 -160.070546)
		(width 0.1651)
		(layer "In2.Cu")
		(net "PE_RX3_DR4_P")
	)
	(segment
		(start 88.909398 -160.070546)
		(end 33.612074 -239.042448)
		(width 0.1651)
		(layer "In2.Cu")
		(net "PE_RX3_DR4_P")
	)
	(segment
		(start 5.308346 -280.919936)
		(end 5.08 -281.148282)
		(width 0.1651)
		(layer "In2.Cu")
		(net "PE_RX3_DR4_P")
	)
	(segment
		(start 222.89135 -74.837544)
		(end 222.133414 -74.837544)
		(width 0.174752)
		(layer "F.Cu")
		(net "PE_RX3_DR4_N")
	)
	(segment
		(start 222.133414 -74.837544)
		(end 221.727014 -74.431144)
		(width 0.174752)
		(layer "F.Cu")
		(net "PE_RX3_DR4_N")
	)
	(segment
		(start 224.199958 -74.589894)
		(end 223.139 -74.589894)
		(width 0.174752)
		(layer "F.Cu")
		(net "PE_RX3_DR4_N")
	)
	(segment
		(start 223.139 -74.589894)
		(end 222.89135 -74.837544)
		(width 0.174752)
		(layer "F.Cu")
		(net "PE_RX3_DR4_N")
	)
	(via
		(at 5.08 -280.335482)
		(size 0.508)
		(drill 0.254)
		(layers "F.Cu" "B.Cu")
		(net "PE_RX3_DR4_N")
	)
	(via
		(at 221.727014 -74.431144)
		(size 0.508)
		(drill 0.254)
		(layers "F.Cu" "B.Cu")
		(net "PE_RX3_DR4_N")
	)
	(segment
		(start 3.905504 -280.589482)
		(end 4.826 -280.589482)
		(width 0.174752)
		(layer "B.Cu")
		(net "PE_RX3_DR4_N")
	)
	(segment
		(start 4.826 -280.589482)
		(end 5.08 -280.335482)
		(width 0.174752)
		(layer "B.Cu")
		(net "PE_RX3_DR4_N")
	)
	(segment
		(start 1.868932 -280.342086)
		(end 3.658108 -280.342086)
		(width 0.174752)
		(layer "B.Cu")
		(net "PE_RX3_DR4_N")
	)
	(segment
		(start 3.658108 -280.342086)
		(end 3.905504 -280.589482)
		(width 0.174752)
		(layer "B.Cu")
		(net "PE_RX3_DR4_N")
	)
	(segment
		(start 5.308854 -280.564336)
		(end 5.08 -280.335482)
		(width 0.1651)
		(layer "In2.Cu")
		(net "PE_RX3_DR4_N")
	)
	(segment
		(start 220.313758 -74.812398)
		(end 206.59344 -77.232002)
		(width 0.1651)
		(layer "In2.Cu")
		(net "PE_RX3_DR4_N")
	)
	(segment
		(start 221.727014 -74.431144)
		(end 221.34576 -74.812398)
		(width 0.1651)
		(layer "In2.Cu")
		(net "PE_RX3_DR4_N")
	)
	(segment
		(start 221.34576 -74.812398)
		(end 220.313758 -74.812398)
		(width 0.1651)
		(layer "In2.Cu")
		(net "PE_RX3_DR4_N")
	)
	(segment
		(start 88.653874 -159.815022)
		(end 33.275524 -238.903002)
		(width 0.1651)
		(layer "In2.Cu")
		(net "PE_RX3_DR4_N")
	)
	(segment
		(start 10.615168 -279.946354)
		(end 7.112 -280.564336)
		(width 0.1651)
		(layer "In2.Cu")
		(net "PE_RX3_DR4_N")
	)
	(segment
		(start 23.311104 -269.858236)
		(end 21.664422 -272.210276)
		(width 0.1651)
		(layer "In2.Cu")
		(net "PE_RX3_DR4_N")
	)
	(segment
		(start 7.112 -280.564336)
		(end 5.308854 -280.564336)
		(width 0.1651)
		(layer "In2.Cu")
		(net "PE_RX3_DR4_N")
	)
	(segment
		(start 206.59344 -77.232002)
		(end 88.653874 -159.815022)
		(width 0.1651)
		(layer "In2.Cu")
		(net "PE_RX3_DR4_N")
	)
	(segment
		(start 31.71063 -247.77573)
		(end 25.689306 -256.375662)
		(width 0.1651)
		(layer "In2.Cu")
		(net "PE_RX3_DR4_N")
	)
	(segment
		(start 33.275524 -238.903002)
		(end 31.71063 -247.77573)
		(width 0.1651)
		(layer "In2.Cu")
		(net "PE_RX3_DR4_N")
	)
	(segment
		(start 21.664422 -272.210276)
		(end 10.615168 -279.946354)
		(width 0.1651)
		(layer "In2.Cu")
		(net "PE_RX3_DR4_N")
	)
	(segment
		(start 25.689306 -256.375662)
		(end 23.311104 -269.858236)
		(width 0.1651)
		(layer "In2.Cu")
		(net "PE_RX3_DR4_N")
	)
	(segment
		(start 223.139 -178.390042)
		(end 222.891604 -178.142646)
		(width 0.174752)
		(layer "F.Cu")
		(net "PE_RX3_DR3_P")
	)
	(segment
		(start 222.891604 -178.142646)
		(end 222.13316 -178.142646)
		(width 0.174752)
		(layer "F.Cu")
		(net "PE_RX3_DR3_P")
	)
	(segment
		(start 222.13316 -178.142646)
		(end 221.727014 -178.548792)
		(width 0.174752)
		(layer "F.Cu")
		(net "PE_RX3_DR3_P")
	)
	(segment
		(start 224.199958 -178.390042)
		(end 223.139 -178.390042)
		(width 0.174752)
		(layer "F.Cu")
		(net "PE_RX3_DR3_P")
	)
	(via
		(at 221.727014 -178.548792)
		(size 0.508)
		(drill 0.254)
		(layers "F.Cu" "B.Cu")
		(net "PE_RX3_DR3_P")
	)
	(via
		(at 5.08 -297.14825)
		(size 0.508)
		(drill 0.254)
		(layers "F.Cu" "B.Cu")
		(net "PE_RX3_DR3_P")
	)
	(segment
		(start 1.868932 -297.142154)
		(end 3.657854 -297.142154)
		(width 0.174752)
		(layer "B.Cu")
		(net "PE_RX3_DR3_P")
	)
	(segment
		(start 3.657854 -297.142154)
		(end 3.905504 -296.894504)
		(width 0.174752)
		(layer "B.Cu")
		(net "PE_RX3_DR3_P")
	)
	(segment
		(start 4.826254 -296.894504)
		(end 5.08 -297.14825)
		(width 0.174752)
		(layer "B.Cu")
		(net "PE_RX3_DR3_P")
	)
	(segment
		(start 3.905504 -296.894504)
		(end 4.826254 -296.894504)
		(width 0.174752)
		(layer "B.Cu")
		(net "PE_RX3_DR3_P")
	)
	(segment
		(start 31.23057 -256.26568)
		(end 28.049982 -274.296632)
		(width 0.1651)
		(layer "In2.Cu")
		(net "PE_RX3_DR3_P")
	)
	(segment
		(start 10.656824 -295.237662)
		(end 8.491728 -296.753788)
		(width 0.1651)
		(layer "In2.Cu")
		(net "PE_RX3_DR3_P")
	)
	(segment
		(start 35.927792 -249.55754)
		(end 35.883342 -249.621294)
		(width 0.1651)
		(layer "In2.Cu")
		(net "PE_RX3_DR3_P")
	)
	(segment
		(start 213.484968 -179.620164)
		(end 192.804288 -175.973232)
		(width 0.1651)
		(layer "In2.Cu")
		(net "PE_RX3_DR3_P")
	)
	(segment
		(start 7.55142 -296.919904)
		(end 5.308346 -296.919904)
		(width 0.1651)
		(layer "In2.Cu")
		(net "PE_RX3_DR3_P")
	)
	(segment
		(start 35.883342 -249.62104)
		(end 31.23057 -256.26568)
		(width 0.1651)
		(layer "In2.Cu")
		(net "PE_RX3_DR3_P")
	)
	(segment
		(start 221.727014 -178.548792)
		(end 221.346268 -178.168046)
		(width 0.1651)
		(layer "In2.Cu")
		(net "PE_RX3_DR3_P")
	)
	(segment
		(start 14.557248 -293.563802)
		(end 12.62126 -294.820594)
		(width 0.1651)
		(layer "In2.Cu")
		(net "PE_RX3_DR3_P")
	)
	(segment
		(start 8.491728 -296.753788)
		(end 7.55142 -296.919904)
		(width 0.1651)
		(layer "In2.Cu")
		(net "PE_RX3_DR3_P")
	)
	(segment
		(start 28.049982 -274.296632)
		(end 28.049982 -274.296886)
		(width 0.1651)
		(layer "In2.Cu")
		(net "PE_RX3_DR3_P")
	)
	(segment
		(start 56.131968 -213.793832)
		(end 37.555678 -240.317528)
		(width 0.1651)
		(layer "In2.Cu")
		(net "PE_RX3_DR3_P")
	)
	(segment
		(start 35.883342 -249.621294)
		(end 35.883342 -249.62104)
		(width 0.1651)
		(layer "In2.Cu")
		(net "PE_RX3_DR3_P")
	)
	(segment
		(start 221.346268 -178.168046)
		(end 220.314266 -178.168046)
		(width 0.1651)
		(layer "In2.Cu")
		(net "PE_RX3_DR3_P")
	)
	(segment
		(start 192.804288 -175.973232)
		(end 82.338164 -195.443348)
		(width 0.1651)
		(layer "In2.Cu")
		(net "PE_RX3_DR3_P")
	)
	(segment
		(start 12.62126 -294.820594)
		(end 10.656824 -295.237662)
		(width 0.1651)
		(layer "In2.Cu")
		(net "PE_RX3_DR3_P")
	)
	(segment
		(start 82.338164 -195.443348)
		(end 56.131968 -213.793832)
		(width 0.1651)
		(layer "In2.Cu")
		(net "PE_RX3_DR3_P")
	)
	(segment
		(start 37.555678 -240.317528)
		(end 35.927792 -249.55754)
		(width 0.1651)
		(layer "In2.Cu")
		(net "PE_RX3_DR3_P")
	)
	(segment
		(start 28.049982 -274.296886)
		(end 14.557248 -293.563802)
		(width 0.1651)
		(layer "In2.Cu")
		(net "PE_RX3_DR3_P")
	)
	(segment
		(start 5.308346 -296.919904)
		(end 5.08 -297.14825)
		(width 0.1651)
		(layer "In2.Cu")
		(net "PE_RX3_DR3_P")
	)
	(segment
		(start 220.314266 -178.168046)
		(end 213.484968 -179.620164)
		(width 0.1651)
		(layer "In2.Cu")
		(net "PE_RX3_DR3_P")
	)
	(segment
		(start 224.199958 -177.589942)
		(end 223.139 -177.589942)
		(width 0.174752)
		(layer "F.Cu")
		(net "PE_RX3_DR3_N")
	)
	(segment
		(start 222.89135 -177.837592)
		(end 222.133414 -177.837592)
		(width 0.174752)
		(layer "F.Cu")
		(net "PE_RX3_DR3_N")
	)
	(segment
		(start 223.139 -177.589942)
		(end 222.89135 -177.837592)
		(width 0.174752)
		(layer "F.Cu")
		(net "PE_RX3_DR3_N")
	)
	(segment
		(start 222.133414 -177.837592)
		(end 221.727014 -177.431192)
		(width 0.174752)
		(layer "F.Cu")
		(net "PE_RX3_DR3_N")
	)
	(via
		(at 5.08 -296.33545)
		(size 0.508)
		(drill 0.254)
		(layers "F.Cu" "B.Cu")
		(net "PE_RX3_DR3_N")
	)
	(via
		(at 221.727014 -177.431192)
		(size 0.508)
		(drill 0.254)
		(layers "F.Cu" "B.Cu")
		(net "PE_RX3_DR3_N")
	)
	(segment
		(start 3.658108 -296.342054)
		(end 3.905504 -296.58945)
		(width 0.174752)
		(layer "B.Cu")
		(net "PE_RX3_DR3_N")
	)
	(segment
		(start 1.868932 -296.342054)
		(end 3.658108 -296.342054)
		(width 0.174752)
		(layer "B.Cu")
		(net "PE_RX3_DR3_N")
	)
	(segment
		(start 4.826 -296.58945)
		(end 5.08 -296.33545)
		(width 0.174752)
		(layer "B.Cu")
		(net "PE_RX3_DR3_N")
	)
	(segment
		(start 3.905504 -296.58945)
		(end 4.826 -296.58945)
		(width 0.174752)
		(layer "B.Cu")
		(net "PE_RX3_DR3_N")
	)
	(segment
		(start 37.219128 -240.178082)
		(end 35.591242 -249.418094)
		(width 0.1651)
		(layer "In2.Cu")
		(net "PE_RX3_DR3_N")
	)
	(segment
		(start 82.198718 -195.106798)
		(end 55.876444 -213.538308)
		(width 0.1651)
		(layer "In2.Cu")
		(net "PE_RX3_DR3_N")
	)
	(segment
		(start 27.713178 -274.157186)
		(end 27.713432 -274.157186)
		(width 0.1651)
		(layer "In2.Cu")
		(net "PE_RX3_DR3_N")
	)
	(segment
		(start 221.727014 -177.431192)
		(end 221.34576 -177.812446)
		(width 0.1651)
		(layer "In2.Cu")
		(net "PE_RX3_DR3_N")
	)
	(segment
		(start 7.520178 -296.564304)
		(end 5.308854 -296.564304)
		(width 0.1651)
		(layer "In2.Cu")
		(net "PE_RX3_DR3_N")
	)
	(segment
		(start 5.308854 -296.564304)
		(end 5.08 -296.33545)
		(width 0.1651)
		(layer "In2.Cu")
		(net "PE_RX3_DR3_N")
	)
	(segment
		(start 11.565382 -294.681148)
		(end 10.512044 -294.904668)
		(width 0.1651)
		(layer "In2.Cu")
		(net "PE_RX3_DR3_N")
	)
	(segment
		(start 12.48283 -294.48633)
		(end 11.565382 -294.681148)
		(width 0.1651)
		(layer "In2.Cu")
		(net "PE_RX3_DR3_N")
	)
	(segment
		(start 220.276674 -177.812446)
		(end 213.478618 -179.257706)
		(width 0.1651)
		(layer "In2.Cu")
		(net "PE_RX3_DR3_N")
	)
	(segment
		(start 10.512044 -294.904668)
		(end 8.352282 -296.417238)
		(width 0.1651)
		(layer "In2.Cu")
		(net "PE_RX3_DR3_N")
	)
	(segment
		(start 35.591242 -249.418094)
		(end 35.589718 -249.42038)
		(width 0.1651)
		(layer "In2.Cu")
		(net "PE_RX3_DR3_N")
	)
	(segment
		(start 192.804288 -175.612044)
		(end 82.198718 -195.106798)
		(width 0.1651)
		(layer "In2.Cu")
		(net "PE_RX3_DR3_N")
	)
	(segment
		(start 213.478618 -179.257706)
		(end 192.804288 -175.612044)
		(width 0.1651)
		(layer "In2.Cu")
		(net "PE_RX3_DR3_N")
	)
	(segment
		(start 221.34576 -177.812446)
		(end 220.276674 -177.812446)
		(width 0.1651)
		(layer "In2.Cu")
		(net "PE_RX3_DR3_N")
	)
	(segment
		(start 35.589718 -249.42038)
		(end 30.89402 -256.126234)
		(width 0.1651)
		(layer "In2.Cu")
		(net "PE_RX3_DR3_N")
	)
	(segment
		(start 8.352282 -296.417238)
		(end 7.520178 -296.564304)
		(width 0.1651)
		(layer "In2.Cu")
		(net "PE_RX3_DR3_N")
	)
	(segment
		(start 27.713432 -274.157186)
		(end 14.306042 -293.302436)
		(width 0.1651)
		(layer "In2.Cu")
		(net "PE_RX3_DR3_N")
	)
	(segment
		(start 14.306042 -293.302436)
		(end 12.48283 -294.48633)
		(width 0.1651)
		(layer "In2.Cu")
		(net "PE_RX3_DR3_N")
	)
	(segment
		(start 30.89402 -256.126234)
		(end 27.713178 -274.157186)
		(width 0.1651)
		(layer "In2.Cu")
		(net "PE_RX3_DR3_N")
	)
	(segment
		(start 55.876444 -213.538308)
		(end 37.219128 -240.178082)
		(width 0.1651)
		(layer "In2.Cu")
		(net "PE_RX3_DR3_N")
	)
	(segment
		(start 222.13316 -281.142694)
		(end 221.727014 -281.54884)
		(width 0.174752)
		(layer "F.Cu")
		(net "PE_RX3_DR2_P")
	)
	(segment
		(start 224.199958 -281.39009)
		(end 223.132396 -281.39009)
		(width 0.174752)
		(layer "F.Cu")
		(net "PE_RX3_DR2_P")
	)
	(segment
		(start 222.885 -281.142694)
		(end 222.13316 -281.142694)
		(width 0.174752)
		(layer "F.Cu")
		(net "PE_RX3_DR2_P")
	)
	(segment
		(start 223.132396 -281.39009)
		(end 222.885 -281.142694)
		(width 0.174752)
		(layer "F.Cu")
		(net "PE_RX3_DR2_P")
	)
	(via
		(at 5.08 -327.54824)
		(size 0.508)
		(drill 0.254)
		(layers "F.Cu" "B.Cu")
		(net "PE_RX3_DR2_P")
	)
	(via
		(at 221.727014 -281.54884)
		(size 0.508)
		(drill 0.254)
		(layers "F.Cu" "B.Cu")
		(net "PE_RX3_DR2_P")
	)
	(segment
		(start 4.826254 -327.294494)
		(end 5.08 -327.54824)
		(width 0.174752)
		(layer "B.Cu")
		(net "PE_RX3_DR2_P")
	)
	(segment
		(start 1.868932 -327.542144)
		(end 3.657854 -327.542144)
		(width 0.174752)
		(layer "B.Cu")
		(net "PE_RX3_DR2_P")
	)
	(segment
		(start 3.905504 -327.294494)
		(end 4.826254 -327.294494)
		(width 0.174752)
		(layer "B.Cu")
		(net "PE_RX3_DR2_P")
	)
	(segment
		(start 3.657854 -327.542144)
		(end 3.905504 -327.294494)
		(width 0.174752)
		(layer "B.Cu")
		(net "PE_RX3_DR2_P")
	)
	(segment
		(start 7.112 -327.319894)
		(end 5.308346 -327.319894)
		(width 0.1651)
		(layer "In2.Cu")
		(net "PE_RX3_DR2_P")
	)
	(segment
		(start 15.736062 -308.230778)
		(end 13.136626 -322.97243)
		(width 0.1651)
		(layer "In2.Cu")
		(net "PE_RX3_DR2_P")
	)
	(segment
		(start 39.03472 -306.160932)
		(end 23.114254 -303.35347)
		(width 0.1651)
		(layer "In2.Cu")
		(net "PE_RX3_DR2_P")
	)
	(segment
		(start 11.651488 -325.093584)
		(end 8.930132 -326.999346)
		(width 0.1651)
		(layer "In2.Cu")
		(net "PE_RX3_DR2_P")
	)
	(segment
		(start 221.727014 -281.54884)
		(end 221.346268 -281.168094)
		(width 0.1651)
		(layer "In2.Cu")
		(net "PE_RX3_DR2_P")
	)
	(segment
		(start 45.935138 -304.944018)
		(end 39.03472 -306.160932)
		(width 0.1651)
		(layer "In2.Cu")
		(net "PE_RX3_DR2_P")
	)
	(segment
		(start 67.575938 -289.791394)
		(end 45.935138 -304.944018)
		(width 0.1651)
		(layer "In2.Cu")
		(net "PE_RX3_DR2_P")
	)
	(segment
		(start 16.892524 -306.579524)
		(end 15.736062 -308.230778)
		(width 0.1651)
		(layer "In2.Cu")
		(net "PE_RX3_DR2_P")
	)
	(segment
		(start 13.136626 -322.97243)
		(end 11.651488 -325.093584)
		(width 0.1651)
		(layer "In2.Cu")
		(net "PE_RX3_DR2_P")
	)
	(segment
		(start 221.346268 -281.168094)
		(end 220.313758 -281.168094)
		(width 0.1651)
		(layer "In2.Cu")
		(net "PE_RX3_DR2_P")
	)
	(segment
		(start 23.114254 -303.35347)
		(end 20.95627 -303.733708)
		(width 0.1651)
		(layer "In2.Cu")
		(net "PE_RX3_DR2_P")
	)
	(segment
		(start 5.308346 -327.319894)
		(end 5.08 -327.54824)
		(width 0.1651)
		(layer "In2.Cu")
		(net "PE_RX3_DR2_P")
	)
	(segment
		(start 20.95627 -303.733708)
		(end 16.892524 -306.579524)
		(width 0.1651)
		(layer "In2.Cu")
		(net "PE_RX3_DR2_P")
	)
	(segment
		(start 168.398698 -272.014188)
		(end 67.575938 -289.791394)
		(width 0.1651)
		(layer "In2.Cu")
		(net "PE_RX3_DR2_P")
	)
	(segment
		(start 8.930132 -326.999346)
		(end 7.112 -327.319894)
		(width 0.1651)
		(layer "In2.Cu")
		(net "PE_RX3_DR2_P")
	)
	(segment
		(start 220.313758 -281.168094)
		(end 168.398698 -272.014188)
		(width 0.1651)
		(layer "In2.Cu")
		(net "PE_RX3_DR2_P")
	)
	(segment
		(start 222.133414 -280.83764)
		(end 221.727014 -280.43124)
		(width 0.174752)
		(layer "F.Cu")
		(net "PE_RX3_DR2_N")
	)
	(segment
		(start 224.199958 -280.58999)
		(end 223.139 -280.58999)
		(width 0.174752)
		(layer "F.Cu")
		(net "PE_RX3_DR2_N")
	)
	(segment
		(start 223.139 -280.58999)
		(end 222.89135 -280.83764)
		(width 0.174752)
		(layer "F.Cu")
		(net "PE_RX3_DR2_N")
	)
	(segment
		(start 222.89135 -280.83764)
		(end 222.133414 -280.83764)
		(width 0.174752)
		(layer "F.Cu")
		(net "PE_RX3_DR2_N")
	)
	(via
		(at 221.727014 -280.43124)
		(size 0.508)
		(drill 0.254)
		(layers "F.Cu" "B.Cu")
		(net "PE_RX3_DR2_N")
	)
	(via
		(at 5.08 -326.73544)
		(size 0.508)
		(drill 0.254)
		(layers "F.Cu" "B.Cu")
		(net "PE_RX3_DR2_N")
	)
	(segment
		(start 3.905504 -326.98944)
		(end 4.826 -326.98944)
		(width 0.174752)
		(layer "B.Cu")
		(net "PE_RX3_DR2_N")
	)
	(segment
		(start 3.658108 -326.742044)
		(end 3.905504 -326.98944)
		(width 0.174752)
		(layer "B.Cu")
		(net "PE_RX3_DR2_N")
	)
	(segment
		(start 1.868932 -326.742044)
		(end 3.658108 -326.742044)
		(width 0.174752)
		(layer "B.Cu")
		(net "PE_RX3_DR2_N")
	)
	(segment
		(start 4.826 -326.98944)
		(end 5.08 -326.73544)
		(width 0.174752)
		(layer "B.Cu")
		(net "PE_RX3_DR2_N")
	)
	(segment
		(start 39.03472 -305.799744)
		(end 23.114254 -302.992282)
		(width 0.1651)
		(layer "In2.Cu")
		(net "PE_RX3_DR2_N")
	)
	(segment
		(start 5.308854 -326.964294)
		(end 5.08 -326.73544)
		(width 0.1651)
		(layer "In2.Cu")
		(net "PE_RX3_DR2_N")
	)
	(segment
		(start 15.399512 -308.091332)
		(end 12.800076 -322.832984)
		(width 0.1651)
		(layer "In2.Cu")
		(net "PE_RX3_DR2_N")
	)
	(segment
		(start 7.080758 -326.964294)
		(end 5.308854 -326.964294)
		(width 0.1651)
		(layer "In2.Cu")
		(net "PE_RX3_DR2_N")
	)
	(segment
		(start 221.34576 -280.812494)
		(end 220.345 -280.812494)
		(width 0.1651)
		(layer "In2.Cu")
		(net "PE_RX3_DR2_N")
	)
	(segment
		(start 20.816824 -303.397158)
		(end 16.637 -306.324)
		(width 0.1651)
		(layer "In2.Cu")
		(net "PE_RX3_DR2_N")
	)
	(segment
		(start 220.345 -280.812494)
		(end 168.398698 -271.653)
		(width 0.1651)
		(layer "In2.Cu")
		(net "PE_RX3_DR2_N")
	)
	(segment
		(start 67.436492 -289.454844)
		(end 45.795692 -304.607468)
		(width 0.1651)
		(layer "In2.Cu")
		(net "PE_RX3_DR2_N")
	)
	(segment
		(start 221.727014 -280.43124)
		(end 221.34576 -280.812494)
		(width 0.1651)
		(layer "In2.Cu")
		(net "PE_RX3_DR2_N")
	)
	(segment
		(start 12.800076 -322.832984)
		(end 11.395964 -324.83806)
		(width 0.1651)
		(layer "In2.Cu")
		(net "PE_RX3_DR2_N")
	)
	(segment
		(start 16.637 -306.324)
		(end 15.399512 -308.091332)
		(width 0.1651)
		(layer "In2.Cu")
		(net "PE_RX3_DR2_N")
	)
	(segment
		(start 11.395964 -324.83806)
		(end 8.790686 -326.662796)
		(width 0.1651)
		(layer "In2.Cu")
		(net "PE_RX3_DR2_N")
	)
	(segment
		(start 168.398698 -271.653)
		(end 67.436492 -289.454844)
		(width 0.1651)
		(layer "In2.Cu")
		(net "PE_RX3_DR2_N")
	)
	(segment
		(start 8.790686 -326.662796)
		(end 7.080758 -326.964294)
		(width 0.1651)
		(layer "In2.Cu")
		(net "PE_RX3_DR2_N")
	)
	(segment
		(start 45.795692 -304.607468)
		(end 39.03472 -305.799744)
		(width 0.1651)
		(layer "In2.Cu")
		(net "PE_RX3_DR2_N")
	)
	(segment
		(start 23.114254 -302.992282)
		(end 20.816824 -303.397158)
		(width 0.1651)
		(layer "In2.Cu")
		(net "PE_RX3_DR2_N")
	)
	(segment
		(start 22.800056 -18.609818)
		(end 23.876 -18.609818)
		(width 0.174752)
		(layer "F.Cu")
		(net "PE_RX3_DR14_P")
	)
	(segment
		(start 24.866854 -18.857214)
		(end 25.273 -18.451068)
		(width 0.174752)
		(layer "F.Cu")
		(net "PE_RX3_DR14_P")
	)
	(segment
		(start 24.123396 -18.857214)
		(end 24.866854 -18.857214)
		(width 0.174752)
		(layer "F.Cu")
		(net "PE_RX3_DR14_P")
	)
	(segment
		(start 23.876 -18.609818)
		(end 24.123396 -18.857214)
		(width 0.174752)
		(layer "F.Cu")
		(net "PE_RX3_DR14_P")
	)
	(via
		(at 25.273 -18.451068)
		(size 0.508)
		(drill 0.254)
		(layers "F.Cu" "B.Cu")
		(net "PE_RX3_DR14_P")
	)
	(via
		(at 5.08 -161.548318)
		(size 0.508)
		(drill 0.254)
		(layers "F.Cu" "B.Cu")
		(net "PE_RX3_DR14_P")
	)
	(segment
		(start 4.826254 -161.294572)
		(end 5.08 -161.548318)
		(width 0.174752)
		(layer "B.Cu")
		(net "PE_RX3_DR14_P")
	)
	(segment
		(start 1.868932 -161.542222)
		(end 3.657854 -161.542222)
		(width 0.174752)
		(layer "B.Cu")
		(net "PE_RX3_DR14_P")
	)
	(segment
		(start 3.905504 -161.294572)
		(end 4.826254 -161.294572)
		(width 0.174752)
		(layer "B.Cu")
		(net "PE_RX3_DR14_P")
	)
	(segment
		(start 3.657854 -161.542222)
		(end 3.905504 -161.294572)
		(width 0.174752)
		(layer "B.Cu")
		(net "PE_RX3_DR14_P")
	)
	(segment
		(start 25.273 -18.451068)
		(end 25.612344 -18.790412)
		(width 0.1651)
		(layer "In2.Cu")
		(net "PE_RX3_DR14_P")
	)
	(segment
		(start 33.021524 -22.422612)
		(end 34.518092 -30.910276)
		(width 0.1651)
		(layer "In2.Cu")
		(net "PE_RX3_DR14_P")
	)
	(segment
		(start 15.11173 -140.850366)
		(end 12.072366 -158.086552)
		(width 0.1651)
		(layer "In2.Cu")
		(net "PE_RX3_DR14_P")
	)
	(segment
		(start 28.211526 -66.675)
		(end 17.915636 -81.375758)
		(width 0.1651)
		(layer "In2.Cu")
		(net "PE_RX3_DR14_P")
	)
	(segment
		(start 26.452322 -18.790412)
		(end 29.433774 -19.315938)
		(width 0.1651)
		(layer "In2.Cu")
		(net "PE_RX3_DR14_P")
	)
	(segment
		(start 25.612344 -18.790412)
		(end 26.452322 -18.790412)
		(width 0.1651)
		(layer "In2.Cu")
		(net "PE_RX3_DR14_P")
	)
	(segment
		(start 8.383778 -161.101278)
		(end 7.081266 -161.330894)
		(width 0.1651)
		(layer "In2.Cu")
		(net "PE_RX3_DR14_P")
	)
	(segment
		(start 12.072366 -158.086552)
		(end 11.479784 -158.933134)
		(width 0.1651)
		(layer "In2.Cu")
		(net "PE_RX3_DR14_P")
	)
	(segment
		(start 34.518092 -30.910276)
		(end 28.211526 -66.675)
		(width 0.1651)
		(layer "In2.Cu")
		(net "PE_RX3_DR14_P")
	)
	(segment
		(start 17.80032 -81.662016)
		(end 17.782286 -81.764124)
		(width 0.1651)
		(layer "In2.Cu")
		(net "PE_RX3_DR14_P")
	)
	(segment
		(start 29.433774 -19.315938)
		(end 32.20974 -21.263864)
		(width 0.1651)
		(layer "In2.Cu")
		(net "PE_RX3_DR14_P")
	)
	(segment
		(start 7.081266 -161.330894)
		(end 5.297424 -161.330894)
		(width 0.1651)
		(layer "In2.Cu")
		(net "PE_RX3_DR14_P")
	)
	(segment
		(start 11.237468 -118.880382)
		(end 15.11173 -140.850366)
		(width 0.1651)
		(layer "In2.Cu")
		(net "PE_RX3_DR14_P")
	)
	(segment
		(start 11.479784 -158.933134)
		(end 8.383778 -161.101278)
		(width 0.1651)
		(layer "In2.Cu")
		(net "PE_RX3_DR14_P")
	)
	(segment
		(start 17.782286 -81.764124)
		(end 11.237468 -118.880382)
		(width 0.1651)
		(layer "In2.Cu")
		(net "PE_RX3_DR14_P")
	)
	(segment
		(start 5.297424 -161.330894)
		(end 5.08 -161.548318)
		(width 0.1651)
		(layer "In2.Cu")
		(net "PE_RX3_DR14_P")
	)
	(segment
		(start 17.915636 -81.375758)
		(end 17.80032 -81.662016)
		(width 0.1651)
		(layer "In2.Cu")
		(net "PE_RX3_DR14_P")
	)
	(segment
		(start 32.20974 -21.263864)
		(end 33.021524 -22.422612)
		(width 0.1651)
		(layer "In2.Cu")
		(net "PE_RX3_DR14_P")
	)
	(segment
		(start 22.800056 -19.409918)
		(end 23.876 -19.409918)
		(width 0.174752)
		(layer "F.Cu")
		(net "PE_RX3_DR14_N")
	)
	(segment
		(start 24.8666 -19.162268)
		(end 25.273 -19.568668)
		(width 0.174752)
		(layer "F.Cu")
		(net "PE_RX3_DR14_N")
	)
	(segment
		(start 23.876 -19.409918)
		(end 24.12365 -19.162268)
		(width 0.174752)
		(layer "F.Cu")
		(net "PE_RX3_DR14_N")
	)
	(segment
		(start 24.12365 -19.162268)
		(end 24.8666 -19.162268)
		(width 0.174752)
		(layer "F.Cu")
		(net "PE_RX3_DR14_N")
	)
	(via
		(at 5.08 -160.735518)
		(size 0.508)
		(drill 0.254)
		(layers "F.Cu" "B.Cu")
		(net "PE_RX3_DR14_N")
	)
	(via
		(at 25.273 -19.568668)
		(size 0.508)
		(drill 0.254)
		(layers "F.Cu" "B.Cu")
		(net "PE_RX3_DR14_N")
	)
	(segment
		(start 3.905504 -160.989518)
		(end 4.826 -160.989518)
		(width 0.174752)
		(layer "B.Cu")
		(net "PE_RX3_DR14_N")
	)
	(segment
		(start 3.658108 -160.742122)
		(end 3.905504 -160.989518)
		(width 0.174752)
		(layer "B.Cu")
		(net "PE_RX3_DR14_N")
	)
	(segment
		(start 4.826 -160.989518)
		(end 5.08 -160.735518)
		(width 0.174752)
		(layer "B.Cu")
		(net "PE_RX3_DR14_N")
	)
	(segment
		(start 1.868932 -160.742122)
		(end 3.658108 -160.742122)
		(width 0.174752)
		(layer "B.Cu")
		(net "PE_RX3_DR14_N")
	)
	(segment
		(start 27.787346 -19.577812)
		(end 28.005024 -19.425412)
		(width 0.1651)
		(layer "In2.Cu")
		(net "PE_RX3_DR14_N")
	)
	(segment
		(start 33.50387 -27.20721)
		(end 33.35147 -27.424888)
		(width 0.1651)
		(layer "In2.Cu")
		(net "PE_RX3_DR14_N")
	)
	(segment
		(start 33.266634 -25.861518)
		(end 33.114234 -26.079196)
		(width 0.1651)
		(layer "In2.Cu")
		(net "PE_RX3_DR14_N")
	)
	(segment
		(start 17.592548 -81.225898)
		(end 17.59077 -81.229962)
		(width 0.1651)
		(layer "In2.Cu")
		(net "PE_RX3_DR14_N")
	)
	(segment
		(start 32.96285 -25.221184)
		(end 33.180528 -25.373838)
		(width 0.1651)
		(layer "In2.Cu")
		(net "PE_RX3_DR14_N")
	)
	(segment
		(start 29.294074 -19.652742)
		(end 31.955232 -21.520658)
		(width 0.1651)
		(layer "In2.Cu")
		(net "PE_RX3_DR14_N")
	)
	(segment
		(start 25.273 -19.568668)
		(end 25.695656 -19.146012)
		(width 0.1651)
		(layer "In2.Cu")
		(net "PE_RX3_DR14_N")
	)
	(segment
		(start 10.482834 -159.19704)
		(end 10.22096 -159.150812)
		(width 0.1651)
		(layer "In2.Cu")
		(net "PE_RX3_DR14_N")
	)
	(segment
		(start 10.22096 -159.150812)
		(end 9.815322 -159.435038)
		(width 0.1651)
		(layer "In2.Cu")
		(net "PE_RX3_DR14_N")
	)
	(segment
		(start 17.59077 -81.229962)
		(end 17.456404 -81.563718)
		(width 0.1651)
		(layer "In2.Cu")
		(net "PE_RX3_DR14_N")
	)
	(segment
		(start 26.42108 -19.146012)
		(end 27.147012 -19.274282)
		(width 0.1651)
		(layer "In2.Cu")
		(net "PE_RX3_DR14_N")
	)
	(segment
		(start 7.050024 -160.975294)
		(end 5.319776 -160.975294)
		(width 0.1651)
		(layer "In2.Cu")
		(net "PE_RX3_DR14_N")
	)
	(segment
		(start 33.180528 -25.373838)
		(end 33.266634 -25.861518)
		(width 0.1651)
		(layer "In2.Cu")
		(net "PE_RX3_DR14_N")
	)
	(segment
		(start 32.725614 -23.875492)
		(end 32.943292 -24.028146)
		(width 0.1651)
		(layer "In2.Cu")
		(net "PE_RX3_DR14_N")
	)
	(segment
		(start 32.684974 -22.562058)
		(end 32.792162 -23.170134)
		(width 0.1651)
		(layer "In2.Cu")
		(net "PE_RX3_DR14_N")
	)
	(segment
		(start 9.769094 -159.696658)
		(end 9.363456 -159.980884)
		(width 0.1651)
		(layer "In2.Cu")
		(net "PE_RX3_DR14_N")
	)
	(segment
		(start 8.649716 -160.480502)
		(end 8.244078 -160.764728)
		(width 0.1651)
		(layer "In2.Cu")
		(net "PE_RX3_DR14_N")
	)
	(segment
		(start 32.792162 -23.170134)
		(end 32.639762 -23.387812)
		(width 0.1651)
		(layer "In2.Cu")
		(net "PE_RX3_DR14_N")
	)
	(segment
		(start 8.244332 -160.764728)
		(end 7.050024 -160.975294)
		(width 0.1651)
		(layer "In2.Cu")
		(net "PE_RX3_DR14_N")
	)
	(segment
		(start 28.005024 -19.425412)
		(end 29.294074 -19.652742)
		(width 0.1651)
		(layer "In2.Cu")
		(net "PE_RX3_DR14_N")
	)
	(segment
		(start 17.43202 -81.702402)
		(end 10.87628 -118.880382)
		(width 0.1651)
		(layer "In2.Cu")
		(net "PE_RX3_DR14_N")
	)
	(segment
		(start 8.244078 -160.764728)
		(end 8.244332 -160.764728)
		(width 0.1651)
		(layer "In2.Cu")
		(net "PE_RX3_DR14_N")
	)
	(segment
		(start 32.943292 -24.028146)
		(end 33.029398 -24.515826)
		(width 0.1651)
		(layer "In2.Cu")
		(net "PE_RX3_DR14_N")
	)
	(segment
		(start 17.590262 -81.220056)
		(end 17.592548 -81.225898)
		(width 0.1651)
		(layer "In2.Cu")
		(net "PE_RX3_DR14_N")
	)
	(segment
		(start 32.876998 -24.733504)
		(end 32.96285 -25.221184)
		(width 0.1651)
		(layer "In2.Cu")
		(net "PE_RX3_DR14_N")
	)
	(segment
		(start 11.735816 -157.947106)
		(end 11.22426 -158.67761)
		(width 0.1651)
		(layer "In2.Cu")
		(net "PE_RX3_DR14_N")
	)
	(segment
		(start 27.874976 -66.535554)
		(end 17.590262 -81.220056)
		(width 0.1651)
		(layer "In2.Cu")
		(net "PE_RX3_DR14_N")
	)
	(segment
		(start 33.029398 -24.515826)
		(end 32.876998 -24.733504)
		(width 0.1651)
		(layer "In2.Cu")
		(net "PE_RX3_DR14_N")
	)
	(segment
		(start 25.695656 -19.146012)
		(end 26.42108 -19.146012)
		(width 0.1651)
		(layer "In2.Cu")
		(net "PE_RX3_DR14_N")
	)
	(segment
		(start 8.695944 -160.218882)
		(end 8.649716 -160.480502)
		(width 0.1651)
		(layer "In2.Cu")
		(net "PE_RX3_DR14_N")
	)
	(segment
		(start 33.35147 -27.424888)
		(end 33.437576 -27.912568)
		(width 0.1651)
		(layer "In2.Cu")
		(net "PE_RX3_DR14_N")
	)
	(segment
		(start 9.101582 -159.934656)
		(end 8.695944 -160.218882)
		(width 0.1651)
		(layer "In2.Cu")
		(net "PE_RX3_DR14_N")
	)
	(segment
		(start 33.114234 -26.079196)
		(end 33.200086 -26.566876)
		(width 0.1651)
		(layer "In2.Cu")
		(net "PE_RX3_DR14_N")
	)
	(segment
		(start 27.299666 -19.49196)
		(end 27.787346 -19.577812)
		(width 0.1651)
		(layer "In2.Cu")
		(net "PE_RX3_DR14_N")
	)
	(segment
		(start 33.417764 -26.71953)
		(end 33.50387 -27.20721)
		(width 0.1651)
		(layer "In2.Cu")
		(net "PE_RX3_DR14_N")
	)
	(segment
		(start 33.655254 -28.065222)
		(end 34.15665 -30.909006)
		(width 0.1651)
		(layer "In2.Cu")
		(net "PE_RX3_DR14_N")
	)
	(segment
		(start 11.22426 -158.67761)
		(end 10.482834 -159.19704)
		(width 0.1651)
		(layer "In2.Cu")
		(net "PE_RX3_DR14_N")
	)
	(segment
		(start 33.200086 -26.566876)
		(end 33.417764 -26.71953)
		(width 0.1651)
		(layer "In2.Cu")
		(net "PE_RX3_DR14_N")
	)
	(segment
		(start 34.157158 -30.908752)
		(end 27.874976 -66.535554)
		(width 0.1651)
		(layer "In2.Cu")
		(net "PE_RX3_DR14_N")
	)
	(segment
		(start 5.319776 -160.975294)
		(end 5.08 -160.735518)
		(width 0.1651)
		(layer "In2.Cu")
		(net "PE_RX3_DR14_N")
	)
	(segment
		(start 34.15665 -30.909006)
		(end 34.157158 -30.908752)
		(width 0.1651)
		(layer "In2.Cu")
		(net "PE_RX3_DR14_N")
	)
	(segment
		(start 31.955232 -21.520658)
		(end 32.684974 -22.562058)
		(width 0.1651)
		(layer "In2.Cu")
		(net "PE_RX3_DR14_N")
	)
	(segment
		(start 27.147012 -19.274282)
		(end 27.299666 -19.49196)
		(width 0.1651)
		(layer "In2.Cu")
		(net "PE_RX3_DR14_N")
	)
	(segment
		(start 9.815322 -159.435038)
		(end 9.769094 -159.696658)
		(width 0.1651)
		(layer "In2.Cu")
		(net "PE_RX3_DR14_N")
	)
	(segment
		(start 9.363456 -159.980884)
		(end 9.101582 -159.934656)
		(width 0.1651)
		(layer "In2.Cu")
		(net "PE_RX3_DR14_N")
	)
	(segment
		(start 10.87628 -118.880382)
		(end 14.750542 -140.850366)
		(width 0.1651)
		(layer "In2.Cu")
		(net "PE_RX3_DR14_N")
	)
	(segment
		(start 14.750542 -140.850366)
		(end 11.735816 -157.947106)
		(width 0.1651)
		(layer "In2.Cu")
		(net "PE_RX3_DR14_N")
	)
	(segment
		(start 33.437576 -27.912568)
		(end 33.655254 -28.065222)
		(width 0.1651)
		(layer "In2.Cu")
		(net "PE_RX3_DR14_N")
	)
	(segment
		(start 32.639762 -23.387812)
		(end 32.725614 -23.875492)
		(width 0.1651)
		(layer "In2.Cu")
		(net "PE_RX3_DR14_N")
	)
	(segment
		(start 17.456404 -81.563718)
		(end 17.43202 -81.702402)
		(width 0.1651)
		(layer "In2.Cu")
		(net "PE_RX3_DR14_N")
	)
	(segment
		(start 24.317452 -121.857262)
		(end 24.866854 -121.857262)
		(width 0.174752)
		(layer "F.Cu")
		(net "PE_RX3_DR13_P")
	)
	(segment
		(start 23.941532 -121.609866)
		(end 24.317452 -121.857262)
		(width 0.174752)
		(layer "F.Cu")
		(net "PE_RX3_DR13_P")
	)
	(segment
		(start 24.866854 -121.857262)
		(end 25.273 -121.451116)
		(width 0.174752)
		(layer "F.Cu")
		(net "PE_RX3_DR13_P")
	)
	(segment
		(start 22.800056 -121.609866)
		(end 23.941532 -121.609866)
		(width 0.174752)
		(layer "F.Cu")
		(net "PE_RX3_DR13_P")
	)
	(via
		(at 5.08 -174.34814)
		(size 0.508)
		(drill 0.254)
		(layers "F.Cu" "B.Cu")
		(net "PE_RX3_DR13_P")
	)
	(via
		(at 25.273 -121.451116)
		(size 0.508)
		(drill 0.254)
		(layers "F.Cu" "B.Cu")
		(net "PE_RX3_DR13_P")
	)
	(segment
		(start 1.868932 -174.342044)
		(end 3.658108 -174.342044)
		(width 0.174752)
		(layer "B.Cu")
		(net "PE_RX3_DR13_P")
	)
	(segment
		(start 3.658108 -174.342044)
		(end 3.905504 -174.094648)
		(width 0.174752)
		(layer "B.Cu")
		(net "PE_RX3_DR13_P")
	)
	(segment
		(start 3.905504 -174.094648)
		(end 4.826508 -174.094648)
		(width 0.174752)
		(layer "B.Cu")
		(net "PE_RX3_DR13_P")
	)
	(segment
		(start 4.826508 -174.094648)
		(end 5.08 -174.34814)
		(width 0.174752)
		(layer "B.Cu")
		(net "PE_RX3_DR13_P")
	)
	(segment
		(start 24.137366 -170.647106)
		(end 24.207216 -170.598338)
		(width 0.1651)
		(layer "In2.Cu")
		(net "PE_RX3_DR13_P")
	)
	(segment
		(start 33.955482 -130.720338)
		(end 33.512506 -128.207516)
		(width 0.1651)
		(layer "In2.Cu")
		(net "PE_RX3_DR13_P")
	)
	(segment
		(start 24.207216 -170.598338)
		(end 24.258524 -170.562524)
		(width 0.1651)
		(layer "In2.Cu")
		(net "PE_RX3_DR13_P")
	)
	(segment
		(start 7.701026 -174.120048)
		(end 23.040594 -171.415456)
		(width 0.1651)
		(layer "In2.Cu")
		(net "PE_RX3_DR13_P")
	)
	(segment
		(start 5.08 -174.34814)
		(end 5.308092 -174.120048)
		(width 0.1651)
		(layer "In2.Cu")
		(net "PE_RX3_DR13_P")
	)
	(segment
		(start 31.239714 -146.122644)
		(end 33.955482 -130.720338)
		(width 0.1651)
		(layer "In2.Cu")
		(net "PE_RX3_DR13_P")
	)
	(segment
		(start 5.308092 -174.120048)
		(end 7.701026 -174.120048)
		(width 0.1651)
		(layer "In2.Cu")
		(net "PE_RX3_DR13_P")
	)
	(segment
		(start 23.040594 -171.415456)
		(end 24.137366 -170.647106)
		(width 0.1651)
		(layer "In2.Cu")
		(net "PE_RX3_DR13_P")
	)
	(segment
		(start 26.686256 -121.831862)
		(end 25.653746 -121.831862)
		(width 0.1651)
		(layer "In2.Cu")
		(net "PE_RX3_DR13_P")
	)
	(segment
		(start 27.487626 -121.973086)
		(end 26.686256 -121.831862)
		(width 0.1651)
		(layer "In2.Cu")
		(net "PE_RX3_DR13_P")
	)
	(segment
		(start 33.512506 -128.207516)
		(end 30.743906 -124.253498)
		(width 0.1651)
		(layer "In2.Cu")
		(net "PE_RX3_DR13_P")
	)
	(segment
		(start 25.653746 -121.831862)
		(end 25.273 -121.451116)
		(width 0.1651)
		(layer "In2.Cu")
		(net "PE_RX3_DR13_P")
	)
	(segment
		(start 30.743906 -124.253498)
		(end 27.487626 -121.973086)
		(width 0.1651)
		(layer "In2.Cu")
		(net "PE_RX3_DR13_P")
	)
	(segment
		(start 24.916892 -169.621962)
		(end 28.32862 -150.280624)
		(width 0.1651)
		(layer "In2.Cu")
		(net "PE_RX3_DR13_P")
	)
	(segment
		(start 28.32862 -150.280624)
		(end 31.239714 -146.122644)
		(width 0.1651)
		(layer "In2.Cu")
		(net "PE_RX3_DR13_P")
	)
	(segment
		(start 24.258524 -170.562524)
		(end 24.916892 -169.621962)
		(width 0.1651)
		(layer "In2.Cu")
		(net "PE_RX3_DR13_P")
	)
	(segment
		(start 24.278844 -122.162316)
		(end 24.8666 -122.162316)
		(width 0.174752)
		(layer "F.Cu")
		(net "PE_RX3_DR13_N")
	)
	(segment
		(start 24.031194 -122.409966)
		(end 24.278844 -122.162316)
		(width 0.174752)
		(layer "F.Cu")
		(net "PE_RX3_DR13_N")
	)
	(segment
		(start 22.800056 -122.409966)
		(end 24.031194 -122.409966)
		(width 0.174752)
		(layer "F.Cu")
		(net "PE_RX3_DR13_N")
	)
	(segment
		(start 24.8666 -122.162316)
		(end 25.273 -122.568716)
		(width 0.174752)
		(layer "F.Cu")
		(net "PE_RX3_DR13_N")
	)
	(via
		(at 25.273 -122.568716)
		(size 0.508)
		(drill 0.254)
		(layers "F.Cu" "B.Cu")
		(net "PE_RX3_DR13_N")
	)
	(via
		(at 5.08 -173.53534)
		(size 0.508)
		(drill 0.254)
		(layers "F.Cu" "B.Cu")
		(net "PE_RX3_DR13_N")
	)
	(segment
		(start 3.905504 -173.789594)
		(end 4.825746 -173.789594)
		(width 0.174752)
		(layer "B.Cu")
		(net "PE_RX3_DR13_N")
	)
	(segment
		(start 1.868932 -173.542198)
		(end 3.658108 -173.542198)
		(width 0.174752)
		(layer "B.Cu")
		(net "PE_RX3_DR13_N")
	)
	(segment
		(start 4.825746 -173.789594)
		(end 5.08 -173.53534)
		(width 0.174752)
		(layer "B.Cu")
		(net "PE_RX3_DR13_N")
	)
	(segment
		(start 3.658108 -173.542198)
		(end 3.905504 -173.789594)
		(width 0.174752)
		(layer "B.Cu")
		(net "PE_RX3_DR13_N")
	)
	(segment
		(start 12.314682 -172.754544)
		(end 12.162028 -172.972222)
		(width 0.1651)
		(layer "In2.Cu")
		(net "PE_RX3_DR13_N")
	)
	(segment
		(start 28.205684 -123.139708)
		(end 28.467558 -123.09348)
		(width 0.1651)
		(layer "In2.Cu")
		(net "PE_RX3_DR13_N")
	)
	(segment
		(start 9.470644 -173.446948)
		(end 7.669784 -173.764448)
		(width 0.1651)
		(layer "In2.Cu")
		(net "PE_RX3_DR13_N")
	)
	(segment
		(start 12.802362 -172.668692)
		(end 12.314682 -172.754544)
		(width 0.1651)
		(layer "In2.Cu")
		(net "PE_RX3_DR13_N")
	)
	(segment
		(start 31.510224 -126.295912)
		(end 31.794196 -126.70155)
		(width 0.1651)
		(layer "In2.Cu")
		(net "PE_RX3_DR13_N")
	)
	(segment
		(start 32.294068 -127.41529)
		(end 32.57804 -127.820928)
		(width 0.1651)
		(layer "In2.Cu")
		(net "PE_RX3_DR13_N")
	)
	(segment
		(start 31.556452 -126.034038)
		(end 31.510224 -126.295912)
		(width 0.1651)
		(layer "In2.Cu")
		(net "PE_RX3_DR13_N")
	)
	(segment
		(start 10.816336 -173.209458)
		(end 10.328656 -173.295564)
		(width 0.1651)
		(layer "In2.Cu")
		(net "PE_RX3_DR13_N")
	)
	(segment
		(start 24.003 -170.306746)
		(end 24.003254 -170.306746)
		(width 0.1651)
		(layer "In2.Cu")
		(net "PE_RX3_DR13_N")
	)
	(segment
		(start 27.800046 -122.855482)
		(end 28.205684 -123.139708)
		(width 0.1651)
		(layer "In2.Cu")
		(net "PE_RX3_DR13_N")
	)
	(segment
		(start 26.655014 -122.187462)
		(end 27.34818 -122.309636)
		(width 0.1651)
		(layer "In2.Cu")
		(net "PE_RX3_DR13_N")
	)
	(segment
		(start 30.903164 -145.983198)
		(end 27.99207 -150.141178)
		(width 0.1651)
		(layer "In2.Cu")
		(net "PE_RX3_DR13_N")
	)
	(segment
		(start 27.99207 -150.141178)
		(end 24.580342 -169.482516)
		(width 0.1651)
		(layer "In2.Cu")
		(net "PE_RX3_DR13_N")
	)
	(segment
		(start 33.175956 -128.346962)
		(end 33.594294 -130.720338)
		(width 0.1651)
		(layer "In2.Cu")
		(net "PE_RX3_DR13_N")
	)
	(segment
		(start 32.57804 -127.820928)
		(end 32.839914 -127.867156)
		(width 0.1651)
		(layer "In2.Cu")
		(net "PE_RX3_DR13_N")
	)
	(segment
		(start 25.273 -122.568716)
		(end 25.654254 -122.187462)
		(width 0.1651)
		(layer "In2.Cu")
		(net "PE_RX3_DR13_N")
	)
	(segment
		(start 11.674348 -173.058328)
		(end 11.45667 -172.905928)
		(width 0.1651)
		(layer "In2.Cu")
		(net "PE_RX3_DR13_N")
	)
	(segment
		(start 27.34818 -122.309636)
		(end 27.753818 -122.593862)
		(width 0.1651)
		(layer "In2.Cu")
		(net "PE_RX3_DR13_N")
	)
	(segment
		(start 33.594294 -130.720338)
		(end 30.903164 -145.983198)
		(width 0.1651)
		(layer "In2.Cu")
		(net "PE_RX3_DR13_N")
	)
	(segment
		(start 9.623298 -173.22927)
		(end 9.470644 -173.446948)
		(width 0.1651)
		(layer "In2.Cu")
		(net "PE_RX3_DR13_N")
	)
	(segment
		(start 30.772608 -124.91466)
		(end 30.72638 -125.176534)
		(width 0.1651)
		(layer "In2.Cu")
		(net "PE_RX3_DR13_N")
	)
	(segment
		(start 24.003 -170.307)
		(end 22.901148 -171.078906)
		(width 0.1651)
		(layer "In2.Cu")
		(net "PE_RX3_DR13_N")
	)
	(segment
		(start 7.669784 -173.764448)
		(end 5.309108 -173.764448)
		(width 0.1651)
		(layer "In2.Cu")
		(net "PE_RX3_DR13_N")
	)
	(segment
		(start 28.467558 -123.09348)
		(end 30.488382 -124.509022)
		(width 0.1651)
		(layer "In2.Cu")
		(net "PE_RX3_DR13_N")
	)
	(segment
		(start 24.003254 -170.306746)
		(end 24.003 -170.307)
		(width 0.1651)
		(layer "In2.Cu")
		(net "PE_RX3_DR13_N")
	)
	(segment
		(start 12.162028 -172.972222)
		(end 11.674348 -173.058328)
		(width 0.1651)
		(layer "In2.Cu")
		(net "PE_RX3_DR13_N")
	)
	(segment
		(start 25.654254 -122.187462)
		(end 26.655014 -122.187462)
		(width 0.1651)
		(layer "In2.Cu")
		(net "PE_RX3_DR13_N")
	)
	(segment
		(start 32.340296 -127.153416)
		(end 32.294068 -127.41529)
		(width 0.1651)
		(layer "In2.Cu")
		(net "PE_RX3_DR13_N")
	)
	(segment
		(start 11.45667 -172.905928)
		(end 10.96899 -172.99178)
		(width 0.1651)
		(layer "In2.Cu")
		(net "PE_RX3_DR13_N")
	)
	(segment
		(start 27.753818 -122.593862)
		(end 27.800046 -122.855482)
		(width 0.1651)
		(layer "In2.Cu")
		(net "PE_RX3_DR13_N")
	)
	(segment
		(start 10.328656 -173.295564)
		(end 10.110978 -173.143164)
		(width 0.1651)
		(layer "In2.Cu")
		(net "PE_RX3_DR13_N")
	)
	(segment
		(start 32.839914 -127.867156)
		(end 33.175956 -128.346962)
		(width 0.1651)
		(layer "In2.Cu")
		(net "PE_RX3_DR13_N")
	)
	(segment
		(start 10.110978 -173.143164)
		(end 9.623298 -173.22927)
		(width 0.1651)
		(layer "In2.Cu")
		(net "PE_RX3_DR13_N")
	)
	(segment
		(start 30.488382 -124.509022)
		(end 30.772608 -124.91466)
		(width 0.1651)
		(layer "In2.Cu")
		(net "PE_RX3_DR13_N")
	)
	(segment
		(start 30.72638 -125.176534)
		(end 31.010352 -125.582172)
		(width 0.1651)
		(layer "In2.Cu")
		(net "PE_RX3_DR13_N")
	)
	(segment
		(start 31.272226 -125.6284)
		(end 31.556452 -126.034038)
		(width 0.1651)
		(layer "In2.Cu")
		(net "PE_RX3_DR13_N")
	)
	(segment
		(start 22.901148 -171.078906)
		(end 13.02004 -172.821092)
		(width 0.1651)
		(layer "In2.Cu")
		(net "PE_RX3_DR13_N")
	)
	(segment
		(start 13.02004 -172.821092)
		(end 12.802362 -172.668692)
		(width 0.1651)
		(layer "In2.Cu")
		(net "PE_RX3_DR13_N")
	)
	(segment
		(start 31.010352 -125.582172)
		(end 31.272226 -125.6284)
		(width 0.1651)
		(layer "In2.Cu")
		(net "PE_RX3_DR13_N")
	)
	(segment
		(start 10.96899 -172.99178)
		(end 10.816336 -173.209458)
		(width 0.1651)
		(layer "In2.Cu")
		(net "PE_RX3_DR13_N")
	)
	(segment
		(start 24.580342 -169.482516)
		(end 24.003 -170.306746)
		(width 0.1651)
		(layer "In2.Cu")
		(net "PE_RX3_DR13_N")
	)
	(segment
		(start 32.05607 -126.747778)
		(end 32.340296 -127.153416)
		(width 0.1651)
		(layer "In2.Cu")
		(net "PE_RX3_DR13_N")
	)
	(segment
		(start 31.794196 -126.70155)
		(end 32.05607 -126.747778)
		(width 0.1651)
		(layer "In2.Cu")
		(net "PE_RX3_DR13_N")
	)
	(segment
		(start 5.309108 -173.764448)
		(end 5.08 -173.53534)
		(width 0.1651)
		(layer "In2.Cu")
		(net "PE_RX3_DR13_N")
	)
	(segment
		(start 24.123396 -224.85731)
		(end 24.866854 -224.85731)
		(width 0.174752)
		(layer "F.Cu")
		(net "PE_RX3_DR12_P")
	)
	(segment
		(start 24.866854 -224.85731)
		(end 25.273 -224.451164)
		(width 0.174752)
		(layer "F.Cu")
		(net "PE_RX3_DR12_P")
	)
	(segment
		(start 22.800056 -224.609914)
		(end 23.876 -224.609914)
		(width 0.174752)
		(layer "F.Cu")
		(net "PE_RX3_DR12_P")
	)
	(segment
		(start 23.876 -224.609914)
		(end 24.123396 -224.85731)
		(width 0.174752)
		(layer "F.Cu")
		(net "PE_RX3_DR12_P")
	)
	(via
		(at 5.08 -219.948252)
		(size 0.508)
		(drill 0.254)
		(layers "F.Cu" "B.Cu")
		(net "PE_RX3_DR12_P")
	)
	(via
		(at 25.273 -224.451164)
		(size 0.508)
		(drill 0.254)
		(layers "F.Cu" "B.Cu")
		(net "PE_RX3_DR12_P")
	)
	(segment
		(start 4.026154 -219.694506)
		(end 4.826254 -219.694506)
		(width 0.174752)
		(layer "B.Cu")
		(net "PE_RX3_DR12_P")
	)
	(segment
		(start 4.826254 -219.694506)
		(end 5.08 -219.948252)
		(width 0.174752)
		(layer "B.Cu")
		(net "PE_RX3_DR12_P")
	)
	(segment
		(start 1.868932 -219.942156)
		(end 3.778504 -219.942156)
		(width 0.174752)
		(layer "B.Cu")
		(net "PE_RX3_DR12_P")
	)
	(segment
		(start 3.778504 -219.942156)
		(end 4.026154 -219.694506)
		(width 0.174752)
		(layer "B.Cu")
		(net "PE_RX3_DR12_P")
	)
	(segment
		(start 5.08 -219.948252)
		(end 5.308346 -219.719906)
		(width 0.1651)
		(layer "In2.Cu")
		(net "PE_RX3_DR12_P")
	)
	(segment
		(start 14.76883 -211.56295)
		(end 14.61643 -211.345018)
		(width 0.1651)
		(layer "In2.Cu")
		(net "PE_RX3_DR12_P")
	)
	(segment
		(start 36.220146 -219.277946)
		(end 32.058864 -222.19158)
		(width 0.1651)
		(layer "In2.Cu")
		(net "PE_RX3_DR12_P")
	)
	(segment
		(start 14.379194 -212.690964)
		(end 14.465046 -212.20303)
		(width 0.1651)
		(layer "In2.Cu")
		(net "PE_RX3_DR12_P")
	)
	(segment
		(start 14.208252 -214.742014)
		(end 14.294358 -214.254334)
		(width 0.1651)
		(layer "In2.Cu")
		(net "PE_RX3_DR12_P")
	)
	(segment
		(start 30.225746 -223.475296)
		(end 29.820108 -223.759268)
		(width 0.1651)
		(layer "In2.Cu")
		(net "PE_RX3_DR12_P")
	)
	(segment
		(start 27.062684 -224.83191)
		(end 25.653746 -224.83191)
		(width 0.1651)
		(layer "In2.Cu")
		(net "PE_RX3_DR12_P")
	)
	(segment
		(start 14.531594 -212.908642)
		(end 14.379194 -212.690964)
		(width 0.1651)
		(layer "In2.Cu")
		(net "PE_RX3_DR12_P")
	)
	(segment
		(start 36.933886 -218.778328)
		(end 36.672012 -218.7321)
		(width 0.1651)
		(layer "In2.Cu")
		(net "PE_RX3_DR12_P")
	)
	(segment
		(start 28.70073 -224.543112)
		(end 27.062684 -224.83191)
		(width 0.1651)
		(layer "In2.Cu")
		(net "PE_RX3_DR12_P")
	)
	(segment
		(start 13.990574 -214.894668)
		(end 14.208252 -214.742014)
		(width 0.1651)
		(layer "In2.Cu")
		(net "PE_RX3_DR12_P")
	)
	(segment
		(start 14.294358 -214.254334)
		(end 14.141704 -214.036656)
		(width 0.1651)
		(layer "In2.Cu")
		(net "PE_RX3_DR12_P")
	)
	(segment
		(start 31.345124 -222.691452)
		(end 30.939486 -222.975424)
		(width 0.1651)
		(layer "In2.Cu")
		(net "PE_RX3_DR12_P")
	)
	(segment
		(start 30.939486 -222.975424)
		(end 30.677612 -222.92945)
		(width 0.1651)
		(layer "In2.Cu")
		(net "PE_RX3_DR12_P")
	)
	(segment
		(start 14.465046 -212.20303)
		(end 14.682978 -212.05063)
		(width 0.1651)
		(layer "In2.Cu")
		(net "PE_RX3_DR12_P")
	)
	(segment
		(start 42.466768 -206.988664)
		(end 42.866056 -209.253582)
		(width 0.1651)
		(layer "In2.Cu")
		(net "PE_RX3_DR12_P")
	)
	(segment
		(start 41.339516 -205.378812)
		(end 42.466768 -206.988664)
		(width 0.1651)
		(layer "In2.Cu")
		(net "PE_RX3_DR12_P")
	)
	(segment
		(start 25.653746 -224.83191)
		(end 25.273 -224.451164)
		(width 0.1651)
		(layer "In2.Cu")
		(net "PE_RX3_DR12_P")
	)
	(segment
		(start 14.445488 -213.396322)
		(end 14.531594 -212.908642)
		(width 0.1651)
		(layer "In2.Cu")
		(net "PE_RX3_DR12_P")
	)
	(segment
		(start 19.916394 -201.082148)
		(end 22.711156 -200.589388)
		(width 0.1651)
		(layer "In2.Cu")
		(net "PE_RX3_DR12_P")
	)
	(segment
		(start 38.46576 -203.366624)
		(end 41.339516 -205.378812)
		(width 0.1651)
		(layer "In2.Cu")
		(net "PE_RX3_DR12_P")
	)
	(segment
		(start 29.820108 -223.759268)
		(end 29.558234 -223.71304)
		(width 0.1651)
		(layer "In2.Cu")
		(net "PE_RX3_DR12_P")
	)
	(segment
		(start 31.391352 -222.429578)
		(end 31.345124 -222.691452)
		(width 0.1651)
		(layer "In2.Cu")
		(net "PE_RX3_DR12_P")
	)
	(segment
		(start 14.22781 -213.548722)
		(end 14.445488 -213.396322)
		(width 0.1651)
		(layer "In2.Cu")
		(net "PE_RX3_DR12_P")
	)
	(segment
		(start 14.61643 -211.345018)
		(end 15.514066 -206.254604)
		(width 0.1651)
		(layer "In2.Cu")
		(net "PE_RX3_DR12_P")
	)
	(segment
		(start 30.677612 -222.92945)
		(end 30.271974 -223.213422)
		(width 0.1651)
		(layer "In2.Cu")
		(net "PE_RX3_DR12_P")
	)
	(segment
		(start 5.308346 -219.719906)
		(end 7.112 -219.719906)
		(width 0.1651)
		(layer "In2.Cu")
		(net "PE_RX3_DR12_P")
	)
	(segment
		(start 31.79699 -222.145606)
		(end 31.391352 -222.429578)
		(width 0.1651)
		(layer "In2.Cu")
		(net "PE_RX3_DR12_P")
	)
	(segment
		(start 15.514066 -206.254604)
		(end 18.385282 -202.154282)
		(width 0.1651)
		(layer "In2.Cu")
		(net "PE_RX3_DR12_P")
	)
	(segment
		(start 29.152596 -223.997266)
		(end 29.106368 -224.25914)
		(width 0.1651)
		(layer "In2.Cu")
		(net "PE_RX3_DR12_P")
	)
	(segment
		(start 30.271974 -223.213422)
		(end 30.225746 -223.475296)
		(width 0.1651)
		(layer "In2.Cu")
		(net "PE_RX3_DR12_P")
	)
	(segment
		(start 42.866056 -209.253582)
		(end 42.408094 -211.850478)
		(width 0.1651)
		(layer "In2.Cu")
		(net "PE_RX3_DR12_P")
	)
	(segment
		(start 14.682978 -212.05063)
		(end 14.76883 -211.56295)
		(width 0.1651)
		(layer "In2.Cu")
		(net "PE_RX3_DR12_P")
	)
	(segment
		(start 22.711156 -200.589388)
		(end 38.46576 -203.366624)
		(width 0.1651)
		(layer "In2.Cu")
		(net "PE_RX3_DR12_P")
	)
	(segment
		(start 14.141704 -214.036656)
		(end 14.22781 -213.548722)
		(width 0.1651)
		(layer "In2.Cu")
		(net "PE_RX3_DR12_P")
	)
	(segment
		(start 12.130278 -217.913712)
		(end 13.904468 -215.382348)
		(width 0.1651)
		(layer "In2.Cu")
		(net "PE_RX3_DR12_P")
	)
	(segment
		(start 36.672012 -218.7321)
		(end 36.266374 -219.016072)
		(width 0.1651)
		(layer "In2.Cu")
		(net "PE_RX3_DR12_P")
	)
	(segment
		(start 10.373106 -219.14485)
		(end 12.130278 -217.913712)
		(width 0.1651)
		(layer "In2.Cu")
		(net "PE_RX3_DR12_P")
	)
	(segment
		(start 29.106368 -224.25914)
		(end 28.70073 -224.543112)
		(width 0.1651)
		(layer "In2.Cu")
		(net "PE_RX3_DR12_P")
	)
	(segment
		(start 7.112 -219.719906)
		(end 10.373106 -219.14485)
		(width 0.1651)
		(layer "In2.Cu")
		(net "PE_RX3_DR12_P")
	)
	(segment
		(start 13.904468 -215.382348)
		(end 13.990574 -214.894668)
		(width 0.1651)
		(layer "In2.Cu")
		(net "PE_RX3_DR12_P")
	)
	(segment
		(start 18.385282 -202.154282)
		(end 19.916394 -201.082148)
		(width 0.1651)
		(layer "In2.Cu")
		(net "PE_RX3_DR12_P")
	)
	(segment
		(start 38.157658 -217.921332)
		(end 36.933886 -218.778328)
		(width 0.1651)
		(layer "In2.Cu")
		(net "PE_RX3_DR12_P")
	)
	(segment
		(start 32.058864 -222.19158)
		(end 31.79699 -222.145606)
		(width 0.1651)
		(layer "In2.Cu")
		(net "PE_RX3_DR12_P")
	)
	(segment
		(start 36.266374 -219.016072)
		(end 36.220146 -219.277946)
		(width 0.1651)
		(layer "In2.Cu")
		(net "PE_RX3_DR12_P")
	)
	(segment
		(start 29.558234 -223.71304)
		(end 29.152596 -223.997266)
		(width 0.1651)
		(layer "In2.Cu")
		(net "PE_RX3_DR12_P")
	)
	(segment
		(start 42.408094 -211.850478)
		(end 38.157658 -217.921332)
		(width 0.1651)
		(layer "In2.Cu")
		(net "PE_RX3_DR12_P")
	)
	(segment
		(start 22.800056 -225.410014)
		(end 23.890986 -225.410014)
		(width 0.174752)
		(layer "F.Cu")
		(net "PE_RX3_DR12_N")
	)
	(segment
		(start 24.138636 -225.162364)
		(end 24.8666 -225.162364)
		(width 0.174752)
		(layer "F.Cu")
		(net "PE_RX3_DR12_N")
	)
	(segment
		(start 23.890986 -225.410014)
		(end 24.138636 -225.162364)
		(width 0.174752)
		(layer "F.Cu")
		(net "PE_RX3_DR12_N")
	)
	(segment
		(start 24.8666 -225.162364)
		(end 25.273 -225.568764)
		(width 0.174752)
		(layer "F.Cu")
		(net "PE_RX3_DR12_N")
	)
	(via
		(at 25.273 -225.568764)
		(size 0.508)
		(drill 0.254)
		(layers "F.Cu" "B.Cu")
		(net "PE_RX3_DR12_N")
	)
	(via
		(at 5.08 -219.135452)
		(size 0.508)
		(drill 0.254)
		(layers "F.Cu" "B.Cu")
		(net "PE_RX3_DR12_N")
	)
	(segment
		(start 4.013454 -219.389452)
		(end 4.826 -219.389452)
		(width 0.174752)
		(layer "B.Cu")
		(net "PE_RX3_DR12_N")
	)
	(segment
		(start 4.826 -219.389452)
		(end 5.08 -219.135452)
		(width 0.174752)
		(layer "B.Cu")
		(net "PE_RX3_DR12_N")
	)
	(segment
		(start 1.868932 -219.142056)
		(end 3.661918 -219.142056)
		(width 0.174752)
		(layer "B.Cu")
		(net "PE_RX3_DR12_N")
	)
	(segment
		(start 3.661918 -219.142056)
		(end 4.013454 -219.389452)
		(width 0.174752)
		(layer "B.Cu")
		(net "PE_RX3_DR12_N")
	)
	(segment
		(start 5.308854 -219.364306)
		(end 7.080758 -219.364306)
		(width 0.1651)
		(layer "In2.Cu")
		(net "PE_RX3_DR12_N")
	)
	(segment
		(start 5.08 -219.135452)
		(end 5.308854 -219.364306)
		(width 0.1651)
		(layer "In2.Cu")
		(net "PE_RX3_DR12_N")
	)
	(segment
		(start 7.080758 -219.364306)
		(end 10.23366 -218.8083)
		(width 0.1651)
		(layer "In2.Cu")
		(net "PE_RX3_DR12_N")
	)
	(segment
		(start 38.413182 -218.176856)
		(end 28.840176 -224.879662)
		(width 0.1651)
		(layer "In2.Cu")
		(net "PE_RX3_DR12_N")
	)
	(segment
		(start 38.605206 -203.030074)
		(end 41.59504 -205.123288)
		(width 0.1651)
		(layer "In2.Cu")
		(net "PE_RX3_DR12_N")
	)
	(segment
		(start 27.093926 -225.18751)
		(end 25.654254 -225.18751)
		(width 0.1651)
		(layer "In2.Cu")
		(net "PE_RX3_DR12_N")
	)
	(segment
		(start 42.744644 -211.989924)
		(end 38.413182 -218.176856)
		(width 0.1651)
		(layer "In2.Cu")
		(net "PE_RX3_DR12_N")
	)
	(segment
		(start 10.23366 -218.8083)
		(end 11.874754 -217.658188)
		(width 0.1651)
		(layer "In2.Cu")
		(net "PE_RX3_DR12_N")
	)
	(segment
		(start 42.803318 -206.849218)
		(end 43.227244 -209.253582)
		(width 0.1651)
		(layer "In2.Cu")
		(net "PE_RX3_DR12_N")
	)
	(segment
		(start 15.177516 -206.115158)
		(end 18.129758 -201.898758)
		(width 0.1651)
		(layer "In2.Cu")
		(net "PE_RX3_DR12_N")
	)
	(segment
		(start 11.874754 -217.658188)
		(end 13.567918 -215.242902)
		(width 0.1651)
		(layer "In2.Cu")
		(net "PE_RX3_DR12_N")
	)
	(segment
		(start 28.840176 -224.879662)
		(end 27.093926 -225.18751)
		(width 0.1651)
		(layer "In2.Cu")
		(net "PE_RX3_DR12_N")
	)
	(segment
		(start 13.567918 -215.242902)
		(end 15.177516 -206.115158)
		(width 0.1651)
		(layer "In2.Cu")
		(net "PE_RX3_DR12_N")
	)
	(segment
		(start 41.59504 -205.123288)
		(end 42.803318 -206.849218)
		(width 0.1651)
		(layer "In2.Cu")
		(net "PE_RX3_DR12_N")
	)
	(segment
		(start 18.129758 -201.898758)
		(end 19.776948 -200.745598)
		(width 0.1651)
		(layer "In2.Cu")
		(net "PE_RX3_DR12_N")
	)
	(segment
		(start 22.711156 -200.2282)
		(end 38.605206 -203.030074)
		(width 0.1651)
		(layer "In2.Cu")
		(net "PE_RX3_DR12_N")
	)
	(segment
		(start 25.654254 -225.18751)
		(end 25.273 -225.568764)
		(width 0.1651)
		(layer "In2.Cu")
		(net "PE_RX3_DR12_N")
	)
	(segment
		(start 43.227244 -209.253582)
		(end 42.744644 -211.989924)
		(width 0.1651)
		(layer "In2.Cu")
		(net "PE_RX3_DR12_N")
	)
	(segment
		(start 19.776948 -200.745598)
		(end 22.711156 -200.2282)
		(width 0.1651)
		(layer "In2.Cu")
		(net "PE_RX3_DR12_N")
	)
	(segment
		(start 25.273 -327.451212)
		(end 24.879046 -327.845166)
		(width 0.174752)
		(layer "F.Cu")
		(net "PE_RX3_DR11_P")
	)
	(segment
		(start 24.111204 -327.845166)
		(end 23.876 -327.609962)
		(width 0.174752)
		(layer "F.Cu")
		(net "PE_RX3_DR11_P")
	)
	(segment
		(start 23.876 -327.609962)
		(end 22.800056 -327.609962)
		(width 0.174752)
		(layer "F.Cu")
		(net "PE_RX3_DR11_P")
	)
	(segment
		(start 24.879046 -327.845166)
		(end 24.111204 -327.845166)
		(width 0.174752)
		(layer "F.Cu")
		(net "PE_RX3_DR11_P")
	)
	(via
		(at 25.273 -327.451212)
		(size 0.508)
		(drill 0.254)
		(layers "F.Cu" "B.Cu")
		(net "PE_RX3_DR11_P")
	)
	(via
		(at 5.08 -342.748108)
		(size 0.508)
		(drill 0.254)
		(layers "F.Cu" "B.Cu")
		(net "PE_RX3_DR11_P")
	)
	(segment
		(start 4.826508 -342.494616)
		(end 5.08 -342.748108)
		(width 0.174752)
		(layer "B.Cu")
		(net "PE_RX3_DR11_P")
	)
	(segment
		(start 3.658108 -342.742012)
		(end 4.01066 -342.494616)
		(width 0.174752)
		(layer "B.Cu")
		(net "PE_RX3_DR11_P")
	)
	(segment
		(start 4.01066 -342.494616)
		(end 4.826508 -342.494616)
		(width 0.174752)
		(layer "B.Cu")
		(net "PE_RX3_DR11_P")
	)
	(segment
		(start 1.868932 -342.742012)
		(end 3.658108 -342.742012)
		(width 0.174752)
		(layer "B.Cu")
		(net "PE_RX3_DR11_P")
	)
	(segment
		(start 20.250658 -356.531672)
		(end 18.423636 -355.253036)
		(width 0.1651)
		(layer "In2.Cu")
		(net "PE_RX3_DR11_P")
	)
	(segment
		(start 31.09595 -347.858842)
		(end 31.106872 -347.920818)
		(width 0.1651)
		(layer "In2.Cu")
		(net "PE_RX3_DR11_P")
	)
	(segment
		(start 30.481524 -344.374978)
		(end 31.09595 -347.859096)
		(width 0.1651)
		(layer "In2.Cu")
		(net "PE_RX3_DR11_P")
	)
	(segment
		(start 29.453332 -329.564238)
		(end 30.671008 -336.455512)
		(width 0.1651)
		(layer "In2.Cu")
		(net "PE_RX3_DR11_P")
	)
	(segment
		(start 29.87802 -340.952328)
		(end 30.481524 -344.374978)
		(width 0.1651)
		(layer "In2.Cu")
		(net "PE_RX3_DR11_P")
	)
	(segment
		(start 10.686542 -344.203274)
		(end 8.698738 -342.810846)
		(width 0.1651)
		(layer "In2.Cu")
		(net "PE_RX3_DR11_P")
	)
	(segment
		(start 26.550874 -327.808082)
		(end 27.943556 -328.0537)
		(width 0.1651)
		(layer "In2.Cu")
		(net "PE_RX3_DR11_P")
	)
	(segment
		(start 30.671008 -336.455512)
		(end 29.87802 -340.952328)
		(width 0.1651)
		(layer "In2.Cu")
		(net "PE_RX3_DR11_P")
	)
	(segment
		(start 25.273 -327.451212)
		(end 25.62987 -327.808082)
		(width 0.1651)
		(layer "In2.Cu")
		(net "PE_RX3_DR11_P")
	)
	(segment
		(start 30.080458 -351.55124)
		(end 22.852126 -356.612444)
		(width 0.1651)
		(layer "In2.Cu")
		(net "PE_RX3_DR11_P")
	)
	(segment
		(start 31.106872 -347.920818)
		(end 30.596586 -350.813878)
		(width 0.1651)
		(layer "In2.Cu")
		(net "PE_RX3_DR11_P")
	)
	(segment
		(start 30.596586 -350.813878)
		(end 30.080458 -351.55124)
		(width 0.1651)
		(layer "In2.Cu")
		(net "PE_RX3_DR11_P")
	)
	(segment
		(start 21.7805 -356.801674)
		(end 20.250658 -356.531672)
		(width 0.1651)
		(layer "In2.Cu")
		(net "PE_RX3_DR11_P")
	)
	(segment
		(start 28.830524 -328.674476)
		(end 29.453332 -329.564238)
		(width 0.1651)
		(layer "In2.Cu")
		(net "PE_RX3_DR11_P")
	)
	(segment
		(start 31.09595 -347.859096)
		(end 31.09595 -347.858842)
		(width 0.1651)
		(layer "In2.Cu")
		(net "PE_RX3_DR11_P")
	)
	(segment
		(start 18.423636 -355.253036)
		(end 10.686542 -344.203274)
		(width 0.1651)
		(layer "In2.Cu")
		(net "PE_RX3_DR11_P")
	)
	(segment
		(start 27.943556 -328.0537)
		(end 28.830524 -328.674476)
		(width 0.1651)
		(layer "In2.Cu")
		(net "PE_RX3_DR11_P")
	)
	(segment
		(start 25.62987 -327.808082)
		(end 26.550874 -327.808082)
		(width 0.1651)
		(layer "In2.Cu")
		(net "PE_RX3_DR11_P")
	)
	(segment
		(start 6.996176 -342.510618)
		(end 5.31749 -342.510618)
		(width 0.1651)
		(layer "In2.Cu")
		(net "PE_RX3_DR11_P")
	)
	(segment
		(start 22.852126 -356.612444)
		(end 21.7805 -356.801674)
		(width 0.1651)
		(layer "In2.Cu")
		(net "PE_RX3_DR11_P")
	)
	(segment
		(start 5.31749 -342.510618)
		(end 5.08 -342.748108)
		(width 0.1651)
		(layer "In2.Cu")
		(net "PE_RX3_DR11_P")
	)
	(segment
		(start 8.698738 -342.810846)
		(end 6.996176 -342.510618)
		(width 0.1651)
		(layer "In2.Cu")
		(net "PE_RX3_DR11_P")
	)
	(segment
		(start 25.273 -328.568812)
		(end 24.854408 -328.15022)
		(width 0.174752)
		(layer "F.Cu")
		(net "PE_RX3_DR11_N")
	)
	(segment
		(start 23.887938 -328.410062)
		(end 22.800056 -328.410062)
		(width 0.174752)
		(layer "F.Cu")
		(net "PE_RX3_DR11_N")
	)
	(segment
		(start 24.14778 -328.15022)
		(end 23.887938 -328.410062)
		(width 0.174752)
		(layer "F.Cu")
		(net "PE_RX3_DR11_N")
	)
	(segment
		(start 24.854408 -328.15022)
		(end 24.14778 -328.15022)
		(width 0.174752)
		(layer "F.Cu")
		(net "PE_RX3_DR11_N")
	)
	(via
		(at 25.273 -328.568812)
		(size 0.508)
		(drill 0.254)
		(layers "F.Cu" "B.Cu")
		(net "PE_RX3_DR11_N")
	)
	(via
		(at 5.08 -341.935308)
		(size 0.508)
		(drill 0.254)
		(layers "F.Cu" "B.Cu")
		(net "PE_RX3_DR11_N")
	)
	(segment
		(start 1.868932 -341.942166)
		(end 3.658108 -341.942166)
		(width 0.174752)
		(layer "B.Cu")
		(net "PE_RX3_DR11_N")
	)
	(segment
		(start 3.905504 -342.189562)
		(end 4.825746 -342.189562)
		(width 0.174752)
		(layer "B.Cu")
		(net "PE_RX3_DR11_N")
	)
	(segment
		(start 3.658108 -341.942166)
		(end 3.905504 -342.189562)
		(width 0.174752)
		(layer "B.Cu")
		(net "PE_RX3_DR11_N")
	)
	(segment
		(start 4.825746 -342.189562)
		(end 5.08 -341.935308)
		(width 0.174752)
		(layer "B.Cu")
		(net "PE_RX3_DR11_N")
	)
	(segment
		(start 29.05887 -330.397358)
		(end 29.144976 -330.885292)
		(width 0.1651)
		(layer "In2.Cu")
		(net "PE_RX3_DR11_N")
	)
	(segment
		(start 29.585158 -332.354936)
		(end 29.671264 -332.842616)
		(width 0.1651)
		(layer "In2.Cu")
		(net "PE_RX3_DR11_N")
	)
	(segment
		(start 29.613352 -333.536544)
		(end 29.819346 -333.680562)
		(width 0.1651)
		(layer "In2.Cu")
		(net "PE_RX3_DR11_N")
	)
	(segment
		(start 25.403302 -354.16236)
		(end 25.357074 -354.424234)
		(width 0.1651)
		(layer "In2.Cu")
		(net "PE_RX3_DR11_N")
	)
	(segment
		(start 29.35097 -331.02931)
		(end 29.437076 -331.51699)
		(width 0.1651)
		(layer "In2.Cu")
		(net "PE_RX3_DR11_N")
	)
	(segment
		(start 29.527246 -333.04861)
		(end 29.613352 -333.536544)
		(width 0.1651)
		(layer "In2.Cu")
		(net "PE_RX3_DR11_N")
	)
	(segment
		(start 29.516832 -340.952328)
		(end 30.745684 -347.920818)
		(width 0.1651)
		(layer "In2.Cu")
		(net "PE_RX3_DR11_N")
	)
	(segment
		(start 11.226038 -344.353388)
		(end 10.942066 -343.94775)
		(width 0.1651)
		(layer "In2.Cu")
		(net "PE_RX3_DR11_N")
	)
	(segment
		(start 18.67916 -354.997512)
		(end 11.714226 -345.050618)
		(width 0.1651)
		(layer "In2.Cu")
		(net "PE_RX3_DR11_N")
	)
	(segment
		(start 27.80411 -328.39025)
		(end 27.803856 -328.39025)
		(width 0.1651)
		(layer "In2.Cu")
		(net "PE_RX3_DR11_N")
	)
	(segment
		(start 7.027418 -342.155018)
		(end 5.29971 -342.155018)
		(width 0.1651)
		(layer "In2.Cu")
		(net "PE_RX3_DR11_N")
	)
	(segment
		(start 8.838184 -342.474296)
		(end 7.027418 -342.155018)
		(width 0.1651)
		(layer "In2.Cu")
		(net "PE_RX3_DR11_N")
	)
	(segment
		(start 10.942066 -343.94775)
		(end 8.838184 -342.474296)
		(width 0.1651)
		(layer "In2.Cu")
		(net "PE_RX3_DR11_N")
	)
	(segment
		(start 24.237696 -355.208078)
		(end 23.832058 -355.49205)
		(width 0.1651)
		(layer "In2.Cu")
		(net "PE_RX3_DR11_N")
	)
	(segment
		(start 23.570184 -355.445822)
		(end 23.164546 -355.730048)
		(width 0.1651)
		(layer "In2.Cu")
		(net "PE_RX3_DR11_N")
	)
	(segment
		(start 23.832058 -355.49205)
		(end 23.570184 -355.445822)
		(width 0.1651)
		(layer "In2.Cu")
		(net "PE_RX3_DR11_N")
	)
	(segment
		(start 30.30982 -336.455512)
		(end 29.516832 -340.952328)
		(width 0.1651)
		(layer "In2.Cu")
		(net "PE_RX3_DR11_N")
	)
	(segment
		(start 29.671264 -332.842616)
		(end 29.527246 -333.04861)
		(width 0.1651)
		(layer "In2.Cu")
		(net "PE_RX3_DR11_N")
	)
	(segment
		(start 30.260036 -350.674432)
		(end 29.824934 -351.295716)
		(width 0.1651)
		(layer "In2.Cu")
		(net "PE_RX3_DR11_N")
	)
	(segment
		(start 29.293058 -331.722984)
		(end 29.379164 -332.210918)
		(width 0.1651)
		(layer "In2.Cu")
		(net "PE_RX3_DR11_N")
	)
	(segment
		(start 25.273 -328.568812)
		(end 25.67813 -328.163682)
		(width 0.1651)
		(layer "In2.Cu")
		(net "PE_RX3_DR11_N")
	)
	(segment
		(start 20.390104 -356.195122)
		(end 18.67916 -354.997512)
		(width 0.1651)
		(layer "In2.Cu")
		(net "PE_RX3_DR11_N")
	)
	(segment
		(start 29.144976 -330.885292)
		(end 29.35097 -331.02931)
		(width 0.1651)
		(layer "In2.Cu")
		(net "PE_RX3_DR11_N")
	)
	(segment
		(start 22.71268 -356.275894)
		(end 21.7805 -356.440486)
		(width 0.1651)
		(layer "In2.Cu")
		(net "PE_RX3_DR11_N")
	)
	(segment
		(start 23.118318 -355.991668)
		(end 22.71268 -356.275894)
		(width 0.1651)
		(layer "In2.Cu")
		(net "PE_RX3_DR11_N")
	)
	(segment
		(start 29.202888 -330.191364)
		(end 29.05887 -330.397358)
		(width 0.1651)
		(layer "In2.Cu")
		(net "PE_RX3_DR11_N")
	)
	(segment
		(start 26.070814 -353.924362)
		(end 25.80894 -353.878388)
		(width 0.1651)
		(layer "In2.Cu")
		(net "PE_RX3_DR11_N")
	)
	(segment
		(start 30.745684 -347.920818)
		(end 30.260036 -350.674432)
		(width 0.1651)
		(layer "In2.Cu")
		(net "PE_RX3_DR11_N")
	)
	(segment
		(start 25.357074 -354.424234)
		(end 24.951436 -354.708206)
		(width 0.1651)
		(layer "In2.Cu")
		(net "PE_RX3_DR11_N")
	)
	(segment
		(start 24.951436 -354.708206)
		(end 24.689562 -354.661978)
		(width 0.1651)
		(layer "In2.Cu")
		(net "PE_RX3_DR11_N")
	)
	(segment
		(start 29.824934 -351.295716)
		(end 26.070814 -353.924362)
		(width 0.1651)
		(layer "In2.Cu")
		(net "PE_RX3_DR11_N")
	)
	(segment
		(start 29.819346 -333.680562)
		(end 30.30982 -336.455512)
		(width 0.1651)
		(layer "In2.Cu")
		(net "PE_RX3_DR11_N")
	)
	(segment
		(start 24.283924 -354.946204)
		(end 24.237696 -355.208078)
		(width 0.1651)
		(layer "In2.Cu")
		(net "PE_RX3_DR11_N")
	)
	(segment
		(start 25.67813 -328.163682)
		(end 26.519632 -328.163682)
		(width 0.1651)
		(layer "In2.Cu")
		(net "PE_RX3_DR11_N")
	)
	(segment
		(start 23.164546 -355.730048)
		(end 23.118318 -355.991668)
		(width 0.1651)
		(layer "In2.Cu")
		(net "PE_RX3_DR11_N")
	)
	(segment
		(start 11.714226 -345.050618)
		(end 11.757914 -344.802968)
		(width 0.1651)
		(layer "In2.Cu")
		(net "PE_RX3_DR11_N")
	)
	(segment
		(start 29.116782 -329.703684)
		(end 29.202888 -330.191364)
		(width 0.1651)
		(layer "In2.Cu")
		(net "PE_RX3_DR11_N")
	)
	(segment
		(start 21.7805 -356.440486)
		(end 20.390104 -356.195122)
		(width 0.1651)
		(layer "In2.Cu")
		(net "PE_RX3_DR11_N")
	)
	(segment
		(start 11.473688 -344.397076)
		(end 11.226038 -344.353388)
		(width 0.1651)
		(layer "In2.Cu")
		(net "PE_RX3_DR11_N")
	)
	(segment
		(start 27.803856 -328.39025)
		(end 28.575 -328.93)
		(width 0.1651)
		(layer "In2.Cu")
		(net "PE_RX3_DR11_N")
	)
	(segment
		(start 11.757914 -344.802968)
		(end 11.473688 -344.397076)
		(width 0.1651)
		(layer "In2.Cu")
		(net "PE_RX3_DR11_N")
	)
	(segment
		(start 29.437076 -331.51699)
		(end 29.293058 -331.722984)
		(width 0.1651)
		(layer "In2.Cu")
		(net "PE_RX3_DR11_N")
	)
	(segment
		(start 5.29971 -342.155018)
		(end 5.08 -341.935308)
		(width 0.1651)
		(layer "In2.Cu")
		(net "PE_RX3_DR11_N")
	)
	(segment
		(start 29.379164 -332.210918)
		(end 29.585158 -332.354936)
		(width 0.1651)
		(layer "In2.Cu")
		(net "PE_RX3_DR11_N")
	)
	(segment
		(start 26.519632 -328.163682)
		(end 27.80411 -328.39025)
		(width 0.1651)
		(layer "In2.Cu")
		(net "PE_RX3_DR11_N")
	)
	(segment
		(start 25.80894 -353.878388)
		(end 25.403302 -354.16236)
		(width 0.1651)
		(layer "In2.Cu")
		(net "PE_RX3_DR11_N")
	)
	(segment
		(start 28.575 -328.93)
		(end 29.116782 -329.703684)
		(width 0.1651)
		(layer "In2.Cu")
		(net "PE_RX3_DR11_N")
	)
	(segment
		(start 24.689562 -354.661978)
		(end 24.283924 -354.946204)
		(width 0.1651)
		(layer "In2.Cu")
		(net "PE_RX3_DR11_N")
	)
	(segment
		(start 23.88235 -431.41011)
		(end 22.800056 -431.41011)
		(width 0.174752)
		(layer "F.Cu")
		(net "PE_RX3_DR10_P")
	)
	(segment
		(start 24.1046 -431.18786)
		(end 23.88235 -431.41011)
		(width 0.174752)
		(layer "F.Cu")
		(net "PE_RX3_DR10_P")
	)
	(segment
		(start 25.273 -431.56886)
		(end 24.892 -431.18786)
		(width 0.174752)
		(layer "F.Cu")
		(net "PE_RX3_DR10_P")
	)
	(segment
		(start 24.892 -431.18786)
		(end 24.1046 -431.18786)
		(width 0.174752)
		(layer "F.Cu")
		(net "PE_RX3_DR10_P")
	)
	(via
		(at 25.273 -431.56886)
		(size 0.508)
		(drill 0.254)
		(layers "F.Cu" "B.Cu")
		(net "PE_RX3_DR10_P")
	)
	(via
		(at 5.08 -410.335222)
		(size 0.508)
		(drill 0.254)
		(layers "F.Cu" "B.Cu")
		(net "PE_RX3_DR10_P")
	)
	(segment
		(start 4.826 -410.589222)
		(end 5.08 -410.335222)
		(width 0.174752)
		(layer "B.Cu")
		(net "PE_RX3_DR10_P")
	)
	(segment
		(start 1.868932 -410.341826)
		(end 3.658108 -410.341826)
		(width 0.174752)
		(layer "B.Cu")
		(net "PE_RX3_DR10_P")
	)
	(segment
		(start 3.905504 -410.589222)
		(end 4.826 -410.589222)
		(width 0.174752)
		(layer "B.Cu")
		(net "PE_RX3_DR10_P")
	)
	(segment
		(start 3.658108 -410.341826)
		(end 3.905504 -410.589222)
		(width 0.174752)
		(layer "B.Cu")
		(net "PE_RX3_DR10_P")
	)
	(segment
		(start 42.803064 -413.992568)
		(end 41.860978 -412.647384)
		(width 0.1651)
		(layer "In2.Cu")
		(net "PE_RX3_DR10_P")
	)
	(segment
		(start 26.686256 -431.187606)
		(end 27.887168 -430.976024)
		(width 0.1651)
		(layer "In2.Cu")
		(net "PE_RX3_DR10_P")
	)
	(segment
		(start 22.416516 -408.450796)
		(end 10.44575 -410.561536)
		(width 0.1651)
		(layer "In2.Cu")
		(net "PE_RX3_DR10_P")
	)
	(segment
		(start 27.887168 -430.976024)
		(end 40.38219 -422.226994)
		(width 0.1651)
		(layer "In2.Cu")
		(net "PE_RX3_DR10_P")
	)
	(segment
		(start 25.654254 -431.187606)
		(end 26.686256 -431.187606)
		(width 0.1651)
		(layer "In2.Cu")
		(net "PE_RX3_DR10_P")
	)
	(segment
		(start 5.308854 -410.564076)
		(end 5.08 -410.335222)
		(width 0.1651)
		(layer "In2.Cu")
		(net "PE_RX3_DR10_P")
	)
	(segment
		(start 40.531796 -422.077134)
		(end 42.257218 -419.612572)
		(width 0.1651)
		(layer "In2.Cu")
		(net "PE_RX3_DR10_P")
	)
	(segment
		(start 10.44575 -410.561536)
		(end 10.445496 -410.561536)
		(width 0.1651)
		(layer "In2.Cu")
		(net "PE_RX3_DR10_P")
	)
	(segment
		(start 43.05935 -415.165286)
		(end 42.889424 -414.200848)
		(width 0.1651)
		(layer "In2.Cu")
		(net "PE_RX3_DR10_P")
	)
	(segment
		(start 23.61057 -408.624024)
		(end 22.416516 -408.450796)
		(width 0.1651)
		(layer "In2.Cu")
		(net "PE_RX3_DR10_P")
	)
	(segment
		(start 40.28186 -411.563058)
		(end 23.61057 -408.624024)
		(width 0.1651)
		(layer "In2.Cu")
		(net "PE_RX3_DR10_P")
	)
	(segment
		(start 10.416794 -410.564076)
		(end 5.308854 -410.564076)
		(width 0.1651)
		(layer "In2.Cu")
		(net "PE_RX3_DR10_P")
	)
	(segment
		(start 41.733216 -412.519622)
		(end 40.49014 -411.649418)
		(width 0.1651)
		(layer "In2.Cu")
		(net "PE_RX3_DR10_P")
	)
	(segment
		(start 42.343578 -419.404546)
		(end 43.05935 -415.346134)
		(width 0.1651)
		(layer "In2.Cu")
		(net "PE_RX3_DR10_P")
	)
	(segment
		(start 25.273 -431.56886)
		(end 25.654254 -431.187606)
		(width 0.1651)
		(layer "In2.Cu")
		(net "PE_RX3_DR10_P")
	)
	(arc
		(start 43.05935 -415.346134)
		(mid 43.067261 -415.25571)
		(end 43.05935 -415.165286)
		(width 0.1651)
		(layer "In2.Cu")
		(net "PE_RX3_DR10_P")
	)
	(arc
		(start 10.445496 -410.561536)
		(mid 10.431201 -410.563443)
		(end 10.416794 -410.564076)
		(width 0.1651)
		(layer "In2.Cu")
		(net "PE_RX3_DR10_P")
	)
	(arc
		(start 42.889424 -414.200848)
		(mid 42.857636 -414.091987)
		(end 42.803064 -413.992568)
		(width 0.1651)
		(layer "In2.Cu")
		(net "PE_RX3_DR10_P")
	)
	(arc
		(start 41.860978 -412.647384)
		(mid 41.802681 -412.577919)
		(end 41.733216 -412.519622)
		(width 0.1651)
		(layer "In2.Cu")
		(net "PE_RX3_DR10_P")
	)
	(arc
		(start 40.49014 -411.649418)
		(mid 40.390735 -411.594814)
		(end 40.28186 -411.563058)
		(width 0.1651)
		(layer "In2.Cu")
		(net "PE_RX3_DR10_P")
	)
	(arc
		(start 40.38219 -422.226994)
		(mid 40.463558 -422.158617)
		(end 40.531796 -422.077134)
		(width 0.1651)
		(layer "In2.Cu")
		(net "PE_RX3_DR10_P")
	)
	(arc
		(start 42.257218 -419.612572)
		(mid 42.311774 -419.513282)
		(end 42.343578 -419.404546)
		(width 0.1651)
		(layer "In2.Cu")
		(net "PE_RX3_DR10_P")
	)
	(segment
		(start 24.148796 -430.882806)
		(end 23.876 -430.61001)
		(width 0.174752)
		(layer "F.Cu")
		(net "PE_RX3_DR10_N")
	)
	(segment
		(start 23.876 -430.61001)
		(end 22.800056 -430.61001)
		(width 0.174752)
		(layer "F.Cu")
		(net "PE_RX3_DR10_N")
	)
	(segment
		(start 24.841454 -430.882806)
		(end 24.148796 -430.882806)
		(width 0.174752)
		(layer "F.Cu")
		(net "PE_RX3_DR10_N")
	)
	(segment
		(start 25.273 -430.45126)
		(end 24.841454 -430.882806)
		(width 0.174752)
		(layer "F.Cu")
		(net "PE_RX3_DR10_N")
	)
	(via
		(at 5.08 -411.148022)
		(size 0.508)
		(drill 0.254)
		(layers "F.Cu" "B.Cu")
		(net "PE_RX3_DR10_N")
	)
	(via
		(at 25.273 -430.45126)
		(size 0.508)
		(drill 0.254)
		(layers "F.Cu" "B.Cu")
		(net "PE_RX3_DR10_N")
	)
	(segment
		(start 3.905504 -410.894276)
		(end 4.826254 -410.894276)
		(width 0.174752)
		(layer "B.Cu")
		(net "PE_RX3_DR10_N")
	)
	(segment
		(start 1.868932 -411.141926)
		(end 3.657854 -411.141926)
		(width 0.174752)
		(layer "B.Cu")
		(net "PE_RX3_DR10_N")
	)
	(segment
		(start 4.826254 -410.894276)
		(end 5.08 -411.148022)
		(width 0.174752)
		(layer "B.Cu")
		(net "PE_RX3_DR10_N")
	)
	(segment
		(start 3.657854 -411.141926)
		(end 3.905504 -410.894276)
		(width 0.174752)
		(layer "B.Cu")
		(net "PE_RX3_DR10_N")
	)
	(segment
		(start 35.305746 -425.117768)
		(end 34.900108 -425.40174)
		(width 0.1651)
		(layer "In2.Cu")
		(net "PE_RX3_DR10_N")
	)
	(segment
		(start 37.985446 -423.24147)
		(end 37.939218 -423.503344)
		(width 0.1651)
		(layer "In2.Cu")
		(net "PE_RX3_DR10_N")
	)
	(segment
		(start 5.308346 -410.919676)
		(end 10.417048 -410.919676)
		(width 0.1651)
		(layer "In2.Cu")
		(net "PE_RX3_DR10_N")
	)
	(segment
		(start 41.96588 -419.40861)
		(end 40.240458 -421.873172)
		(width 0.1651)
		(layer "In2.Cu")
		(net "PE_RX3_DR10_N")
	)
	(segment
		(start 22.422104 -408.810968)
		(end 23.554182 -408.975306)
		(width 0.1651)
		(layer "In2.Cu")
		(net "PE_RX3_DR10_N")
	)
	(segment
		(start 39.772336 -422.219882)
		(end 39.510462 -422.173654)
		(width 0.1651)
		(layer "In2.Cu")
		(net "PE_RX3_DR10_N")
	)
	(segment
		(start 28.707334 -429.750474)
		(end 28.301696 -430.0347)
		(width 0.1651)
		(layer "In2.Cu")
		(net "PE_RX3_DR10_N")
	)
	(segment
		(start 28.258008 -430.282096)
		(end 27.747722 -430.639474)
		(width 0.1651)
		(layer "In2.Cu")
		(net "PE_RX3_DR10_N")
	)
	(segment
		(start 34.186368 -425.901612)
		(end 33.78073 -426.185584)
		(width 0.1651)
		(layer "In2.Cu")
		(net "PE_RX3_DR10_N")
	)
	(segment
		(start 31.160212 -428.249842)
		(end 30.912816 -428.206154)
		(width 0.1651)
		(layer "In2.Cu")
		(net "PE_RX3_DR10_N")
	)
	(segment
		(start 34.900108 -425.40174)
		(end 34.85388 -425.663614)
		(width 0.1651)
		(layer "In2.Cu")
		(net "PE_RX3_DR10_N")
	)
	(segment
		(start 34.85388 -425.663614)
		(end 34.448242 -425.94784)
		(width 0.1651)
		(layer "In2.Cu")
		(net "PE_RX3_DR10_N")
	)
	(segment
		(start 37.938964 -423.503344)
		(end 35.56762 -425.163996)
		(width 0.1651)
		(layer "In2.Cu")
		(net "PE_RX3_DR10_N")
	)
	(segment
		(start 38.391084 -422.957498)
		(end 37.985446 -423.24147)
		(width 0.1651)
		(layer "In2.Cu")
		(net "PE_RX3_DR10_N")
	)
	(segment
		(start 28.301696 -430.0347)
		(end 28.258008 -430.282096)
		(width 0.1651)
		(layer "In2.Cu")
		(net "PE_RX3_DR10_N")
	)
	(segment
		(start 25.653746 -430.832006)
		(end 25.273 -430.45126)
		(width 0.1651)
		(layer "In2.Cu")
		(net "PE_RX3_DR10_N")
	)
	(segment
		(start 30.912816 -428.206154)
		(end 30.506924 -428.49038)
		(width 0.1651)
		(layer "In2.Cu")
		(net "PE_RX3_DR10_N")
	)
	(segment
		(start 29.809948 -428.978314)
		(end 29.40431 -429.26254)
		(width 0.1651)
		(layer "In2.Cu")
		(net "PE_RX3_DR10_N")
	)
	(segment
		(start 10.507472 -410.911802)
		(end 22.422104 -408.810968)
		(width 0.1651)
		(layer "In2.Cu")
		(net "PE_RX3_DR10_N")
	)
	(segment
		(start 33.734248 -426.447458)
		(end 31.160212 -428.249842)
		(width 0.1651)
		(layer "In2.Cu")
		(net "PE_RX3_DR10_N")
	)
	(segment
		(start 29.360622 -429.509936)
		(end 28.954984 -429.794162)
		(width 0.1651)
		(layer "In2.Cu")
		(net "PE_RX3_DR10_N")
	)
	(segment
		(start 42.709084 -415.284412)
		(end 41.993312 -419.34257)
		(width 0.1651)
		(layer "In2.Cu")
		(net "PE_RX3_DR10_N")
	)
	(segment
		(start 5.08 -411.148022)
		(end 5.308346 -410.919676)
		(width 0.1651)
		(layer "In2.Cu")
		(net "PE_RX3_DR10_N")
	)
	(segment
		(start 26.655014 -430.832006)
		(end 25.653746 -430.832006)
		(width 0.1651)
		(layer "In2.Cu")
		(net "PE_RX3_DR10_N")
	)
	(segment
		(start 39.510462 -422.173654)
		(end 39.104824 -422.457626)
		(width 0.1651)
		(layer "In2.Cu")
		(net "PE_RX3_DR10_N")
	)
	(segment
		(start 27.747722 -430.639474)
		(end 26.655014 -430.832006)
		(width 0.1651)
		(layer "In2.Cu")
		(net "PE_RX3_DR10_N")
	)
	(segment
		(start 28.954984 -429.794162)
		(end 28.707334 -429.750474)
		(width 0.1651)
		(layer "In2.Cu")
		(net "PE_RX3_DR10_N")
	)
	(segment
		(start 41.56964 -412.851346)
		(end 42.511726 -414.19653)
		(width 0.1651)
		(layer "In2.Cu")
		(net "PE_RX3_DR10_N")
	)
	(segment
		(start 37.939218 -423.503344)
		(end 37.938964 -423.503344)
		(width 0.1651)
		(layer "In2.Cu")
		(net "PE_RX3_DR10_N")
	)
	(segment
		(start 33.78073 -426.185584)
		(end 33.734502 -426.447458)
		(width 0.1651)
		(layer "In2.Cu")
		(net "PE_RX3_DR10_N")
	)
	(segment
		(start 34.448242 -425.94784)
		(end 34.186368 -425.901612)
		(width 0.1651)
		(layer "In2.Cu")
		(net "PE_RX3_DR10_N")
	)
	(segment
		(start 30.057598 -429.022002)
		(end 29.809948 -428.978314)
		(width 0.1651)
		(layer "In2.Cu")
		(net "PE_RX3_DR10_N")
	)
	(segment
		(start 38.652958 -423.003472)
		(end 38.391084 -422.957498)
		(width 0.1651)
		(layer "In2.Cu")
		(net "PE_RX3_DR10_N")
	)
	(segment
		(start 39.058596 -422.7195)
		(end 38.652958 -423.003472)
		(width 0.1651)
		(layer "In2.Cu")
		(net "PE_RX3_DR10_N")
	)
	(segment
		(start 40.177974 -421.935656)
		(end 39.772336 -422.219882)
		(width 0.1651)
		(layer "In2.Cu")
		(net "PE_RX3_DR10_N")
	)
	(segment
		(start 30.506924 -428.49038)
		(end 30.463236 -428.737776)
		(width 0.1651)
		(layer "In2.Cu")
		(net "PE_RX3_DR10_N")
	)
	(segment
		(start 39.104824 -422.457626)
		(end 39.058596 -422.7195)
		(width 0.1651)
		(layer "In2.Cu")
		(net "PE_RX3_DR10_N")
	)
	(segment
		(start 30.463236 -428.737776)
		(end 30.057598 -429.022002)
		(width 0.1651)
		(layer "In2.Cu")
		(net "PE_RX3_DR10_N")
	)
	(segment
		(start 29.40431 -429.26254)
		(end 29.360622 -429.509936)
		(width 0.1651)
		(layer "In2.Cu")
		(net "PE_RX3_DR10_N")
	)
	(segment
		(start 42.539158 -414.26257)
		(end 42.709084 -415.227008)
		(width 0.1651)
		(layer "In2.Cu")
		(net "PE_RX3_DR10_N")
	)
	(segment
		(start 40.286178 -411.940756)
		(end 41.529254 -412.81096)
		(width 0.1651)
		(layer "In2.Cu")
		(net "PE_RX3_DR10_N")
	)
	(segment
		(start 35.56762 -425.163996)
		(end 35.305746 -425.117768)
		(width 0.1651)
		(layer "In2.Cu")
		(net "PE_RX3_DR10_N")
	)
	(segment
		(start 23.554182 -408.975306)
		(end 23.556722 -408.975814)
		(width 0.1651)
		(layer "In2.Cu")
		(net "PE_RX3_DR10_N")
	)
	(segment
		(start 23.556722 -408.975814)
		(end 40.220138 -411.913324)
		(width 0.1651)
		(layer "In2.Cu")
		(net "PE_RX3_DR10_N")
	)
	(segment
		(start 33.734502 -426.447458)
		(end 33.734248 -426.447458)
		(width 0.1651)
		(layer "In2.Cu")
		(net "PE_RX3_DR10_N")
	)
	(arc
		(start 40.240458 -421.873172)
		(mid 40.211955 -421.907153)
		(end 40.177974 -421.935656)
		(width 0.1651)
		(layer "In2.Cu")
		(net "PE_RX3_DR10_N")
	)
	(arc
		(start 41.529254 -412.81096)
		(mid 41.551207 -412.829393)
		(end 41.56964 -412.851346)
		(width 0.1651)
		(layer "In2.Cu")
		(net "PE_RX3_DR10_N")
	)
	(arc
		(start 40.220138 -411.913324)
		(mid 40.254672 -411.923402)
		(end 40.286178 -411.940756)
		(width 0.1651)
		(layer "In2.Cu")
		(net "PE_RX3_DR10_N")
	)
	(arc
		(start 42.511726 -414.19653)
		(mid 42.529088 -414.228039)
		(end 42.539158 -414.26257)
		(width 0.1651)
		(layer "In2.Cu")
		(net "PE_RX3_DR10_N")
	)
	(arc
		(start 10.417048 -410.919676)
		(mid 10.462432 -410.917717)
		(end 10.507472 -410.911802)
		(width 0.1651)
		(layer "In2.Cu")
		(net "PE_RX3_DR10_N")
	)
	(arc
		(start 41.993312 -419.34257)
		(mid 41.983234 -419.377104)
		(end 41.96588 -419.40861)
		(width 0.1651)
		(layer "In2.Cu")
		(net "PE_RX3_DR10_N")
	)
	(arc
		(start 42.709084 -415.227008)
		(mid 42.711598 -415.25571)
		(end 42.709084 -415.284412)
		(width 0.1651)
		(layer "In2.Cu")
		(net "PE_RX3_DR10_N")
	)
	(segment
		(start 222.891604 -384.142742)
		(end 222.13316 -384.142742)
		(width 0.174752)
		(layer "F.Cu")
		(net "PE_RX3_DR1_P")
	)
	(segment
		(start 223.139 -384.390138)
		(end 222.891604 -384.142742)
		(width 0.174752)
		(layer "F.Cu")
		(net "PE_RX3_DR1_P")
	)
	(segment
		(start 224.199958 -384.390138)
		(end 223.139 -384.390138)
		(width 0.174752)
		(layer "F.Cu")
		(net "PE_RX3_DR1_P")
	)
	(segment
		(start 222.13316 -384.142742)
		(end 221.727014 -384.548888)
		(width 0.174752)
		(layer "F.Cu")
		(net "PE_RX3_DR1_P")
	)
	(via
		(at 5.08 -395.9479)
		(size 0.508)
		(drill 0.254)
		(layers "F.Cu" "B.Cu")
		(net "PE_RX3_DR1_P")
	)
	(via
		(at 221.727014 -384.548888)
		(size 0.508)
		(drill 0.254)
		(layers "F.Cu" "B.Cu")
		(net "PE_RX3_DR1_P")
	)
	(segment
		(start 3.90525 -395.694408)
		(end 4.826508 -395.694408)
		(width 0.174752)
		(layer "B.Cu")
		(net "PE_RX3_DR1_P")
	)
	(segment
		(start 1.868932 -395.941804)
		(end 3.657854 -395.941804)
		(width 0.174752)
		(layer "B.Cu")
		(net "PE_RX3_DR1_P")
	)
	(segment
		(start 3.657854 -395.941804)
		(end 3.90525 -395.694408)
		(width 0.174752)
		(layer "B.Cu")
		(net "PE_RX3_DR1_P")
	)
	(segment
		(start 4.826508 -395.694408)
		(end 5.08 -395.9479)
		(width 0.174752)
		(layer "B.Cu")
		(net "PE_RX3_DR1_P")
	)
	(segment
		(start 200.672954 -380.755144)
		(end 45.150024 -408.17927)
		(width 0.1651)
		(layer "In2.Cu")
		(net "PE_RX3_DR1_P")
	)
	(segment
		(start 20.437348 -403.882098)
		(end 14.82979 -399.955766)
		(width 0.1651)
		(layer "In2.Cu")
		(net "PE_RX3_DR1_P")
	)
	(segment
		(start 9.351518 -396.120112)
		(end 7.080758 -395.719808)
		(width 0.1651)
		(layer "In2.Cu")
		(net "PE_RX3_DR1_P")
	)
	(segment
		(start 220.282516 -384.168142)
		(end 200.893426 -380.755144)
		(width 0.1651)
		(layer "In2.Cu")
		(net "PE_RX3_DR1_P")
	)
	(segment
		(start 221.346268 -384.168142)
		(end 220.282516 -384.168142)
		(width 0.1651)
		(layer "In2.Cu")
		(net "PE_RX3_DR1_P")
	)
	(segment
		(start 14.82979 -399.955766)
		(end 9.351518 -396.120112)
		(width 0.1651)
		(layer "In2.Cu")
		(net "PE_RX3_DR1_P")
	)
	(segment
		(start 45.150024 -408.17927)
		(end 45.150024 -408.179524)
		(width 0.1651)
		(layer "In2.Cu")
		(net "PE_RX3_DR1_P")
	)
	(segment
		(start 221.727014 -384.548888)
		(end 221.346268 -384.168142)
		(width 0.1651)
		(layer "In2.Cu")
		(net "PE_RX3_DR1_P")
	)
	(segment
		(start 7.080758 -395.719808)
		(end 5.308092 -395.719808)
		(width 0.1651)
		(layer "In2.Cu")
		(net "PE_RX3_DR1_P")
	)
	(segment
		(start 5.308092 -395.719808)
		(end 5.08 -395.9479)
		(width 0.1651)
		(layer "In2.Cu")
		(net "PE_RX3_DR1_P")
	)
	(segment
		(start 44.806108 -408.179524)
		(end 20.437348 -403.882098)
		(width 0.1651)
		(layer "In2.Cu")
		(net "PE_RX3_DR1_P")
	)
	(arc
		(start 200.893426 -380.755144)
		(mid 200.78319 -380.745506)
		(end 200.672954 -380.755144)
		(width 0.1651)
		(layer "In2.Cu")
		(net "PE_RX3_DR1_P")
	)
	(arc
		(start 45.150024 -408.179524)
		(mid 44.978066 -408.194562)
		(end 44.806108 -408.179524)
		(width 0.1651)
		(layer "In2.Cu")
		(net "PE_RX3_DR1_P")
	)
	(segment
		(start 223.139 -383.590038)
		(end 222.89135 -383.837688)
		(width 0.174752)
		(layer "F.Cu")
		(net "PE_RX3_DR1_N")
	)
	(segment
		(start 222.133414 -383.837688)
		(end 221.727014 -383.431288)
		(width 0.174752)
		(layer "F.Cu")
		(net "PE_RX3_DR1_N")
	)
	(segment
		(start 224.199958 -383.590038)
		(end 223.139 -383.590038)
		(width 0.174752)
		(layer "F.Cu")
		(net "PE_RX3_DR1_N")
	)
	(segment
		(start 222.89135 -383.837688)
		(end 222.133414 -383.837688)
		(width 0.174752)
		(layer "F.Cu")
		(net "PE_RX3_DR1_N")
	)
	(via
		(at 5.08 -395.1351)
		(size 0.508)
		(drill 0.254)
		(layers "F.Cu" "B.Cu")
		(net "PE_RX3_DR1_N")
	)
	(via
		(at 221.727014 -383.431288)
		(size 0.508)
		(drill 0.254)
		(layers "F.Cu" "B.Cu")
		(net "PE_RX3_DR1_N")
	)
	(segment
		(start 1.868932 -395.141958)
		(end 3.657854 -395.141958)
		(width 0.174752)
		(layer "B.Cu")
		(net "PE_RX3_DR1_N")
	)
	(segment
		(start 3.657854 -395.141958)
		(end 3.90525 -395.389354)
		(width 0.174752)
		(layer "B.Cu")
		(net "PE_RX3_DR1_N")
	)
	(segment
		(start 4.825746 -395.389354)
		(end 5.08 -395.1351)
		(width 0.174752)
		(layer "B.Cu")
		(net "PE_RX3_DR1_N")
	)
	(segment
		(start 3.90525 -395.389354)
		(end 4.825746 -395.389354)
		(width 0.174752)
		(layer "B.Cu")
		(net "PE_RX3_DR1_N")
	)
	(segment
		(start 220.313758 -383.812542)
		(end 200.955148 -380.404878)
		(width 0.1651)
		(layer "In2.Cu")
		(net "PE_RX3_DR1_N")
	)
	(segment
		(start 20.576794 -403.545548)
		(end 9.490964 -395.783562)
		(width 0.1651)
		(layer "In2.Cu")
		(net "PE_RX3_DR1_N")
	)
	(segment
		(start 44.86783 -407.829004)
		(end 20.576794 -403.545548)
		(width 0.1651)
		(layer "In2.Cu")
		(net "PE_RX3_DR1_N")
	)
	(segment
		(start 9.490964 -395.783562)
		(end 7.112 -395.364208)
		(width 0.1651)
		(layer "In2.Cu")
		(net "PE_RX3_DR1_N")
	)
	(segment
		(start 221.34576 -383.812542)
		(end 220.313758 -383.812542)
		(width 0.1651)
		(layer "In2.Cu")
		(net "PE_RX3_DR1_N")
	)
	(segment
		(start 5.309108 -395.364208)
		(end 5.08 -395.1351)
		(width 0.1651)
		(layer "In2.Cu")
		(net "PE_RX3_DR1_N")
	)
	(segment
		(start 7.112 -395.364208)
		(end 5.309108 -395.364208)
		(width 0.1651)
		(layer "In2.Cu")
		(net "PE_RX3_DR1_N")
	)
	(segment
		(start 221.727014 -383.431288)
		(end 221.34576 -383.812542)
		(width 0.1651)
		(layer "In2.Cu")
		(net "PE_RX3_DR1_N")
	)
	(segment
		(start 200.611232 -380.404878)
		(end 45.088302 -407.829004)
		(width 0.1651)
		(layer "In2.Cu")
		(net "PE_RX3_DR1_N")
	)
	(arc
		(start 200.955148 -380.404878)
		(mid 200.78319 -380.38984)
		(end 200.611232 -380.404878)
		(width 0.1651)
		(layer "In2.Cu")
		(net "PE_RX3_DR1_N")
	)
	(arc
		(start 45.088302 -407.829004)
		(mid 44.978066 -407.838646)
		(end 44.86783 -407.829004)
		(width 0.1651)
		(layer "In2.Cu")
		(net "PE_RX3_DR1_N")
	)
	(segment
		(start 223.052386 -487.390186)
		(end 222.80499 -487.14279)
		(width 0.174752)
		(layer "F.Cu")
		(net "PE_RX3_DR0_P")
	)
	(segment
		(start 222.80499 -487.14279)
		(end 222.11538 -487.14279)
		(width 0.174752)
		(layer "F.Cu")
		(net "PE_RX3_DR0_P")
	)
	(segment
		(start 221.727014 -487.531156)
		(end 221.727014 -487.548936)
		(width 0.174752)
		(layer "F.Cu")
		(net "PE_RX3_DR0_P")
	)
	(segment
		(start 224.199958 -487.390186)
		(end 223.052386 -487.390186)
		(width 0.174752)
		(layer "F.Cu")
		(net "PE_RX3_DR0_P")
	)
	(segment
		(start 222.11538 -487.14279)
		(end 221.727014 -487.531156)
		(width 0.174752)
		(layer "F.Cu")
		(net "PE_RX3_DR0_P")
	)
	(via
		(at 221.727014 -487.548936)
		(size 0.508)
		(drill 0.254)
		(layers "F.Cu" "B.Cu")
		(net "PE_RX3_DR0_P")
	)
	(via
		(at 5.08 -427.14799)
		(size 0.508)
		(drill 0.254)
		(layers "F.Cu" "B.Cu")
		(net "PE_RX3_DR0_P")
	)
	(segment
		(start 3.658108 -427.141894)
		(end 3.905504 -426.894498)
		(width 0.174752)
		(layer "B.Cu")
		(net "PE_RX3_DR0_P")
	)
	(segment
		(start 1.868932 -427.141894)
		(end 3.658108 -427.141894)
		(width 0.174752)
		(layer "B.Cu")
		(net "PE_RX3_DR0_P")
	)
	(segment
		(start 3.905504 -426.894498)
		(end 4.826508 -426.894498)
		(width 0.174752)
		(layer "B.Cu")
		(net "PE_RX3_DR0_P")
	)
	(segment
		(start 4.826508 -426.894498)
		(end 5.08 -427.14799)
		(width 0.174752)
		(layer "B.Cu")
		(net "PE_RX3_DR0_P")
	)
	(segment
		(start 195.242434 -470.441782)
		(end 218.695778 -486.860596)
		(width 0.1651)
		(layer "In2.Cu")
		(net "PE_RX3_DR0_P")
	)
	(segment
		(start 18.158714 -458.064616)
		(end 18.158968 -458.064616)
		(width 0.1651)
		(layer "In2.Cu")
		(net "PE_RX3_DR0_P")
	)
	(segment
		(start 7.065772 -426.919644)
		(end 8.129016 -427.107096)
		(width 0.1651)
		(layer "In2.Cu")
		(net "PE_RX3_DR0_P")
	)
	(segment
		(start 8.129016 -427.107096)
		(end 9.91489 -428.357792)
		(width 0.1651)
		(layer "In2.Cu")
		(net "PE_RX3_DR0_P")
	)
	(segment
		(start 36.24072 -446.49644)
		(end 36.24072 -446.496186)
		(width 0.1651)
		(layer "In2.Cu")
		(net "PE_RX3_DR0_P")
	)
	(segment
		(start 10.706354 -429.4886)
		(end 14.92504 -453.410828)
		(width 0.1651)
		(layer "In2.Cu")
		(net "PE_RX3_DR0_P")
	)
	(segment
		(start 5.308346 -426.919644)
		(end 7.065772 -426.919644)
		(width 0.1651)
		(layer "In2.Cu")
		(net "PE_RX3_DR0_P")
	)
	(segment
		(start 36.396676 -446.34023)
		(end 36.397438 -446.339722)
		(width 0.1651)
		(layer "In2.Cu")
		(net "PE_RX3_DR0_P")
	)
	(segment
		(start 18.135346 -458.048106)
		(end 18.158714 -458.064616)
		(width 0.1651)
		(layer "In2.Cu")
		(net "PE_RX3_DR0_P")
	)
	(segment
		(start 220.440758 -487.16819)
		(end 221.346268 -487.16819)
		(width 0.1651)
		(layer "In2.Cu")
		(net "PE_RX3_DR0_P")
	)
	(segment
		(start 36.397438 -446.339722)
		(end 40.200834 -443.676532)
		(width 0.1651)
		(layer "In2.Cu")
		(net "PE_RX3_DR0_P")
	)
	(segment
		(start 18.032222 -457.94803)
		(end 18.135346 -458.048106)
		(width 0.1651)
		(layer "In2.Cu")
		(net "PE_RX3_DR0_P")
	)
	(segment
		(start 30.287722 -454.993756)
		(end 36.24072 -446.49644)
		(width 0.1651)
		(layer "In2.Cu")
		(net "PE_RX3_DR0_P")
	)
	(segment
		(start 15.026132 -453.654668)
		(end 15.026386 -453.654922)
		(width 0.1651)
		(layer "In2.Cu")
		(net "PE_RX3_DR0_P")
	)
	(segment
		(start 40.200834 -443.676532)
		(end 41.846754 -443.38621)
		(width 0.1651)
		(layer "In2.Cu")
		(net "PE_RX3_DR0_P")
	)
	(segment
		(start 41.846754 -443.38621)
		(end 195.242434 -470.441782)
		(width 0.1651)
		(layer "In2.Cu")
		(net "PE_RX3_DR0_P")
	)
	(segment
		(start 221.346268 -487.16819)
		(end 221.727014 -487.548936)
		(width 0.1651)
		(layer "In2.Cu")
		(net "PE_RX3_DR0_P")
	)
	(segment
		(start 218.695778 -486.860596)
		(end 220.440758 -487.16819)
		(width 0.1651)
		(layer "In2.Cu")
		(net "PE_RX3_DR0_P")
	)
	(segment
		(start 18.158968 -458.064616)
		(end 20.079716 -459.409546)
		(width 0.1651)
		(layer "In2.Cu")
		(net "PE_RX3_DR0_P")
	)
	(segment
		(start 30.18409 -455.09561)
		(end 30.287722 -454.993756)
		(width 0.1651)
		(layer "In2.Cu")
		(net "PE_RX3_DR0_P")
	)
	(segment
		(start 15.026386 -453.654922)
		(end 18.032222 -457.94803)
		(width 0.1651)
		(layer "In2.Cu")
		(net "PE_RX3_DR0_P")
	)
	(segment
		(start 5.08 -427.14799)
		(end 5.308346 -426.919644)
		(width 0.1651)
		(layer "In2.Cu")
		(net "PE_RX3_DR0_P")
	)
	(segment
		(start 9.91489 -428.357792)
		(end 10.706354 -429.4886)
		(width 0.1651)
		(layer "In2.Cu")
		(net "PE_RX3_DR0_P")
	)
	(segment
		(start 24.092662 -459.36027)
		(end 30.18409 -455.09561)
		(width 0.1651)
		(layer "In2.Cu")
		(net "PE_RX3_DR0_P")
	)
	(segment
		(start 22.11959 -459.787752)
		(end 23.856188 -459.459838)
		(width 0.1651)
		(layer "In2.Cu")
		(net "PE_RX3_DR0_P")
	)
	(segment
		(start 20.323556 -459.510638)
		(end 21.900388 -459.789022)
		(width 0.1651)
		(layer "In2.Cu")
		(net "PE_RX3_DR0_P")
	)
	(arc
		(start 21.900388 -459.789022)
		(mid 22.010047 -459.79833)
		(end 22.11959 -459.787752)
		(width 0.1651)
		(layer "In2.Cu")
		(net "PE_RX3_DR0_P")
	)
	(arc
		(start 20.079716 -459.409546)
		(mid 20.1961 -459.473444)
		(end 20.323556 -459.510638)
		(width 0.1651)
		(layer "In2.Cu")
		(net "PE_RX3_DR0_P")
	)
	(arc
		(start 36.24072 -446.496186)
		(mid 36.311875 -446.411385)
		(end 36.396676 -446.34023)
		(width 0.1651)
		(layer "In2.Cu")
		(net "PE_RX3_DR0_P")
	)
	(arc
		(start 23.856188 -459.459838)
		(mid 23.979719 -459.42263)
		(end 24.092662 -459.36027)
		(width 0.1651)
		(layer "In2.Cu")
		(net "PE_RX3_DR0_P")
	)
	(arc
		(start 14.92504 -453.410828)
		(mid 14.962219 -453.538291)
		(end 15.026132 -453.654668)
		(width 0.1651)
		(layer "In2.Cu")
		(net "PE_RX3_DR0_P")
	)
	(segment
		(start 222.133414 -486.837736)
		(end 221.727014 -486.431336)
		(width 0.174752)
		(layer "F.Cu")
		(net "PE_RX3_DR0_N")
	)
	(segment
		(start 222.838264 -486.837736)
		(end 222.133414 -486.837736)
		(width 0.174752)
		(layer "F.Cu")
		(net "PE_RX3_DR0_N")
	)
	(segment
		(start 223.085914 -486.590086)
		(end 222.838264 -486.837736)
		(width 0.174752)
		(layer "F.Cu")
		(net "PE_RX3_DR0_N")
	)
	(segment
		(start 224.199958 -486.590086)
		(end 223.085914 -486.590086)
		(width 0.174752)
		(layer "F.Cu")
		(net "PE_RX3_DR0_N")
	)
	(via
		(at 221.727014 -486.431336)
		(size 0.508)
		(drill 0.254)
		(layers "F.Cu" "B.Cu")
		(net "PE_RX3_DR0_N")
	)
	(via
		(at 5.08 -426.33519)
		(size 0.508)
		(drill 0.254)
		(layers "F.Cu" "B.Cu")
		(net "PE_RX3_DR0_N")
	)
	(segment
		(start 4.825746 -426.589444)
		(end 5.08 -426.33519)
		(width 0.174752)
		(layer "B.Cu")
		(net "PE_RX3_DR0_N")
	)
	(segment
		(start 1.868932 -426.341794)
		(end 3.657854 -426.341794)
		(width 0.174752)
		(layer "B.Cu")
		(net "PE_RX3_DR0_N")
	)
	(segment
		(start 3.905504 -426.589444)
		(end 4.825746 -426.589444)
		(width 0.174752)
		(layer "B.Cu")
		(net "PE_RX3_DR0_N")
	)
	(segment
		(start 3.657854 -426.341794)
		(end 3.905504 -426.589444)
		(width 0.174752)
		(layer "B.Cu")
		(net "PE_RX3_DR0_N")
	)
	(segment
		(start 29.955744 -454.821036)
		(end 30.014926 -454.76287)
		(width 0.1651)
		(layer "In2.Cu")
		(net "PE_RX3_DR0_N")
	)
	(segment
		(start 41.846754 -443.025022)
		(end 195.38188 -470.105232)
		(width 0.1651)
		(layer "In2.Cu")
		(net "PE_RX3_DR0_N")
	)
	(segment
		(start 20.385278 -459.160372)
		(end 21.96211 -459.438756)
		(width 0.1651)
		(layer "In2.Cu")
		(net "PE_RX3_DR0_N")
	)
	(segment
		(start 218.835224 -486.524046)
		(end 220.472 -486.81259)
		(width 0.1651)
		(layer "In2.Cu")
		(net "PE_RX3_DR0_N")
	)
	(segment
		(start 15.275306 -453.349106)
		(end 15.27556 -453.349106)
		(width 0.1651)
		(layer "In2.Cu")
		(net "PE_RX3_DR0_N")
	)
	(segment
		(start 15.317724 -453.450706)
		(end 18.303748 -457.71562)
		(width 0.1651)
		(layer "In2.Cu")
		(net "PE_RX3_DR0_N")
	)
	(segment
		(start 22.05355 -459.438248)
		(end 23.790148 -459.11008)
		(width 0.1651)
		(layer "In2.Cu")
		(net "PE_RX3_DR0_N")
	)
	(segment
		(start 5.08 -426.33519)
		(end 5.308854 -426.564044)
		(width 0.1651)
		(layer "In2.Cu")
		(net "PE_RX3_DR0_N")
	)
	(segment
		(start 19.323558 -458.44587)
		(end 20.283678 -459.118208)
		(width 0.1651)
		(layer "In2.Cu")
		(net "PE_RX3_DR0_N")
	)
	(segment
		(start 8.268462 -426.770546)
		(end 10.170414 -428.102268)
		(width 0.1651)
		(layer "In2.Cu")
		(net "PE_RX3_DR0_N")
	)
	(segment
		(start 195.38188 -470.105232)
		(end 218.835224 -486.524046)
		(width 0.1651)
		(layer "In2.Cu")
		(net "PE_RX3_DR0_N")
	)
	(segment
		(start 7.097014 -426.564044)
		(end 8.268462 -426.770546)
		(width 0.1651)
		(layer "In2.Cu")
		(net "PE_RX3_DR0_N")
	)
	(segment
		(start 36.193222 -446.04813)
		(end 40.061642 -443.339728)
		(width 0.1651)
		(layer "In2.Cu")
		(net "PE_RX3_DR0_N")
	)
	(segment
		(start 18.303748 -457.71562)
		(end 18.36293 -457.773278)
		(width 0.1651)
		(layer "In2.Cu")
		(net "PE_RX3_DR0_N")
	)
	(segment
		(start 5.308854 -426.564044)
		(end 7.097014 -426.564044)
		(width 0.1651)
		(layer "In2.Cu")
		(net "PE_RX3_DR0_N")
	)
	(segment
		(start 40.061642 -443.339728)
		(end 41.846754 -443.025022)
		(width 0.1651)
		(layer "In2.Cu")
		(net "PE_RX3_DR0_N")
	)
	(segment
		(start 18.36293 -457.773278)
		(end 19.323558 -458.44587)
		(width 0.1651)
		(layer "In2.Cu")
		(net "PE_RX3_DR0_N")
	)
	(segment
		(start 23.8887 -459.068678)
		(end 29.955744 -454.821036)
		(width 0.1651)
		(layer "In2.Cu")
		(net "PE_RX3_DR0_N")
	)
	(segment
		(start 11.049254 -429.385222)
		(end 11.049254 -429.384968)
		(width 0.1651)
		(layer "In2.Cu")
		(net "PE_RX3_DR0_N")
	)
	(segment
		(start 221.34576 -486.81259)
		(end 221.727014 -486.431336)
		(width 0.1651)
		(layer "In2.Cu")
		(net "PE_RX3_DR0_N")
	)
	(segment
		(start 10.170414 -428.102268)
		(end 11.021822 -429.319182)
		(width 0.1651)
		(layer "In2.Cu")
		(net "PE_RX3_DR0_N")
	)
	(segment
		(start 15.317724 -453.45096)
		(end 15.317724 -453.450706)
		(width 0.1651)
		(layer "In2.Cu")
		(net "PE_RX3_DR0_N")
	)
	(segment
		(start 220.472 -486.81259)
		(end 221.34576 -486.81259)
		(width 0.1651)
		(layer "In2.Cu")
		(net "PE_RX3_DR0_N")
	)
	(segment
		(start 11.049254 -429.384968)
		(end 15.275306 -453.349106)
		(width 0.1651)
		(layer "In2.Cu")
		(net "PE_RX3_DR0_N")
	)
	(segment
		(start 30.014926 -454.76287)
		(end 35.949382 -446.292224)
		(width 0.1651)
		(layer "In2.Cu")
		(net "PE_RX3_DR0_N")
	)
	(segment
		(start 35.949382 -446.292224)
		(end 35.950144 -446.291208)
		(width 0.1651)
		(layer "In2.Cu")
		(net "PE_RX3_DR0_N")
	)
	(arc
		(start 20.283678 -459.118208)
		(mid 20.332173 -459.144839)
		(end 20.385278 -459.160372)
		(width 0.1651)
		(layer "In2.Cu")
		(net "PE_RX3_DR0_N")
	)
	(arc
		(start 21.96211 -459.438756)
		(mid 22.007855 -459.442671)
		(end 22.05355 -459.438248)
		(width 0.1651)
		(layer "In2.Cu")
		(net "PE_RX3_DR0_N")
	)
	(arc
		(start 35.950144 -446.291208)
		(mid 36.061057 -446.159043)
		(end 36.193222 -446.04813)
		(width 0.1651)
		(layer "In2.Cu")
		(net "PE_RX3_DR0_N")
	)
	(arc
		(start 23.790148 -459.11008)
		(mid 23.841636 -459.09464)
		(end 23.8887 -459.068678)
		(width 0.1651)
		(layer "In2.Cu")
		(net "PE_RX3_DR0_N")
	)
	(arc
		(start 11.021822 -429.319182)
		(mid 11.039137 -429.350704)
		(end 11.049254 -429.385222)
		(width 0.1651)
		(layer "In2.Cu")
		(net "PE_RX3_DR0_N")
	)
	(arc
		(start 15.27556 -453.349106)
		(mid 15.291055 -453.402345)
		(end 15.317724 -453.45096)
		(width 0.1651)
		(layer "In2.Cu")
		(net "PE_RX3_DR0_N")
	)
	(segment
		(start 37.133276 -70.342506)
		(end 36.72713 -70.748652)
		(width 0.174752)
		(layer "F.Cu")
		(net "PE_RX2_DR9_P")
	)
	(segment
		(start 39.200074 -70.589902)
		(end 38.1 -70.589902)
		(width 0.174752)
		(layer "F.Cu")
		(net "PE_RX2_DR9_P")
	)
	(segment
		(start 38.1 -70.589902)
		(end 37.852604 -70.342506)
		(width 0.174752)
		(layer "F.Cu")
		(net "PE_RX2_DR9_P")
	)
	(segment
		(start 37.852604 -70.342506)
		(end 37.133276 -70.342506)
		(width 0.174752)
		(layer "F.Cu")
		(net "PE_RX2_DR9_P")
	)
	(via
		(at 5.08 -183.948324)
		(size 0.508)
		(drill 0.254)
		(layers "F.Cu" "B.Cu")
		(net "PE_RX2_DR9_P")
	)
	(via
		(at 36.72713 -70.748652)
		(size 0.508)
		(drill 0.254)
		(layers "F.Cu" "B.Cu")
		(net "PE_RX2_DR9_P")
	)
	(segment
		(start 3.905504 -183.694578)
		(end 4.826254 -183.694578)
		(width 0.174752)
		(layer "B.Cu")
		(net "PE_RX2_DR9_P")
	)
	(segment
		(start 3.657854 -183.942228)
		(end 3.905504 -183.694578)
		(width 0.174752)
		(layer "B.Cu")
		(net "PE_RX2_DR9_P")
	)
	(segment
		(start 1.868932 -183.942228)
		(end 3.657854 -183.942228)
		(width 0.174752)
		(layer "B.Cu")
		(net "PE_RX2_DR9_P")
	)
	(segment
		(start 4.826254 -183.694578)
		(end 5.08 -183.948324)
		(width 0.174752)
		(layer "B.Cu")
		(net "PE_RX2_DR9_P")
	)
	(segment
		(start 20.611084 -85.019896)
		(end 28.259024 -74.097388)
		(width 0.1651)
		(layer "In2.Cu")
		(net "PE_RX2_DR9_P")
	)
	(segment
		(start 42.544238 -102.575106)
		(end 39.891208 -100.717604)
		(width 0.1651)
		(layer "In2.Cu")
		(net "PE_RX2_DR9_P")
	)
	(segment
		(start 35.482022 -70.367906)
		(end 36.346384 -70.367906)
		(width 0.1651)
		(layer "In2.Cu")
		(net "PE_RX2_DR9_P")
	)
	(segment
		(start 35.063176 -146.104102)
		(end 40.472614 -115.431062)
		(width 0.1651)
		(layer "In2.Cu")
		(net "PE_RX2_DR9_P")
	)
	(segment
		(start 31.39313 -151.345646)
		(end 35.063176 -146.104102)
		(width 0.1651)
		(layer "In2.Cu")
		(net "PE_RX2_DR9_P")
	)
	(segment
		(start 5.308346 -183.719978)
		(end 7.143242 -183.719978)
		(width 0.1651)
		(layer "In2.Cu")
		(net "PE_RX2_DR9_P")
	)
	(segment
		(start 19.874738 -89.19718)
		(end 20.611084 -85.019896)
		(width 0.1651)
		(layer "In2.Cu")
		(net "PE_RX2_DR9_P")
	)
	(segment
		(start 20.650962 -93.597984)
		(end 19.874738 -89.19718)
		(width 0.1651)
		(layer "In2.Cu")
		(net "PE_RX2_DR9_P")
	)
	(segment
		(start 39.891208 -100.717604)
		(end 25.046178 -98.099118)
		(width 0.1651)
		(layer "In2.Cu")
		(net "PE_RX2_DR9_P")
	)
	(segment
		(start 43.765216 -106.172)
		(end 43.328336 -103.695246)
		(width 0.1651)
		(layer "In2.Cu")
		(net "PE_RX2_DR9_P")
	)
	(segment
		(start 27.892756 -171.191428)
		(end 31.39313 -151.345646)
		(width 0.1651)
		(layer "In2.Cu")
		(net "PE_RX2_DR9_P")
	)
	(segment
		(start 42.690796 -112.263174)
		(end 43.765216 -106.172)
		(width 0.1651)
		(layer "In2.Cu")
		(net "PE_RX2_DR9_P")
	)
	(segment
		(start 43.328336 -103.695246)
		(end 42.544238 -102.575106)
		(width 0.1651)
		(layer "In2.Cu")
		(net "PE_RX2_DR9_P")
	)
	(segment
		(start 22.416516 -179.011834)
		(end 27.892756 -171.191428)
		(width 0.1651)
		(layer "In2.Cu")
		(net "PE_RX2_DR9_P")
	)
	(segment
		(start 7.143242 -183.719978)
		(end 18.569178 -181.705758)
		(width 0.1651)
		(layer "In2.Cu")
		(net "PE_RX2_DR9_P")
	)
	(segment
		(start 32.946848 -70.814946)
		(end 35.482022 -70.367906)
		(width 0.1651)
		(layer "In2.Cu")
		(net "PE_RX2_DR9_P")
	)
	(segment
		(start 22.607524 -96.391476)
		(end 20.650962 -93.597984)
		(width 0.1651)
		(layer "In2.Cu")
		(net "PE_RX2_DR9_P")
	)
	(segment
		(start 28.259024 -74.097388)
		(end 32.946848 -70.814946)
		(width 0.1651)
		(layer "In2.Cu")
		(net "PE_RX2_DR9_P")
	)
	(segment
		(start 40.472614 -115.431062)
		(end 42.690796 -112.263174)
		(width 0.1651)
		(layer "In2.Cu")
		(net "PE_RX2_DR9_P")
	)
	(segment
		(start 5.08 -183.948324)
		(end 5.308346 -183.719978)
		(width 0.1651)
		(layer "In2.Cu")
		(net "PE_RX2_DR9_P")
	)
	(segment
		(start 36.346384 -70.367906)
		(end 36.72713 -70.748652)
		(width 0.1651)
		(layer "In2.Cu")
		(net "PE_RX2_DR9_P")
	)
	(segment
		(start 18.569178 -181.705758)
		(end 22.416516 -179.011834)
		(width 0.1651)
		(layer "In2.Cu")
		(net "PE_RX2_DR9_P")
	)
	(segment
		(start 25.046178 -98.099118)
		(end 22.607524 -96.391476)
		(width 0.1651)
		(layer "In2.Cu")
		(net "PE_RX2_DR9_P")
	)
	(segment
		(start 37.13353 -70.037452)
		(end 36.72713 -69.631052)
		(width 0.174752)
		(layer "F.Cu")
		(net "PE_RX2_DR9_N")
	)
	(segment
		(start 39.200074 -69.789802)
		(end 38.09365 -69.789802)
		(width 0.174752)
		(layer "F.Cu")
		(net "PE_RX2_DR9_N")
	)
	(segment
		(start 37.846 -70.037452)
		(end 37.13353 -70.037452)
		(width 0.174752)
		(layer "F.Cu")
		(net "PE_RX2_DR9_N")
	)
	(segment
		(start 38.09365 -69.789802)
		(end 37.846 -70.037452)
		(width 0.174752)
		(layer "F.Cu")
		(net "PE_RX2_DR9_N")
	)
	(via
		(at 36.72713 -69.631052)
		(size 0.508)
		(drill 0.254)
		(layers "F.Cu" "B.Cu")
		(net "PE_RX2_DR9_N")
	)
	(via
		(at 5.08 -183.135524)
		(size 0.508)
		(drill 0.254)
		(layers "F.Cu" "B.Cu")
		(net "PE_RX2_DR9_N")
	)
	(segment
		(start 4.826 -183.389524)
		(end 5.08 -183.135524)
		(width 0.174752)
		(layer "B.Cu")
		(net "PE_RX2_DR9_N")
	)
	(segment
		(start 3.905504 -183.389524)
		(end 4.826 -183.389524)
		(width 0.174752)
		(layer "B.Cu")
		(net "PE_RX2_DR9_N")
	)
	(segment
		(start 3.658108 -183.142128)
		(end 3.905504 -183.389524)
		(width 0.174752)
		(layer "B.Cu")
		(net "PE_RX2_DR9_N")
	)
	(segment
		(start 1.868932 -183.142128)
		(end 3.658108 -183.142128)
		(width 0.174752)
		(layer "B.Cu")
		(net "PE_RX2_DR9_N")
	)
	(segment
		(start 39.751762 -101.054154)
		(end 42.288714 -102.83063)
		(width 0.1651)
		(layer "In2.Cu")
		(net "PE_RX2_DR9_N")
	)
	(segment
		(start 19.51355 -89.19718)
		(end 20.314412 -93.73743)
		(width 0.1651)
		(layer "In2.Cu")
		(net "PE_RX2_DR9_N")
	)
	(segment
		(start 22.160992 -178.75631)
		(end 18.429732 -181.369208)
		(width 0.1651)
		(layer "In2.Cu")
		(net "PE_RX2_DR9_N")
	)
	(segment
		(start 36.72713 -69.631052)
		(end 36.345876 -70.012306)
		(width 0.1651)
		(layer "In2.Cu")
		(net "PE_RX2_DR9_N")
	)
	(segment
		(start 20.274534 -84.88045)
		(end 19.51355 -89.19718)
		(width 0.1651)
		(layer "In2.Cu")
		(net "PE_RX2_DR9_N")
	)
	(segment
		(start 5.308854 -183.364378)
		(end 5.08 -183.135524)
		(width 0.1651)
		(layer "In2.Cu")
		(net "PE_RX2_DR9_N")
	)
	(segment
		(start 18.429732 -181.369208)
		(end 9.150858 -183.004968)
		(width 0.1651)
		(layer "In2.Cu")
		(net "PE_RX2_DR9_N")
	)
	(segment
		(start 20.314412 -93.73743)
		(end 22.352 -96.647)
		(width 0.1651)
		(layer "In2.Cu")
		(net "PE_RX2_DR9_N")
	)
	(segment
		(start 36.345876 -70.012306)
		(end 35.45078 -70.012306)
		(width 0.1651)
		(layer "In2.Cu")
		(net "PE_RX2_DR9_N")
	)
	(segment
		(start 9.150858 -183.004968)
		(end 8.244586 -183.164734)
		(width 0.1651)
		(layer "In2.Cu")
		(net "PE_RX2_DR9_N")
	)
	(segment
		(start 42.288714 -102.83063)
		(end 42.991786 -103.834692)
		(width 0.1651)
		(layer "In2.Cu")
		(net "PE_RX2_DR9_N")
	)
	(segment
		(start 34.611818 -146.128486)
		(end 34.49447 -146.296126)
		(width 0.1651)
		(layer "In2.Cu")
		(net "PE_RX2_DR9_N")
	)
	(segment
		(start 43.404028 -106.172)
		(end 42.354246 -112.123728)
		(width 0.1651)
		(layer "In2.Cu")
		(net "PE_RX2_DR9_N")
	)
	(segment
		(start 42.354246 -112.123728)
		(end 40.136064 -115.291616)
		(width 0.1651)
		(layer "In2.Cu")
		(net "PE_RX2_DR9_N")
	)
	(segment
		(start 40.136064 -115.291616)
		(end 34.726372 -145.964656)
		(width 0.1651)
		(layer "In2.Cu")
		(net "PE_RX2_DR9_N")
	)
	(segment
		(start 28.0035 -73.841864)
		(end 20.274534 -84.88045)
		(width 0.1651)
		(layer "In2.Cu")
		(net "PE_RX2_DR9_N")
	)
	(segment
		(start 7.112 -183.364378)
		(end 5.308854 -183.364378)
		(width 0.1651)
		(layer "In2.Cu")
		(net "PE_RX2_DR9_N")
	)
	(segment
		(start 35.45078 -70.012306)
		(end 32.807402 -70.478396)
		(width 0.1651)
		(layer "In2.Cu")
		(net "PE_RX2_DR9_N")
	)
	(segment
		(start 27.556206 -171.051982)
		(end 22.160992 -178.75631)
		(width 0.1651)
		(layer "In2.Cu")
		(net "PE_RX2_DR9_N")
	)
	(segment
		(start 34.726372 -145.964656)
		(end 34.611818 -146.128486)
		(width 0.1651)
		(layer "In2.Cu")
		(net "PE_RX2_DR9_N")
	)
	(segment
		(start 22.352 -96.647)
		(end 24.906732 -98.435668)
		(width 0.1651)
		(layer "In2.Cu")
		(net "PE_RX2_DR9_N")
	)
	(segment
		(start 34.49447 -146.296126)
		(end 31.05658 -151.2062)
		(width 0.1651)
		(layer "In2.Cu")
		(net "PE_RX2_DR9_N")
	)
	(segment
		(start 31.05658 -151.2062)
		(end 27.556206 -171.051982)
		(width 0.1651)
		(layer "In2.Cu")
		(net "PE_RX2_DR9_N")
	)
	(segment
		(start 24.906732 -98.435668)
		(end 39.751762 -101.054154)
		(width 0.1651)
		(layer "In2.Cu")
		(net "PE_RX2_DR9_N")
	)
	(segment
		(start 8.244586 -183.164734)
		(end 7.112 -183.364378)
		(width 0.1651)
		(layer "In2.Cu")
		(net "PE_RX2_DR9_N")
	)
	(segment
		(start 32.807402 -70.478396)
		(end 28.0035 -73.841864)
		(width 0.1651)
		(layer "In2.Cu")
		(net "PE_RX2_DR9_N")
	)
	(segment
		(start 42.991786 -103.834692)
		(end 43.404028 -106.172)
		(width 0.1651)
		(layer "In2.Cu")
		(net "PE_RX2_DR9_N")
	)
	(segment
		(start 37.852604 -173.342554)
		(end 37.133276 -173.342554)
		(width 0.174752)
		(layer "F.Cu")
		(net "PE_RX2_DR8_P")
	)
	(segment
		(start 37.133276 -173.342554)
		(end 36.72713 -173.7487)
		(width 0.174752)
		(layer "F.Cu")
		(net "PE_RX2_DR8_P")
	)
	(segment
		(start 38.1 -173.58995)
		(end 37.852604 -173.342554)
		(width 0.174752)
		(layer "F.Cu")
		(net "PE_RX2_DR8_P")
	)
	(segment
		(start 39.200074 -173.58995)
		(end 38.1 -173.58995)
		(width 0.174752)
		(layer "F.Cu")
		(net "PE_RX2_DR8_P")
	)
	(via
		(at 5.08 -203.948284)
		(size 0.508)
		(drill 0.254)
		(layers "F.Cu" "B.Cu")
		(net "PE_RX2_DR8_P")
	)
	(via
		(at 36.72713 -173.7487)
		(size 0.508)
		(drill 0.254)
		(layers "F.Cu" "B.Cu")
		(net "PE_RX2_DR8_P")
	)
	(segment
		(start 3.657854 -203.942188)
		(end 3.905504 -203.694538)
		(width 0.174752)
		(layer "B.Cu")
		(net "PE_RX2_DR8_P")
	)
	(segment
		(start 4.826254 -203.694538)
		(end 5.08 -203.948284)
		(width 0.174752)
		(layer "B.Cu")
		(net "PE_RX2_DR8_P")
	)
	(segment
		(start 1.868932 -203.942188)
		(end 3.657854 -203.942188)
		(width 0.174752)
		(layer "B.Cu")
		(net "PE_RX2_DR8_P")
	)
	(segment
		(start 3.905504 -203.694538)
		(end 4.826254 -203.694538)
		(width 0.174752)
		(layer "B.Cu")
		(net "PE_RX2_DR8_P")
	)
	(segment
		(start 8.062976 -203.552044)
		(end 7.112 -203.719938)
		(width 0.1651)
		(layer "In2.Cu")
		(net "PE_RX2_DR8_P")
	)
	(segment
		(start 36.346384 -173.367954)
		(end 35.482022 -173.367954)
		(width 0.1651)
		(layer "In2.Cu")
		(net "PE_RX2_DR8_P")
	)
	(segment
		(start 28.898088 -176.941734)
		(end 12.383516 -200.527158)
		(width 0.1651)
		(layer "In2.Cu")
		(net "PE_RX2_DR8_P")
	)
	(segment
		(start 33.503362 -173.717204)
		(end 28.898088 -176.941734)
		(width 0.1651)
		(layer "In2.Cu")
		(net "PE_RX2_DR8_P")
	)
	(segment
		(start 7.112 -203.719938)
		(end 5.308346 -203.719938)
		(width 0.1651)
		(layer "In2.Cu")
		(net "PE_RX2_DR8_P")
	)
	(segment
		(start 35.482022 -173.367954)
		(end 33.503362 -173.717204)
		(width 0.1651)
		(layer "In2.Cu")
		(net "PE_RX2_DR8_P")
	)
	(segment
		(start 5.308346 -203.719938)
		(end 5.08 -203.948284)
		(width 0.1651)
		(layer "In2.Cu")
		(net "PE_RX2_DR8_P")
	)
	(segment
		(start 12.383516 -200.527158)
		(end 8.062976 -203.552044)
		(width 0.1651)
		(layer "In2.Cu")
		(net "PE_RX2_DR8_P")
	)
	(segment
		(start 36.72713 -173.7487)
		(end 36.346384 -173.367954)
		(width 0.1651)
		(layer "In2.Cu")
		(net "PE_RX2_DR8_P")
	)
	(segment
		(start 39.200074 -172.78985)
		(end 38.09365 -172.78985)
		(width 0.174752)
		(layer "F.Cu")
		(net "PE_RX2_DR8_N")
	)
	(segment
		(start 37.846 -173.0375)
		(end 37.13353 -173.0375)
		(width 0.174752)
		(layer "F.Cu")
		(net "PE_RX2_DR8_N")
	)
	(segment
		(start 37.13353 -173.0375)
		(end 36.72713 -172.6311)
		(width 0.174752)
		(layer "F.Cu")
		(net "PE_RX2_DR8_N")
	)
	(segment
		(start 38.09365 -172.78985)
		(end 37.846 -173.0375)
		(width 0.174752)
		(layer "F.Cu")
		(net "PE_RX2_DR8_N")
	)
	(via
		(at 5.08 -203.135484)
		(size 0.508)
		(drill 0.254)
		(layers "F.Cu" "B.Cu")
		(net "PE_RX2_DR8_N")
	)
	(via
		(at 36.72713 -172.6311)
		(size 0.508)
		(drill 0.254)
		(layers "F.Cu" "B.Cu")
		(net "PE_RX2_DR8_N")
	)
	(segment
		(start 3.905504 -203.389484)
		(end 4.826 -203.389484)
		(width 0.174752)
		(layer "B.Cu")
		(net "PE_RX2_DR8_N")
	)
	(segment
		(start 4.826 -203.389484)
		(end 5.08 -203.135484)
		(width 0.174752)
		(layer "B.Cu")
		(net "PE_RX2_DR8_N")
	)
	(segment
		(start 1.868932 -203.142088)
		(end 3.658108 -203.142088)
		(width 0.174752)
		(layer "B.Cu")
		(net "PE_RX2_DR8_N")
	)
	(segment
		(start 3.658108 -203.142088)
		(end 3.905504 -203.389484)
		(width 0.174752)
		(layer "B.Cu")
		(net "PE_RX2_DR8_N")
	)
	(segment
		(start 35.45078 -173.012354)
		(end 33.363916 -173.380654)
		(width 0.1651)
		(layer "In2.Cu")
		(net "PE_RX2_DR8_N")
	)
	(segment
		(start 36.345876 -173.012354)
		(end 35.45078 -173.012354)
		(width 0.1651)
		(layer "In2.Cu")
		(net "PE_RX2_DR8_N")
	)
	(segment
		(start 33.363916 -173.380654)
		(end 28.642564 -176.68621)
		(width 0.1651)
		(layer "In2.Cu")
		(net "PE_RX2_DR8_N")
	)
	(segment
		(start 7.92353 -203.215494)
		(end 7.080758 -203.364338)
		(width 0.1651)
		(layer "In2.Cu")
		(net "PE_RX2_DR8_N")
	)
	(segment
		(start 7.080758 -203.364338)
		(end 5.308854 -203.364338)
		(width 0.1651)
		(layer "In2.Cu")
		(net "PE_RX2_DR8_N")
	)
	(segment
		(start 28.642564 -176.68621)
		(end 12.127992 -200.271634)
		(width 0.1651)
		(layer "In2.Cu")
		(net "PE_RX2_DR8_N")
	)
	(segment
		(start 12.127992 -200.271634)
		(end 7.92353 -203.215494)
		(width 0.1651)
		(layer "In2.Cu")
		(net "PE_RX2_DR8_N")
	)
	(segment
		(start 5.308854 -203.364338)
		(end 5.08 -203.135484)
		(width 0.1651)
		(layer "In2.Cu")
		(net "PE_RX2_DR8_N")
	)
	(segment
		(start 36.72713 -172.6311)
		(end 36.345876 -173.012354)
		(width 0.1651)
		(layer "In2.Cu")
		(net "PE_RX2_DR8_N")
	)
	(segment
		(start 37.133276 -276.342602)
		(end 36.72713 -276.748748)
		(width 0.174752)
		(layer "F.Cu")
		(net "PE_RX2_DR7_P")
	)
	(segment
		(start 37.852604 -276.342602)
		(end 37.133276 -276.342602)
		(width 0.174752)
		(layer "F.Cu")
		(net "PE_RX2_DR7_P")
	)
	(segment
		(start 39.200074 -276.589998)
		(end 38.1 -276.589998)
		(width 0.174752)
		(layer "F.Cu")
		(net "PE_RX2_DR7_P")
	)
	(segment
		(start 38.1 -276.589998)
		(end 37.852604 -276.342602)
		(width 0.174752)
		(layer "F.Cu")
		(net "PE_RX2_DR7_P")
	)
	(via
		(at 36.72713 -276.748748)
		(size 0.508)
		(drill 0.254)
		(layers "F.Cu" "B.Cu")
		(net "PE_RX2_DR7_P")
	)
	(via
		(at 5.08 -306.74818)
		(size 0.508)
		(drill 0.254)
		(layers "F.Cu" "B.Cu")
		(net "PE_RX2_DR7_P")
	)
	(segment
		(start 4.826254 -306.494434)
		(end 5.08 -306.74818)
		(width 0.174752)
		(layer "B.Cu")
		(net "PE_RX2_DR7_P")
	)
	(segment
		(start 1.868932 -306.742084)
		(end 3.657854 -306.742084)
		(width 0.174752)
		(layer "B.Cu")
		(net "PE_RX2_DR7_P")
	)
	(segment
		(start 3.657854 -306.742084)
		(end 3.905504 -306.494434)
		(width 0.174752)
		(layer "B.Cu")
		(net "PE_RX2_DR7_P")
	)
	(segment
		(start 3.905504 -306.494434)
		(end 4.826254 -306.494434)
		(width 0.174752)
		(layer "B.Cu")
		(net "PE_RX2_DR7_P")
	)
	(segment
		(start 36.72713 -276.748748)
		(end 36.346384 -276.368002)
		(width 0.1651)
		(layer "In2.Cu")
		(net "PE_RX2_DR7_P")
	)
	(segment
		(start 36.346384 -276.368002)
		(end 35.513264 -276.368002)
		(width 0.1651)
		(layer "In2.Cu")
		(net "PE_RX2_DR7_P")
	)
	(segment
		(start 11.386566 -304.62601)
		(end 9.210294 -306.149756)
		(width 0.1651)
		(layer "In2.Cu")
		(net "PE_RX2_DR7_P")
	)
	(segment
		(start 35.513264 -276.368002)
		(end 32.734758 -276.858476)
		(width 0.1651)
		(layer "In2.Cu")
		(net "PE_RX2_DR7_P")
	)
	(segment
		(start 7.112 -306.519834)
		(end 5.308346 -306.519834)
		(width 0.1651)
		(layer "In2.Cu")
		(net "PE_RX2_DR7_P")
	)
	(segment
		(start 28.996386 -279.4762)
		(end 11.386566 -304.62601)
		(width 0.1651)
		(layer "In2.Cu")
		(net "PE_RX2_DR7_P")
	)
	(segment
		(start 9.210294 -306.149756)
		(end 7.112 -306.519834)
		(width 0.1651)
		(layer "In2.Cu")
		(net "PE_RX2_DR7_P")
	)
	(segment
		(start 5.308346 -306.519834)
		(end 5.08 -306.74818)
		(width 0.1651)
		(layer "In2.Cu")
		(net "PE_RX2_DR7_P")
	)
	(segment
		(start 32.734758 -276.858476)
		(end 28.996386 -279.4762)
		(width 0.1651)
		(layer "In2.Cu")
		(net "PE_RX2_DR7_P")
	)
	(segment
		(start 37.846 -276.037548)
		(end 37.13353 -276.037548)
		(width 0.174752)
		(layer "F.Cu")
		(net "PE_RX2_DR7_N")
	)
	(segment
		(start 39.200074 -275.789898)
		(end 38.09365 -275.789898)
		(width 0.174752)
		(layer "F.Cu")
		(net "PE_RX2_DR7_N")
	)
	(segment
		(start 38.09365 -275.789898)
		(end 37.846 -276.037548)
		(width 0.174752)
		(layer "F.Cu")
		(net "PE_RX2_DR7_N")
	)
	(segment
		(start 37.13353 -276.037548)
		(end 36.72713 -275.631148)
		(width 0.174752)
		(layer "F.Cu")
		(net "PE_RX2_DR7_N")
	)
	(via
		(at 36.72713 -275.631148)
		(size 0.508)
		(drill 0.254)
		(layers "F.Cu" "B.Cu")
		(net "PE_RX2_DR7_N")
	)
	(via
		(at 5.08 -305.93538)
		(size 0.508)
		(drill 0.254)
		(layers "F.Cu" "B.Cu")
		(net "PE_RX2_DR7_N")
	)
	(segment
		(start 3.658108 -305.941984)
		(end 3.905504 -306.18938)
		(width 0.174752)
		(layer "B.Cu")
		(net "PE_RX2_DR7_N")
	)
	(segment
		(start 1.868932 -305.941984)
		(end 3.658108 -305.941984)
		(width 0.174752)
		(layer "B.Cu")
		(net "PE_RX2_DR7_N")
	)
	(segment
		(start 3.905504 -306.18938)
		(end 4.826 -306.18938)
		(width 0.174752)
		(layer "B.Cu")
		(net "PE_RX2_DR7_N")
	)
	(segment
		(start 4.826 -306.18938)
		(end 5.08 -305.93538)
		(width 0.174752)
		(layer "B.Cu")
		(net "PE_RX2_DR7_N")
	)
	(segment
		(start 7.080758 -306.164234)
		(end 5.308854 -306.164234)
		(width 0.1651)
		(layer "In2.Cu")
		(net "PE_RX2_DR7_N")
	)
	(segment
		(start 36.72713 -275.631148)
		(end 36.345876 -276.012402)
		(width 0.1651)
		(layer "In2.Cu")
		(net "PE_RX2_DR7_N")
	)
	(segment
		(start 36.345876 -276.012402)
		(end 35.482022 -276.012402)
		(width 0.1651)
		(layer "In2.Cu")
		(net "PE_RX2_DR7_N")
	)
	(segment
		(start 11.131042 -304.370486)
		(end 9.070848 -305.813206)
		(width 0.1651)
		(layer "In2.Cu")
		(net "PE_RX2_DR7_N")
	)
	(segment
		(start 32.595312 -276.521926)
		(end 28.740862 -279.220676)
		(width 0.1651)
		(layer "In2.Cu")
		(net "PE_RX2_DR7_N")
	)
	(segment
		(start 5.308854 -306.164234)
		(end 5.08 -305.93538)
		(width 0.1651)
		(layer "In2.Cu")
		(net "PE_RX2_DR7_N")
	)
	(segment
		(start 35.482022 -276.012402)
		(end 32.595312 -276.521926)
		(width 0.1651)
		(layer "In2.Cu")
		(net "PE_RX2_DR7_N")
	)
	(segment
		(start 28.740862 -279.220676)
		(end 11.131042 -304.370486)
		(width 0.1651)
		(layer "In2.Cu")
		(net "PE_RX2_DR7_N")
	)
	(segment
		(start 9.070848 -305.813206)
		(end 7.080758 -306.164234)
		(width 0.1651)
		(layer "In2.Cu")
		(net "PE_RX2_DR7_N")
	)
	(segment
		(start 38.1 -379.590046)
		(end 37.852604 -379.34265)
		(width 0.174752)
		(layer "F.Cu")
		(net "PE_RX2_DR6_P")
	)
	(segment
		(start 39.200074 -379.590046)
		(end 38.1 -379.590046)
		(width 0.174752)
		(layer "F.Cu")
		(net "PE_RX2_DR6_P")
	)
	(segment
		(start 37.133276 -379.34265)
		(end 36.72713 -379.748796)
		(width 0.174752)
		(layer "F.Cu")
		(net "PE_RX2_DR6_P")
	)
	(segment
		(start 37.852604 -379.34265)
		(end 37.133276 -379.34265)
		(width 0.174752)
		(layer "F.Cu")
		(net "PE_RX2_DR6_P")
	)
	(via
		(at 36.72713 -379.748796)
		(size 0.508)
		(drill 0.254)
		(layers "F.Cu" "B.Cu")
		(net "PE_RX2_DR6_P")
	)
	(via
		(at 5.08 -352.348292)
		(size 0.508)
		(drill 0.254)
		(layers "F.Cu" "B.Cu")
		(net "PE_RX2_DR6_P")
	)
	(segment
		(start 3.657854 -352.342196)
		(end 3.905504 -352.094546)
		(width 0.174752)
		(layer "B.Cu")
		(net "PE_RX2_DR6_P")
	)
	(segment
		(start 1.868932 -352.342196)
		(end 3.657854 -352.342196)
		(width 0.174752)
		(layer "B.Cu")
		(net "PE_RX2_DR6_P")
	)
	(segment
		(start 3.905504 -352.094546)
		(end 4.826254 -352.094546)
		(width 0.174752)
		(layer "B.Cu")
		(net "PE_RX2_DR6_P")
	)
	(segment
		(start 4.826254 -352.094546)
		(end 5.08 -352.348292)
		(width 0.174752)
		(layer "B.Cu")
		(net "PE_RX2_DR6_P")
	)
	(segment
		(start 20.696682 -381.238506)
		(end 18.175478 -379.473206)
		(width 0.1651)
		(layer "In2.Cu")
		(net "PE_RX2_DR6_P")
	)
	(segment
		(start 35.482022 -379.36805)
		(end 22.785324 -381.606806)
		(width 0.1651)
		(layer "In2.Cu")
		(net "PE_RX2_DR6_P")
	)
	(segment
		(start 13.459968 -358.266746)
		(end 10.454894 -353.975416)
		(width 0.1651)
		(layer "In2.Cu")
		(net "PE_RX2_DR6_P")
	)
	(segment
		(start 16.871188 -377.610116)
		(end 13.459968 -358.266746)
		(width 0.1651)
		(layer "In2.Cu")
		(net "PE_RX2_DR6_P")
	)
	(segment
		(start 36.346384 -379.36805)
		(end 35.482022 -379.36805)
		(width 0.1651)
		(layer "In2.Cu")
		(net "PE_RX2_DR6_P")
	)
	(segment
		(start 36.72713 -379.748796)
		(end 36.346384 -379.36805)
		(width 0.1651)
		(layer "In2.Cu")
		(net "PE_RX2_DR6_P")
	)
	(segment
		(start 22.785324 -381.606806)
		(end 20.696682 -381.238506)
		(width 0.1651)
		(layer "In2.Cu")
		(net "PE_RX2_DR6_P")
	)
	(segment
		(start 5.308346 -352.119946)
		(end 5.08 -352.348292)
		(width 0.1651)
		(layer "In2.Cu")
		(net "PE_RX2_DR6_P")
	)
	(segment
		(start 10.454894 -353.975416)
		(end 8.04926 -352.290634)
		(width 0.1651)
		(layer "In2.Cu")
		(net "PE_RX2_DR6_P")
	)
	(segment
		(start 18.175478 -379.473206)
		(end 16.871188 -377.610116)
		(width 0.1651)
		(layer "In2.Cu")
		(net "PE_RX2_DR6_P")
	)
	(segment
		(start 7.080758 -352.119946)
		(end 5.308346 -352.119946)
		(width 0.1651)
		(layer "In2.Cu")
		(net "PE_RX2_DR6_P")
	)
	(segment
		(start 8.04926 -352.290634)
		(end 7.080758 -352.119946)
		(width 0.1651)
		(layer "In2.Cu")
		(net "PE_RX2_DR6_P")
	)
	(segment
		(start 37.85235 -379.037596)
		(end 37.13353 -379.037596)
		(width 0.174752)
		(layer "F.Cu")
		(net "PE_RX2_DR6_N")
	)
	(segment
		(start 39.200074 -378.789946)
		(end 38.1 -378.789946)
		(width 0.174752)
		(layer "F.Cu")
		(net "PE_RX2_DR6_N")
	)
	(segment
		(start 38.1 -378.789946)
		(end 37.85235 -379.037596)
		(width 0.174752)
		(layer "F.Cu")
		(net "PE_RX2_DR6_N")
	)
	(segment
		(start 37.13353 -379.037596)
		(end 36.72713 -378.631196)
		(width 0.174752)
		(layer "F.Cu")
		(net "PE_RX2_DR6_N")
	)
	(via
		(at 36.72713 -378.631196)
		(size 0.508)
		(drill 0.254)
		(layers "F.Cu" "B.Cu")
		(net "PE_RX2_DR6_N")
	)
	(via
		(at 5.08 -351.535492)
		(size 0.508)
		(drill 0.254)
		(layers "F.Cu" "B.Cu")
		(net "PE_RX2_DR6_N")
	)
	(segment
		(start 3.905504 -351.789492)
		(end 4.826 -351.789492)
		(width 0.174752)
		(layer "B.Cu")
		(net "PE_RX2_DR6_N")
	)
	(segment
		(start 1.868932 -351.542096)
		(end 3.658108 -351.542096)
		(width 0.174752)
		(layer "B.Cu")
		(net "PE_RX2_DR6_N")
	)
	(segment
		(start 3.658108 -351.542096)
		(end 3.905504 -351.789492)
		(width 0.174752)
		(layer "B.Cu")
		(net "PE_RX2_DR6_N")
	)
	(segment
		(start 4.826 -351.789492)
		(end 5.08 -351.535492)
		(width 0.174752)
		(layer "B.Cu")
		(net "PE_RX2_DR6_N")
	)
	(segment
		(start 18.431002 -379.217682)
		(end 17.207738 -377.47067)
		(width 0.1651)
		(layer "In2.Cu")
		(net "PE_RX2_DR6_N")
	)
	(segment
		(start 36.345876 -379.01245)
		(end 35.45078 -379.01245)
		(width 0.1651)
		(layer "In2.Cu")
		(net "PE_RX2_DR6_N")
	)
	(segment
		(start 17.207738 -377.47067)
		(end 13.796518 -358.1273)
		(width 0.1651)
		(layer "In2.Cu")
		(net "PE_RX2_DR6_N")
	)
	(segment
		(start 8.188706 -351.954084)
		(end 7.112 -351.764346)
		(width 0.1651)
		(layer "In2.Cu")
		(net "PE_RX2_DR6_N")
	)
	(segment
		(start 22.785324 -381.245618)
		(end 20.836128 -380.901956)
		(width 0.1651)
		(layer "In2.Cu")
		(net "PE_RX2_DR6_N")
	)
	(segment
		(start 5.308854 -351.764346)
		(end 5.08 -351.535492)
		(width 0.1651)
		(layer "In2.Cu")
		(net "PE_RX2_DR6_N")
	)
	(segment
		(start 36.72713 -378.631196)
		(end 36.345876 -379.01245)
		(width 0.1651)
		(layer "In2.Cu")
		(net "PE_RX2_DR6_N")
	)
	(segment
		(start 7.112 -351.764346)
		(end 5.308854 -351.764346)
		(width 0.1651)
		(layer "In2.Cu")
		(net "PE_RX2_DR6_N")
	)
	(segment
		(start 13.796518 -358.1273)
		(end 10.710418 -353.719892)
		(width 0.1651)
		(layer "In2.Cu")
		(net "PE_RX2_DR6_N")
	)
	(segment
		(start 10.710418 -353.719892)
		(end 8.188706 -351.954084)
		(width 0.1651)
		(layer "In2.Cu")
		(net "PE_RX2_DR6_N")
	)
	(segment
		(start 20.836128 -380.901956)
		(end 18.431002 -379.217682)
		(width 0.1651)
		(layer "In2.Cu")
		(net "PE_RX2_DR6_N")
	)
	(segment
		(start 35.45078 -379.01245)
		(end 22.785324 -381.245618)
		(width 0.1651)
		(layer "In2.Cu")
		(net "PE_RX2_DR6_N")
	)
	(segment
		(start 39.200074 -481.789994)
		(end 37.973 -481.789994)
		(width 0.174752)
		(layer "F.Cu")
		(net "PE_RX2_DR5_P")
	)
	(segment
		(start 37.973 -481.789994)
		(end 37.72535 -482.037644)
		(width 0.174752)
		(layer "F.Cu")
		(net "PE_RX2_DR5_P")
	)
	(segment
		(start 37.72535 -482.037644)
		(end 37.13353 -482.037644)
		(width 0.174752)
		(layer "F.Cu")
		(net "PE_RX2_DR5_P")
	)
	(segment
		(start 37.13353 -482.037644)
		(end 36.72713 -481.631244)
		(width 0.174752)
		(layer "F.Cu")
		(net "PE_RX2_DR5_P")
	)
	(via
		(at 36.72713 -481.631244)
		(size 0.508)
		(drill 0.254)
		(layers "F.Cu" "B.Cu")
		(net "PE_RX2_DR5_P")
	)
	(via
		(at 5.08 -438.335166)
		(size 0.508)
		(drill 0.254)
		(layers "F.Cu" "B.Cu")
		(net "PE_RX2_DR5_P")
	)
	(segment
		(start 4.825746 -438.58942)
		(end 5.08 -438.335166)
		(width 0.174752)
		(layer "B.Cu")
		(net "PE_RX2_DR5_P")
	)
	(segment
		(start 3.657854 -438.342024)
		(end 3.90525 -438.58942)
		(width 0.174752)
		(layer "B.Cu")
		(net "PE_RX2_DR5_P")
	)
	(segment
		(start 3.90525 -438.58942)
		(end 4.825746 -438.58942)
		(width 0.174752)
		(layer "B.Cu")
		(net "PE_RX2_DR5_P")
	)
	(segment
		(start 1.868932 -438.342024)
		(end 3.657854 -438.342024)
		(width 0.174752)
		(layer "B.Cu")
		(net "PE_RX2_DR5_P")
	)
	(segment
		(start 36.72713 -481.631244)
		(end 36.345876 -482.012498)
		(width 0.1651)
		(layer "In2.Cu")
		(net "PE_RX2_DR5_P")
	)
	(segment
		(start 35.482022 -482.012498)
		(end 24.694642 -480.110546)
		(width 0.1651)
		(layer "In2.Cu")
		(net "PE_RX2_DR5_P")
	)
	(segment
		(start 18.376646 -475.68612)
		(end 15.249398 -471.220292)
		(width 0.1651)
		(layer "In2.Cu")
		(net "PE_RX2_DR5_P")
	)
	(segment
		(start 15.249398 -471.220292)
		(end 9.879076 -440.771788)
		(width 0.1651)
		(layer "In2.Cu")
		(net "PE_RX2_DR5_P")
	)
	(segment
		(start 36.345876 -482.012498)
		(end 35.482022 -482.012498)
		(width 0.1651)
		(layer "In2.Cu")
		(net "PE_RX2_DR5_P")
	)
	(segment
		(start 9.879076 -440.771788)
		(end 8.917686 -439.398664)
		(width 0.1651)
		(layer "In2.Cu")
		(net "PE_RX2_DR5_P")
	)
	(segment
		(start 7.932166 -438.708546)
		(end 7.112 -438.56402)
		(width 0.1651)
		(layer "In2.Cu")
		(net "PE_RX2_DR5_P")
	)
	(segment
		(start 7.112 -438.56402)
		(end 5.308854 -438.56402)
		(width 0.1651)
		(layer "In2.Cu")
		(net "PE_RX2_DR5_P")
	)
	(segment
		(start 5.308854 -438.56402)
		(end 5.08 -438.335166)
		(width 0.1651)
		(layer "In2.Cu")
		(net "PE_RX2_DR5_P")
	)
	(segment
		(start 8.917686 -439.398664)
		(end 7.932166 -438.708546)
		(width 0.1651)
		(layer "In2.Cu")
		(net "PE_RX2_DR5_P")
	)
	(segment
		(start 24.694642 -480.110546)
		(end 18.376646 -475.68612)
		(width 0.1651)
		(layer "In2.Cu")
		(net "PE_RX2_DR5_P")
	)
	(segment
		(start 39.200074 -482.590094)
		(end 37.973 -482.590094)
		(width 0.174752)
		(layer "F.Cu")
		(net "PE_RX2_DR5_N")
	)
	(segment
		(start 37.973 -482.590094)
		(end 37.725604 -482.342698)
		(width 0.174752)
		(layer "F.Cu")
		(net "PE_RX2_DR5_N")
	)
	(segment
		(start 37.133276 -482.342698)
		(end 36.72713 -482.748844)
		(width 0.174752)
		(layer "F.Cu")
		(net "PE_RX2_DR5_N")
	)
	(segment
		(start 37.725604 -482.342698)
		(end 37.133276 -482.342698)
		(width 0.174752)
		(layer "F.Cu")
		(net "PE_RX2_DR5_N")
	)
	(via
		(at 5.08 -439.147966)
		(size 0.508)
		(drill 0.254)
		(layers "F.Cu" "B.Cu")
		(net "PE_RX2_DR5_N")
	)
	(via
		(at 36.72713 -482.748844)
		(size 0.508)
		(drill 0.254)
		(layers "F.Cu" "B.Cu")
		(net "PE_RX2_DR5_N")
	)
	(segment
		(start 3.90525 -438.894474)
		(end 4.826508 -438.894474)
		(width 0.174752)
		(layer "B.Cu")
		(net "PE_RX2_DR5_N")
	)
	(segment
		(start 3.657854 -439.14187)
		(end 3.90525 -438.894474)
		(width 0.174752)
		(layer "B.Cu")
		(net "PE_RX2_DR5_N")
	)
	(segment
		(start 1.868932 -439.14187)
		(end 3.657854 -439.14187)
		(width 0.174752)
		(layer "B.Cu")
		(net "PE_RX2_DR5_N")
	)
	(segment
		(start 4.826508 -438.894474)
		(end 5.08 -439.147966)
		(width 0.174752)
		(layer "B.Cu")
		(net "PE_RX2_DR5_N")
	)
	(segment
		(start 14.912848 -471.359738)
		(end 9.542526 -440.911234)
		(width 0.1651)
		(layer "In2.Cu")
		(net "PE_RX2_DR5_N")
	)
	(segment
		(start 7.080758 -438.91962)
		(end 5.308346 -438.91962)
		(width 0.1651)
		(layer "In2.Cu")
		(net "PE_RX2_DR5_N")
	)
	(segment
		(start 24.555196 -480.447096)
		(end 18.121122 -475.941644)
		(width 0.1651)
		(layer "In2.Cu")
		(net "PE_RX2_DR5_N")
	)
	(segment
		(start 35.45078 -482.368098)
		(end 24.555196 -480.447096)
		(width 0.1651)
		(layer "In2.Cu")
		(net "PE_RX2_DR5_N")
	)
	(segment
		(start 36.72713 -482.748844)
		(end 36.346384 -482.368098)
		(width 0.1651)
		(layer "In2.Cu")
		(net "PE_RX2_DR5_N")
	)
	(segment
		(start 9.542526 -440.911234)
		(end 8.662162 -439.654188)
		(width 0.1651)
		(layer "In2.Cu")
		(net "PE_RX2_DR5_N")
	)
	(segment
		(start 7.79272 -439.045096)
		(end 7.080758 -438.91962)
		(width 0.1651)
		(layer "In2.Cu")
		(net "PE_RX2_DR5_N")
	)
	(segment
		(start 5.308346 -438.91962)
		(end 5.08 -439.147966)
		(width 0.1651)
		(layer "In2.Cu")
		(net "PE_RX2_DR5_N")
	)
	(segment
		(start 8.662162 -439.654188)
		(end 7.79272 -439.045096)
		(width 0.1651)
		(layer "In2.Cu")
		(net "PE_RX2_DR5_N")
	)
	(segment
		(start 36.346384 -482.368098)
		(end 35.45078 -482.368098)
		(width 0.1651)
		(layer "In2.Cu")
		(net "PE_RX2_DR5_N")
	)
	(segment
		(start 18.121122 -475.941644)
		(end 16.52143 -473.657168)
		(width 0.1651)
		(layer "In2.Cu")
		(net "PE_RX2_DR5_N")
	)
	(segment
		(start 16.52143 -473.657168)
		(end 14.912848 -471.359738)
		(width 0.1651)
		(layer "In2.Cu")
		(net "PE_RX2_DR5_N")
	)
	(segment
		(start 224.199958 -70.589902)
		(end 223.139 -70.589902)
		(width 0.174752)
		(layer "F.Cu")
		(net "PE_RX2_DR4_P")
	)
	(segment
		(start 222.891604 -70.342506)
		(end 222.13316 -70.342506)
		(width 0.174752)
		(layer "F.Cu")
		(net "PE_RX2_DR4_P")
	)
	(segment
		(start 222.13316 -70.342506)
		(end 221.727014 -70.748652)
		(width 0.174752)
		(layer "F.Cu")
		(net "PE_RX2_DR4_P")
	)
	(segment
		(start 223.139 -70.589902)
		(end 222.891604 -70.342506)
		(width 0.174752)
		(layer "F.Cu")
		(net "PE_RX2_DR4_P")
	)
	(via
		(at 221.727014 -70.748652)
		(size 0.508)
		(drill 0.254)
		(layers "F.Cu" "B.Cu")
		(net "PE_RX2_DR4_P")
	)
	(via
		(at 5.08 -232.748328)
		(size 0.508)
		(drill 0.254)
		(layers "F.Cu" "B.Cu")
		(net "PE_RX2_DR4_P")
	)
	(segment
		(start 4.826254 -232.494582)
		(end 5.08 -232.748328)
		(width 0.174752)
		(layer "B.Cu")
		(net "PE_RX2_DR4_P")
	)
	(segment
		(start 3.657854 -232.742232)
		(end 3.905504 -232.494582)
		(width 0.174752)
		(layer "B.Cu")
		(net "PE_RX2_DR4_P")
	)
	(segment
		(start 1.868932 -232.742232)
		(end 3.657854 -232.742232)
		(width 0.174752)
		(layer "B.Cu")
		(net "PE_RX2_DR4_P")
	)
	(segment
		(start 3.905504 -232.494582)
		(end 4.826254 -232.494582)
		(width 0.174752)
		(layer "B.Cu")
		(net "PE_RX2_DR4_P")
	)
	(segment
		(start 221.346268 -70.367906)
		(end 220.481906 -70.367906)
		(width 0.1651)
		(layer "In2.Cu")
		(net "PE_RX2_DR4_P")
	)
	(segment
		(start 15.209266 -254.174244)
		(end 12.329668 -237.842806)
		(width 0.1651)
		(layer "In2.Cu")
		(net "PE_RX2_DR4_P")
	)
	(segment
		(start 220.481906 -70.367906)
		(end 213.574376 -71.585836)
		(width 0.1651)
		(layer "In2.Cu")
		(net "PE_RX2_DR4_P")
	)
	(segment
		(start 16.193516 -255.57988)
		(end 15.209266 -254.174244)
		(width 0.1651)
		(layer "In2.Cu")
		(net "PE_RX2_DR4_P")
	)
	(segment
		(start 16.860012 -256.07518)
		(end 16.289528 -255.675892)
		(width 0.1651)
		(layer "In2.Cu")
		(net "PE_RX2_DR4_P")
	)
	(segment
		(start 29.890974 -249.398536)
		(end 20.324064 -256.096262)
		(width 0.1651)
		(layer "In2.Cu")
		(net "PE_RX2_DR4_P")
	)
	(segment
		(start 213.574376 -71.585836)
		(end 88.162892 -159.39897)
		(width 0.1651)
		(layer "In2.Cu")
		(net "PE_RX2_DR4_P")
	)
	(segment
		(start 20.324064 -256.096262)
		(end 19.127978 -256.307336)
		(width 0.1651)
		(layer "In2.Cu")
		(net "PE_RX2_DR4_P")
	)
	(segment
		(start 19.127978 -256.307336)
		(end 18.17497 -256.307336)
		(width 0.1651)
		(layer "In2.Cu")
		(net "PE_RX2_DR4_P")
	)
	(segment
		(start 5.308346 -232.519982)
		(end 5.08 -232.748328)
		(width 0.1651)
		(layer "In2.Cu")
		(net "PE_RX2_DR4_P")
	)
	(segment
		(start 18.17497 -256.307336)
		(end 16.860012 -256.07518)
		(width 0.1651)
		(layer "In2.Cu")
		(net "PE_RX2_DR4_P")
	)
	(segment
		(start 7.972298 -232.84307)
		(end 6.138672 -232.519982)
		(width 0.1651)
		(layer "In2.Cu")
		(net "PE_RX2_DR4_P")
	)
	(segment
		(start 9.651746 -234.018836)
		(end 7.972298 -232.84307)
		(width 0.1651)
		(layer "In2.Cu")
		(net "PE_RX2_DR4_P")
	)
	(segment
		(start 32.745934 -238.542576)
		(end 31.148782 -247.602502)
		(width 0.1651)
		(layer "In2.Cu")
		(net "PE_RX2_DR4_P")
	)
	(segment
		(start 88.162892 -159.39897)
		(end 32.745934 -238.542576)
		(width 0.1651)
		(layer "In2.Cu")
		(net "PE_RX2_DR4_P")
	)
	(segment
		(start 221.727014 -70.748652)
		(end 221.346268 -70.367906)
		(width 0.1651)
		(layer "In2.Cu")
		(net "PE_RX2_DR4_P")
	)
	(segment
		(start 12.329668 -237.842806)
		(end 9.651746 -234.018836)
		(width 0.1651)
		(layer "In2.Cu")
		(net "PE_RX2_DR4_P")
	)
	(segment
		(start 16.289528 -255.675892)
		(end 16.193516 -255.57988)
		(width 0.1651)
		(layer "In2.Cu")
		(net "PE_RX2_DR4_P")
	)
	(segment
		(start 31.148782 -247.602502)
		(end 29.890974 -249.398536)
		(width 0.1651)
		(layer "In2.Cu")
		(net "PE_RX2_DR4_P")
	)
	(segment
		(start 6.138672 -232.519982)
		(end 5.308346 -232.519982)
		(width 0.1651)
		(layer "In2.Cu")
		(net "PE_RX2_DR4_P")
	)
	(segment
		(start 224.199958 -69.789802)
		(end 223.266 -69.789802)
		(width 0.174752)
		(layer "F.Cu")
		(net "PE_RX2_DR4_N")
	)
	(segment
		(start 223.266 -69.789802)
		(end 223.01835 -70.037452)
		(width 0.174752)
		(layer "F.Cu")
		(net "PE_RX2_DR4_N")
	)
	(segment
		(start 222.133414 -70.037452)
		(end 221.727014 -69.631052)
		(width 0.174752)
		(layer "F.Cu")
		(net "PE_RX2_DR4_N")
	)
	(segment
		(start 223.01835 -70.037452)
		(end 222.133414 -70.037452)
		(width 0.174752)
		(layer "F.Cu")
		(net "PE_RX2_DR4_N")
	)
	(via
		(at 5.08 -231.935528)
		(size 0.508)
		(drill 0.254)
		(layers "F.Cu" "B.Cu")
		(net "PE_RX2_DR4_N")
	)
	(via
		(at 221.727014 -69.631052)
		(size 0.508)
		(drill 0.254)
		(layers "F.Cu" "B.Cu")
		(net "PE_RX2_DR4_N")
	)
	(segment
		(start 4.826 -232.189528)
		(end 5.08 -231.935528)
		(width 0.174752)
		(layer "B.Cu")
		(net "PE_RX2_DR4_N")
	)
	(segment
		(start 1.868932 -231.942132)
		(end 3.658108 -231.942132)
		(width 0.174752)
		(layer "B.Cu")
		(net "PE_RX2_DR4_N")
	)
	(segment
		(start 3.658108 -231.942132)
		(end 3.905504 -232.189528)
		(width 0.174752)
		(layer "B.Cu")
		(net "PE_RX2_DR4_N")
	)
	(segment
		(start 3.905504 -232.189528)
		(end 4.826 -232.189528)
		(width 0.174752)
		(layer "B.Cu")
		(net "PE_RX2_DR4_N")
	)
	(segment
		(start 6.169914 -232.164382)
		(end 5.308854 -232.164382)
		(width 0.1651)
		(layer "In2.Cu")
		(net "PE_RX2_DR4_N")
	)
	(segment
		(start 5.308854 -232.164382)
		(end 5.08 -231.935528)
		(width 0.1651)
		(layer "In2.Cu")
		(net "PE_RX2_DR4_N")
	)
	(segment
		(start 30.812232 -247.463056)
		(end 29.63545 -249.143012)
		(width 0.1651)
		(layer "In2.Cu")
		(net "PE_RX2_DR4_N")
	)
	(segment
		(start 220.450664 -70.012306)
		(end 213.43493 -71.249286)
		(width 0.1651)
		(layer "In2.Cu")
		(net "PE_RX2_DR4_N")
	)
	(segment
		(start 16.999458 -255.73863)
		(end 16.51889 -255.402334)
		(width 0.1651)
		(layer "In2.Cu")
		(net "PE_RX2_DR4_N")
	)
	(segment
		(start 19.096736 -255.951736)
		(end 18.206212 -255.951736)
		(width 0.1651)
		(layer "In2.Cu")
		(net "PE_RX2_DR4_N")
	)
	(segment
		(start 8.111744 -232.50652)
		(end 6.169914 -232.164382)
		(width 0.1651)
		(layer "In2.Cu")
		(net "PE_RX2_DR4_N")
	)
	(segment
		(start 32.409384 -238.40313)
		(end 30.812232 -247.463056)
		(width 0.1651)
		(layer "In2.Cu")
		(net "PE_RX2_DR4_N")
	)
	(segment
		(start 20.184618 -255.759712)
		(end 19.096736 -255.951736)
		(width 0.1651)
		(layer "In2.Cu")
		(net "PE_RX2_DR4_N")
	)
	(segment
		(start 16.467074 -255.350518)
		(end 15.545816 -254.034798)
		(width 0.1651)
		(layer "In2.Cu")
		(net "PE_RX2_DR4_N")
	)
	(segment
		(start 15.545816 -254.034798)
		(end 12.666218 -237.70336)
		(width 0.1651)
		(layer "In2.Cu")
		(net "PE_RX2_DR4_N")
	)
	(segment
		(start 221.727014 -69.631052)
		(end 221.34576 -70.012306)
		(width 0.1651)
		(layer "In2.Cu")
		(net "PE_RX2_DR4_N")
	)
	(segment
		(start 213.43493 -71.249286)
		(end 87.907368 -159.143446)
		(width 0.1651)
		(layer "In2.Cu")
		(net "PE_RX2_DR4_N")
	)
	(segment
		(start 9.90727 -233.763312)
		(end 8.111744 -232.50652)
		(width 0.1651)
		(layer "In2.Cu")
		(net "PE_RX2_DR4_N")
	)
	(segment
		(start 18.206212 -255.951736)
		(end 16.999458 -255.73863)
		(width 0.1651)
		(layer "In2.Cu")
		(net "PE_RX2_DR4_N")
	)
	(segment
		(start 29.63545 -249.143012)
		(end 20.184618 -255.759712)
		(width 0.1651)
		(layer "In2.Cu")
		(net "PE_RX2_DR4_N")
	)
	(segment
		(start 12.666218 -237.70336)
		(end 9.90727 -233.763312)
		(width 0.1651)
		(layer "In2.Cu")
		(net "PE_RX2_DR4_N")
	)
	(segment
		(start 16.51889 -255.402334)
		(end 16.467074 -255.350518)
		(width 0.1651)
		(layer "In2.Cu")
		(net "PE_RX2_DR4_N")
	)
	(segment
		(start 221.34576 -70.012306)
		(end 220.450664 -70.012306)
		(width 0.1651)
		(layer "In2.Cu")
		(net "PE_RX2_DR4_N")
	)
	(segment
		(start 87.907368 -159.143446)
		(end 32.409384 -238.40313)
		(width 0.1651)
		(layer "In2.Cu")
		(net "PE_RX2_DR4_N")
	)
	(segment
		(start 222.891604 -173.342554)
		(end 222.13316 -173.342554)
		(width 0.174752)
		(layer "F.Cu")
		(net "PE_RX2_DR3_P")
	)
	(segment
		(start 223.139 -173.58995)
		(end 222.891604 -173.342554)
		(width 0.174752)
		(layer "F.Cu")
		(net "PE_RX2_DR3_P")
	)
	(segment
		(start 222.13316 -173.342554)
		(end 221.727014 -173.7487)
		(width 0.174752)
		(layer "F.Cu")
		(net "PE_RX2_DR3_P")
	)
	(segment
		(start 224.199958 -173.58995)
		(end 223.139 -173.58995)
		(width 0.174752)
		(layer "F.Cu")
		(net "PE_RX2_DR3_P")
	)
	(via
		(at 5.08 -293.948104)
		(size 0.508)
		(drill 0.254)
		(layers "F.Cu" "B.Cu")
		(net "PE_RX2_DR3_P")
	)
	(via
		(at 221.727014 -173.7487)
		(size 0.508)
		(drill 0.254)
		(layers "F.Cu" "B.Cu")
		(net "PE_RX2_DR3_P")
	)
	(segment
		(start 3.658108 -293.942008)
		(end 3.905504 -293.694612)
		(width 0.174752)
		(layer "B.Cu")
		(net "PE_RX2_DR3_P")
	)
	(segment
		(start 1.868932 -293.942008)
		(end 3.658108 -293.942008)
		(width 0.174752)
		(layer "B.Cu")
		(net "PE_RX2_DR3_P")
	)
	(segment
		(start 3.905504 -293.694612)
		(end 4.826508 -293.694612)
		(width 0.174752)
		(layer "B.Cu")
		(net "PE_RX2_DR3_P")
	)
	(segment
		(start 4.826508 -293.694612)
		(end 5.08 -293.948104)
		(width 0.174752)
		(layer "B.Cu")
		(net "PE_RX2_DR3_P")
	)
	(segment
		(start 5.308092 -293.720012)
		(end 6.32968 -293.720012)
		(width 0.1651)
		(layer "In2.Cu")
		(net "PE_RX2_DR3_P")
	)
	(segment
		(start 34.990024 -249.208798)
		(end 35.035236 -249.144028)
		(width 0.1651)
		(layer "In2.Cu")
		(net "PE_RX2_DR3_P")
	)
	(segment
		(start 30.328616 -255.86563)
		(end 34.990024 -249.208544)
		(width 0.1651)
		(layer "In2.Cu")
		(net "PE_RX2_DR3_P")
	)
	(segment
		(start 14.878304 -290.669726)
		(end 27.326336 -272.892012)
		(width 0.1651)
		(layer "In2.Cu")
		(net "PE_RX2_DR3_P")
	)
	(segment
		(start 221.346268 -173.367954)
		(end 221.727014 -173.7487)
		(width 0.1651)
		(layer "In2.Cu")
		(net "PE_RX2_DR3_P")
	)
	(segment
		(start 6.32968 -293.720012)
		(end 8.490712 -294.179498)
		(width 0.1651)
		(layer "In2.Cu")
		(net "PE_RX2_DR3_P")
	)
	(segment
		(start 82.033872 -194.529456)
		(end 211.219542 -171.751244)
		(width 0.1651)
		(layer "In2.Cu")
		(net "PE_RX2_DR3_P")
	)
	(segment
		(start 36.643818 -240.02365)
		(end 55.478934 -213.124288)
		(width 0.1651)
		(layer "In2.Cu")
		(net "PE_RX2_DR3_P")
	)
	(segment
		(start 5.08 -293.948104)
		(end 5.308092 -293.720012)
		(width 0.1651)
		(layer "In2.Cu")
		(net "PE_RX2_DR3_P")
	)
	(segment
		(start 211.219542 -171.751244)
		(end 220.38818 -173.367954)
		(width 0.1651)
		(layer "In2.Cu")
		(net "PE_RX2_DR3_P")
	)
	(segment
		(start 27.326336 -272.892012)
		(end 30.328616 -255.86563)
		(width 0.1651)
		(layer "In2.Cu")
		(net "PE_RX2_DR3_P")
	)
	(segment
		(start 35.035236 -249.144028)
		(end 36.643818 -240.02365)
		(width 0.1651)
		(layer "In2.Cu")
		(net "PE_RX2_DR3_P")
	)
	(segment
		(start 55.478934 -213.124288)
		(end 82.033872 -194.529456)
		(width 0.1651)
		(layer "In2.Cu")
		(net "PE_RX2_DR3_P")
	)
	(segment
		(start 8.490712 -294.179498)
		(end 10.32764 -293.854886)
		(width 0.1651)
		(layer "In2.Cu")
		(net "PE_RX2_DR3_P")
	)
	(segment
		(start 10.32764 -293.854886)
		(end 14.878304 -290.669726)
		(width 0.1651)
		(layer "In2.Cu")
		(net "PE_RX2_DR3_P")
	)
	(segment
		(start 220.38818 -173.367954)
		(end 221.346268 -173.367954)
		(width 0.1651)
		(layer "In2.Cu")
		(net "PE_RX2_DR3_P")
	)
	(segment
		(start 34.990024 -249.208544)
		(end 34.990024 -249.208798)
		(width 0.1651)
		(layer "In2.Cu")
		(net "PE_RX2_DR3_P")
	)
	(segment
		(start 224.199958 -172.78985)
		(end 223.13265 -172.78985)
		(width 0.174752)
		(layer "F.Cu")
		(net "PE_RX2_DR3_N")
	)
	(segment
		(start 222.885 -173.0375)
		(end 222.133414 -173.0375)
		(width 0.174752)
		(layer "F.Cu")
		(net "PE_RX2_DR3_N")
	)
	(segment
		(start 223.13265 -172.78985)
		(end 222.885 -173.0375)
		(width 0.174752)
		(layer "F.Cu")
		(net "PE_RX2_DR3_N")
	)
	(segment
		(start 222.133414 -173.0375)
		(end 221.727014 -172.6311)
		(width 0.174752)
		(layer "F.Cu")
		(net "PE_RX2_DR3_N")
	)
	(via
		(at 221.727014 -172.6311)
		(size 0.508)
		(drill 0.254)
		(layers "F.Cu" "B.Cu")
		(net "PE_RX2_DR3_N")
	)
	(via
		(at 5.08 -293.135304)
		(size 0.508)
		(drill 0.254)
		(layers "F.Cu" "B.Cu")
		(net "PE_RX2_DR3_N")
	)
	(segment
		(start 4.825746 -293.389558)
		(end 5.08 -293.135304)
		(width 0.174752)
		(layer "B.Cu")
		(net "PE_RX2_DR3_N")
	)
	(segment
		(start 3.905504 -293.389558)
		(end 4.825746 -293.389558)
		(width 0.174752)
		(layer "B.Cu")
		(net "PE_RX2_DR3_N")
	)
	(segment
		(start 1.868932 -293.142162)
		(end 3.658108 -293.142162)
		(width 0.174752)
		(layer "B.Cu")
		(net "PE_RX2_DR3_N")
	)
	(segment
		(start 3.658108 -293.142162)
		(end 3.905504 -293.389558)
		(width 0.174752)
		(layer "B.Cu")
		(net "PE_RX2_DR3_N")
	)
	(segment
		(start 211.219796 -171.390056)
		(end 220.419422 -173.012354)
		(width 0.1651)
		(layer "In2.Cu")
		(net "PE_RX2_DR3_N")
	)
	(segment
		(start 36.307268 -239.884204)
		(end 55.22341 -212.868764)
		(width 0.1651)
		(layer "In2.Cu")
		(net "PE_RX2_DR3_N")
	)
	(segment
		(start 8.497062 -293.81704)
		(end 10.188194 -293.518336)
		(width 0.1651)
		(layer "In2.Cu")
		(net "PE_RX2_DR3_N")
	)
	(segment
		(start 220.419422 -173.012354)
		(end 221.34576 -173.012354)
		(width 0.1651)
		(layer "In2.Cu")
		(net "PE_RX2_DR3_N")
	)
	(segment
		(start 34.698686 -249.004582)
		(end 36.307268 -239.884204)
		(width 0.1651)
		(layer "In2.Cu")
		(net "PE_RX2_DR3_N")
	)
	(segment
		(start 55.22341 -212.868764)
		(end 81.894426 -194.192906)
		(width 0.1651)
		(layer "In2.Cu")
		(net "PE_RX2_DR3_N")
	)
	(segment
		(start 14.62278 -290.414202)
		(end 26.989786 -272.752566)
		(width 0.1651)
		(layer "In2.Cu")
		(net "PE_RX2_DR3_N")
	)
	(segment
		(start 29.992066 -255.726184)
		(end 34.698686 -249.004582)
		(width 0.1651)
		(layer "In2.Cu")
		(net "PE_RX2_DR3_N")
	)
	(segment
		(start 81.894426 -194.192906)
		(end 211.219796 -171.390056)
		(width 0.1651)
		(layer "In2.Cu")
		(net "PE_RX2_DR3_N")
	)
	(segment
		(start 10.188194 -293.518336)
		(end 14.62278 -290.414202)
		(width 0.1651)
		(layer "In2.Cu")
		(net "PE_RX2_DR3_N")
	)
	(segment
		(start 26.989786 -272.752566)
		(end 29.992066 -255.726184)
		(width 0.1651)
		(layer "In2.Cu")
		(net "PE_RX2_DR3_N")
	)
	(segment
		(start 221.34576 -173.012354)
		(end 221.727014 -172.6311)
		(width 0.1651)
		(layer "In2.Cu")
		(net "PE_RX2_DR3_N")
	)
	(segment
		(start 5.08 -293.135304)
		(end 5.309108 -293.364412)
		(width 0.1651)
		(layer "In2.Cu")
		(net "PE_RX2_DR3_N")
	)
	(segment
		(start 6.367272 -293.364412)
		(end 8.497062 -293.81704)
		(width 0.1651)
		(layer "In2.Cu")
		(net "PE_RX2_DR3_N")
	)
	(segment
		(start 5.309108 -293.364412)
		(end 6.367272 -293.364412)
		(width 0.1651)
		(layer "In2.Cu")
		(net "PE_RX2_DR3_N")
	)
	(segment
		(start 223.139 -276.589998)
		(end 222.891604 -276.342602)
		(width 0.174752)
		(layer "F.Cu")
		(net "PE_RX2_DR2_P")
	)
	(segment
		(start 222.13316 -276.342602)
		(end 221.727014 -276.748748)
		(width 0.174752)
		(layer "F.Cu")
		(net "PE_RX2_DR2_P")
	)
	(segment
		(start 222.891604 -276.342602)
		(end 222.13316 -276.342602)
		(width 0.174752)
		(layer "F.Cu")
		(net "PE_RX2_DR2_P")
	)
	(segment
		(start 224.199958 -276.589998)
		(end 223.139 -276.589998)
		(width 0.174752)
		(layer "F.Cu")
		(net "PE_RX2_DR2_P")
	)
	(via
		(at 221.727014 -276.748748)
		(size 0.508)
		(drill 0.254)
		(layers "F.Cu" "B.Cu")
		(net "PE_RX2_DR2_P")
	)
	(via
		(at 5.08 -324.348094)
		(size 0.508)
		(drill 0.254)
		(layers "F.Cu" "B.Cu")
		(net "PE_RX2_DR2_P")
	)
	(segment
		(start 1.868932 -324.341998)
		(end 3.658108 -324.341998)
		(width 0.174752)
		(layer "B.Cu")
		(net "PE_RX2_DR2_P")
	)
	(segment
		(start 3.658108 -324.341998)
		(end 3.905504 -324.094602)
		(width 0.174752)
		(layer "B.Cu")
		(net "PE_RX2_DR2_P")
	)
	(segment
		(start 3.905504 -324.094602)
		(end 4.826508 -324.094602)
		(width 0.174752)
		(layer "B.Cu")
		(net "PE_RX2_DR2_P")
	)
	(segment
		(start 4.826508 -324.094602)
		(end 5.08 -324.348094)
		(width 0.174752)
		(layer "B.Cu")
		(net "PE_RX2_DR2_P")
	)
	(segment
		(start 45.579792 -304.085752)
		(end 39.076884 -305.232308)
		(width 0.1651)
		(layer "In2.Cu")
		(net "PE_RX2_DR2_P")
	)
	(segment
		(start 5.308092 -324.120002)
		(end 5.08 -324.348094)
		(width 0.1651)
		(layer "In2.Cu")
		(net "PE_RX2_DR2_P")
	)
	(segment
		(start 8.781034 -323.825616)
		(end 7.112 -324.120002)
		(width 0.1651)
		(layer "In2.Cu")
		(net "PE_RX2_DR2_P")
	)
	(segment
		(start 39.076884 -305.232308)
		(end 23.155402 -302.424592)
		(width 0.1651)
		(layer "In2.Cu")
		(net "PE_RX2_DR2_P")
	)
	(segment
		(start 20.601432 -302.875188)
		(end 16.190976 -305.963574)
		(width 0.1651)
		(layer "In2.Cu")
		(net "PE_RX2_DR2_P")
	)
	(segment
		(start 221.727014 -276.748748)
		(end 221.346268 -276.368002)
		(width 0.1651)
		(layer "In2.Cu")
		(net "PE_RX2_DR2_P")
	)
	(segment
		(start 221.346268 -276.368002)
		(end 220.450664 -276.368002)
		(width 0.1651)
		(layer "In2.Cu")
		(net "PE_RX2_DR2_P")
	)
	(segment
		(start 220.450664 -276.368002)
		(end 179.394358 -269.128748)
		(width 0.1651)
		(layer "In2.Cu")
		(net "PE_RX2_DR2_P")
	)
	(segment
		(start 12.787376 -319.42659)
		(end 10.597388 -322.553838)
		(width 0.1651)
		(layer "In2.Cu")
		(net "PE_RX2_DR2_P")
	)
	(segment
		(start 14.81455 -307.929534)
		(end 12.787376 -319.42659)
		(width 0.1651)
		(layer "In2.Cu")
		(net "PE_RX2_DR2_P")
	)
	(segment
		(start 16.190976 -305.963574)
		(end 14.81455 -307.929534)
		(width 0.1651)
		(layer "In2.Cu")
		(net "PE_RX2_DR2_P")
	)
	(segment
		(start 23.155402 -302.424592)
		(end 20.601432 -302.875188)
		(width 0.1651)
		(layer "In2.Cu")
		(net "PE_RX2_DR2_P")
	)
	(segment
		(start 10.597388 -322.553838)
		(end 8.781034 -323.825616)
		(width 0.1651)
		(layer "In2.Cu")
		(net "PE_RX2_DR2_P")
	)
	(segment
		(start 179.394358 -269.128748)
		(end 67.279012 -288.892742)
		(width 0.1651)
		(layer "In2.Cu")
		(net "PE_RX2_DR2_P")
	)
	(segment
		(start 7.112 -324.120002)
		(end 5.308092 -324.120002)
		(width 0.1651)
		(layer "In2.Cu")
		(net "PE_RX2_DR2_P")
	)
	(segment
		(start 67.279012 -288.892742)
		(end 45.579792 -304.085752)
		(width 0.1651)
		(layer "In2.Cu")
		(net "PE_RX2_DR2_P")
	)
	(segment
		(start 223.139 -275.789898)
		(end 222.89135 -276.037548)
		(width 0.174752)
		(layer "F.Cu")
		(net "PE_RX2_DR2_N")
	)
	(segment
		(start 222.133414 -276.037548)
		(end 221.727014 -275.631148)
		(width 0.174752)
		(layer "F.Cu")
		(net "PE_RX2_DR2_N")
	)
	(segment
		(start 222.89135 -276.037548)
		(end 222.133414 -276.037548)
		(width 0.174752)
		(layer "F.Cu")
		(net "PE_RX2_DR2_N")
	)
	(segment
		(start 224.199958 -275.789898)
		(end 223.139 -275.789898)
		(width 0.174752)
		(layer "F.Cu")
		(net "PE_RX2_DR2_N")
	)
	(via
		(at 5.08 -323.535294)
		(size 0.508)
		(drill 0.254)
		(layers "F.Cu" "B.Cu")
		(net "PE_RX2_DR2_N")
	)
	(via
		(at 221.727014 -275.631148)
		(size 0.508)
		(drill 0.254)
		(layers "F.Cu" "B.Cu")
		(net "PE_RX2_DR2_N")
	)
	(segment
		(start 3.905504 -323.789548)
		(end 4.825746 -323.789548)
		(width 0.174752)
		(layer "B.Cu")
		(net "PE_RX2_DR2_N")
	)
	(segment
		(start 3.658108 -323.542152)
		(end 3.905504 -323.789548)
		(width 0.174752)
		(layer "B.Cu")
		(net "PE_RX2_DR2_N")
	)
	(segment
		(start 1.868932 -323.542152)
		(end 3.658108 -323.542152)
		(width 0.174752)
		(layer "B.Cu")
		(net "PE_RX2_DR2_N")
	)
	(segment
		(start 4.825746 -323.789548)
		(end 5.08 -323.535294)
		(width 0.174752)
		(layer "B.Cu")
		(net "PE_RX2_DR2_N")
	)
	(segment
		(start 45.440346 -303.749202)
		(end 39.076884 -304.87112)
		(width 0.1651)
		(layer "In2.Cu")
		(net "PE_RX2_DR2_N")
	)
	(segment
		(start 10.341864 -322.298314)
		(end 8.641588 -323.489066)
		(width 0.1651)
		(layer "In2.Cu")
		(net "PE_RX2_DR2_N")
	)
	(segment
		(start 14.478 -307.790088)
		(end 12.450826 -319.287144)
		(width 0.1651)
		(layer "In2.Cu")
		(net "PE_RX2_DR2_N")
	)
	(segment
		(start 179.394358 -268.76756)
		(end 67.139566 -288.556192)
		(width 0.1651)
		(layer "In2.Cu")
		(net "PE_RX2_DR2_N")
	)
	(segment
		(start 221.727014 -275.631148)
		(end 221.34576 -276.012402)
		(width 0.1651)
		(layer "In2.Cu")
		(net "PE_RX2_DR2_N")
	)
	(segment
		(start 221.34576 -276.012402)
		(end 220.481906 -276.012402)
		(width 0.1651)
		(layer "In2.Cu")
		(net "PE_RX2_DR2_N")
	)
	(segment
		(start 5.309108 -323.764402)
		(end 5.08 -323.535294)
		(width 0.1651)
		(layer "In2.Cu")
		(net "PE_RX2_DR2_N")
	)
	(segment
		(start 220.481906 -276.012402)
		(end 179.394358 -268.76756)
		(width 0.1651)
		(layer "In2.Cu")
		(net "PE_RX2_DR2_N")
	)
	(segment
		(start 15.935452 -305.70805)
		(end 14.478 -307.790088)
		(width 0.1651)
		(layer "In2.Cu")
		(net "PE_RX2_DR2_N")
	)
	(segment
		(start 39.076884 -304.87112)
		(end 23.155402 -302.063404)
		(width 0.1651)
		(layer "In2.Cu")
		(net "PE_RX2_DR2_N")
	)
	(segment
		(start 8.641588 -323.489066)
		(end 7.080758 -323.764402)
		(width 0.1651)
		(layer "In2.Cu")
		(net "PE_RX2_DR2_N")
	)
	(segment
		(start 12.450826 -319.287144)
		(end 10.341864 -322.298314)
		(width 0.1651)
		(layer "In2.Cu")
		(net "PE_RX2_DR2_N")
	)
	(segment
		(start 67.139566 -288.556192)
		(end 45.440346 -303.749202)
		(width 0.1651)
		(layer "In2.Cu")
		(net "PE_RX2_DR2_N")
	)
	(segment
		(start 23.155402 -302.063404)
		(end 20.461986 -302.538638)
		(width 0.1651)
		(layer "In2.Cu")
		(net "PE_RX2_DR2_N")
	)
	(segment
		(start 7.080758 -323.764402)
		(end 5.309108 -323.764402)
		(width 0.1651)
		(layer "In2.Cu")
		(net "PE_RX2_DR2_N")
	)
	(segment
		(start 20.461986 -302.538638)
		(end 15.935452 -305.70805)
		(width 0.1651)
		(layer "In2.Cu")
		(net "PE_RX2_DR2_N")
	)
	(segment
		(start 22.800056 -23.40991)
		(end 23.876 -23.40991)
		(width 0.174752)
		(layer "F.Cu")
		(net "PE_RX2_DR14_P")
	)
	(segment
		(start 24.866854 -23.657306)
		(end 25.273 -23.25116)
		(width 0.174752)
		(layer "F.Cu")
		(net "PE_RX2_DR14_P")
	)
	(segment
		(start 23.876 -23.40991)
		(end 24.27986 -23.657306)
		(width 0.174752)
		(layer "F.Cu")
		(net "PE_RX2_DR14_P")
	)
	(segment
		(start 24.27986 -23.657306)
		(end 24.866854 -23.657306)
		(width 0.174752)
		(layer "F.Cu")
		(net "PE_RX2_DR14_P")
	)
	(via
		(at 5.08 -158.348172)
		(size 0.508)
		(drill 0.254)
		(layers "F.Cu" "B.Cu")
		(net "PE_RX2_DR14_P")
	)
	(via
		(at 25.273 -23.25116)
		(size 0.508)
		(drill 0.254)
		(layers "F.Cu" "B.Cu")
		(net "PE_RX2_DR14_P")
	)
	(segment
		(start 1.868932 -158.342076)
		(end 3.658108 -158.342076)
		(width 0.174752)
		(layer "B.Cu")
		(net "PE_RX2_DR14_P")
	)
	(segment
		(start 3.658108 -158.342076)
		(end 3.905504 -158.09468)
		(width 0.174752)
		(layer "B.Cu")
		(net "PE_RX2_DR14_P")
	)
	(segment
		(start 3.905504 -158.09468)
		(end 4.826508 -158.09468)
		(width 0.174752)
		(layer "B.Cu")
		(net "PE_RX2_DR14_P")
	)
	(segment
		(start 4.826508 -158.09468)
		(end 5.08 -158.348172)
		(width 0.174752)
		(layer "B.Cu")
		(net "PE_RX2_DR14_P")
	)
	(segment
		(start 9.804654 -156.292804)
		(end 11.900408 -153.299922)
		(width 0.1651)
		(layer "In2.Cu")
		(net "PE_RX2_DR14_P")
	)
	(segment
		(start 30.382972 -25.254204)
		(end 28.602178 -24.007826)
		(width 0.1651)
		(layer "In2.Cu")
		(net "PE_RX2_DR14_P")
	)
	(segment
		(start 5.08 -158.348172)
		(end 5.308092 -158.12008)
		(width 0.1651)
		(layer "In2.Cu")
		(net "PE_RX2_DR14_P")
	)
	(segment
		(start 5.308092 -158.12008)
		(end 6.498336 -158.12008)
		(width 0.1651)
		(layer "In2.Cu")
		(net "PE_RX2_DR14_P")
	)
	(segment
		(start 17.00657 -80.716374)
		(end 27.348688 -65.946782)
		(width 0.1651)
		(layer "In2.Cu")
		(net "PE_RX2_DR14_P")
	)
	(segment
		(start 7.428992 -157.955996)
		(end 9.804654 -156.292804)
		(width 0.1651)
		(layer "In2.Cu")
		(net "PE_RX2_DR14_P")
	)
	(segment
		(start 10.297414 -118.759986)
		(end 17.00657 -80.716374)
		(width 0.1651)
		(layer "In2.Cu")
		(net "PE_RX2_DR14_P")
	)
	(segment
		(start 27.348688 -65.946782)
		(end 33.315656 -32.10306)
		(width 0.1651)
		(layer "In2.Cu")
		(net "PE_RX2_DR14_P")
	)
	(segment
		(start 14.144244 -140.576046)
		(end 10.297414 -118.759986)
		(width 0.1651)
		(layer "In2.Cu")
		(net "PE_RX2_DR14_P")
	)
	(segment
		(start 28.602178 -24.007826)
		(end 26.46934 -23.631906)
		(width 0.1651)
		(layer "In2.Cu")
		(net "PE_RX2_DR14_P")
	)
	(segment
		(start 11.900408 -153.299922)
		(end 14.144244 -140.576046)
		(width 0.1651)
		(layer "In2.Cu")
		(net "PE_RX2_DR14_P")
	)
	(segment
		(start 33.315656 -32.10306)
		(end 32.688276 -28.546552)
		(width 0.1651)
		(layer "In2.Cu")
		(net "PE_RX2_DR14_P")
	)
	(segment
		(start 32.688276 -28.546552)
		(end 30.382972 -25.254204)
		(width 0.1651)
		(layer "In2.Cu")
		(net "PE_RX2_DR14_P")
	)
	(segment
		(start 26.46934 -23.631906)
		(end 25.653746 -23.631906)
		(width 0.1651)
		(layer "In2.Cu")
		(net "PE_RX2_DR14_P")
	)
	(segment
		(start 6.498336 -158.12008)
		(end 7.428992 -157.955996)
		(width 0.1651)
		(layer "In2.Cu")
		(net "PE_RX2_DR14_P")
	)
	(segment
		(start 25.653746 -23.631906)
		(end 25.273 -23.25116)
		(width 0.1651)
		(layer "In2.Cu")
		(net "PE_RX2_DR14_P")
	)
	(segment
		(start 24.8666 -23.96236)
		(end 25.273 -24.36876)
		(width 0.174752)
		(layer "F.Cu")
		(net "PE_RX2_DR14_N")
	)
	(segment
		(start 24.03221 -24.21001)
		(end 24.27986 -23.96236)
		(width 0.174752)
		(layer "F.Cu")
		(net "PE_RX2_DR14_N")
	)
	(segment
		(start 22.800056 -24.21001)
		(end 24.03221 -24.21001)
		(width 0.174752)
		(layer "F.Cu")
		(net "PE_RX2_DR14_N")
	)
	(segment
		(start 24.27986 -23.96236)
		(end 24.8666 -23.96236)
		(width 0.174752)
		(layer "F.Cu")
		(net "PE_RX2_DR14_N")
	)
	(via
		(at 25.273 -24.36876)
		(size 0.508)
		(drill 0.254)
		(layers "F.Cu" "B.Cu")
		(net "PE_RX2_DR14_N")
	)
	(via
		(at 5.08 -157.535372)
		(size 0.508)
		(drill 0.254)
		(layers "F.Cu" "B.Cu")
		(net "PE_RX2_DR14_N")
	)
	(segment
		(start 3.905504 -157.789626)
		(end 4.825746 -157.789626)
		(width 0.174752)
		(layer "B.Cu")
		(net "PE_RX2_DR14_N")
	)
	(segment
		(start 3.658108 -157.54223)
		(end 3.905504 -157.789626)
		(width 0.174752)
		(layer "B.Cu")
		(net "PE_RX2_DR14_N")
	)
	(segment
		(start 4.825746 -157.789626)
		(end 5.08 -157.535372)
		(width 0.174752)
		(layer "B.Cu")
		(net "PE_RX2_DR14_N")
	)
	(segment
		(start 1.868932 -157.54223)
		(end 3.658108 -157.54223)
		(width 0.174752)
		(layer "B.Cu")
		(net "PE_RX2_DR14_N")
	)
	(segment
		(start 32.107886 -35.82162)
		(end 32.325564 -35.668966)
		(width 0.1651)
		(layer "In2.Cu")
		(net "PE_RX2_DR14_N")
	)
	(segment
		(start 31.547562 -39.000684)
		(end 31.633414 -38.513004)
		(width 0.1651)
		(layer "In2.Cu")
		(net "PE_RX2_DR14_N")
	)
	(segment
		(start 27.012138 -65.807336)
		(end 31.699962 -39.218362)
		(width 0.1651)
		(layer "In2.Cu")
		(net "PE_RX2_DR14_N")
	)
	(segment
		(start 30.365446 -26.17724)
		(end 30.411674 -25.915366)
		(width 0.1651)
		(layer "In2.Cu")
		(net "PE_RX2_DR14_N")
	)
	(segment
		(start 32.5628 -34.323274)
		(end 32.954468 -32.10306)
		(width 0.1651)
		(layer "In2.Cu")
		(net "PE_RX2_DR14_N")
	)
	(segment
		(start 31.195518 -27.034744)
		(end 30.911292 -26.629106)
		(width 0.1651)
		(layer "In2.Cu")
		(net "PE_RX2_DR14_N")
	)
	(segment
		(start 31.695136 -27.748484)
		(end 31.433262 -27.702256)
		(width 0.1651)
		(layer "In2.Cu")
		(net "PE_RX2_DR14_N")
	)
	(segment
		(start 9.936226 -118.759986)
		(end 16.67002 -80.576928)
		(width 0.1651)
		(layer "In2.Cu")
		(net "PE_RX2_DR14_N")
	)
	(segment
		(start 30.911292 -26.629106)
		(end 30.649418 -26.582878)
		(width 0.1651)
		(layer "In2.Cu")
		(net "PE_RX2_DR14_N")
	)
	(segment
		(start 31.937198 -37.87267)
		(end 31.784798 -37.654992)
		(width 0.1651)
		(layer "In2.Cu")
		(net "PE_RX2_DR14_N")
	)
	(segment
		(start 32.351726 -28.685998)
		(end 31.695136 -27.748484)
		(width 0.1651)
		(layer "In2.Cu")
		(net "PE_RX2_DR14_N")
	)
	(segment
		(start 31.851092 -38.36035)
		(end 31.937198 -37.87267)
		(width 0.1651)
		(layer "In2.Cu")
		(net "PE_RX2_DR14_N")
	)
	(segment
		(start 5.08 -157.535372)
		(end 5.309108 -157.76448)
		(width 0.1651)
		(layer "In2.Cu")
		(net "PE_RX2_DR14_N")
	)
	(segment
		(start 13.783056 -140.576046)
		(end 9.936226 -118.759986)
		(width 0.1651)
		(layer "In2.Cu")
		(net "PE_RX2_DR14_N")
	)
	(segment
		(start 32.174434 -36.526978)
		(end 32.022034 -36.3093)
		(width 0.1651)
		(layer "In2.Cu")
		(net "PE_RX2_DR14_N")
	)
	(segment
		(start 9.787128 -155.369768)
		(end 10.071354 -154.96413)
		(width 0.1651)
		(layer "In2.Cu")
		(net "PE_RX2_DR14_N")
	)
	(segment
		(start 31.633414 -38.513004)
		(end 31.851092 -38.36035)
		(width 0.1651)
		(layer "In2.Cu")
		(net "PE_RX2_DR14_N")
	)
	(segment
		(start 31.87065 -37.167312)
		(end 32.088328 -37.014658)
		(width 0.1651)
		(layer "In2.Cu")
		(net "PE_RX2_DR14_N")
	)
	(segment
		(start 11.563858 -153.160476)
		(end 13.783056 -140.576046)
		(width 0.1651)
		(layer "In2.Cu")
		(net "PE_RX2_DR14_N")
	)
	(segment
		(start 32.325564 -35.668966)
		(end 32.41167 -35.181286)
		(width 0.1651)
		(layer "In2.Cu")
		(net "PE_RX2_DR14_N")
	)
	(segment
		(start 10.332974 -154.917902)
		(end 11.563858 -153.160476)
		(width 0.1651)
		(layer "In2.Cu")
		(net "PE_RX2_DR14_N")
	)
	(segment
		(start 25.654254 -23.987506)
		(end 25.273 -24.36876)
		(width 0.1651)
		(layer "In2.Cu")
		(net "PE_RX2_DR14_N")
	)
	(segment
		(start 10.071354 -154.96413)
		(end 10.332974 -154.917902)
		(width 0.1651)
		(layer "In2.Cu")
		(net "PE_RX2_DR14_N")
	)
	(segment
		(start 16.67002 -80.576928)
		(end 27.012138 -65.807336)
		(width 0.1651)
		(layer "In2.Cu")
		(net "PE_RX2_DR14_N")
	)
	(segment
		(start 28.462732 -24.344376)
		(end 26.438098 -23.987506)
		(width 0.1651)
		(layer "In2.Cu")
		(net "PE_RX2_DR14_N")
	)
	(segment
		(start 32.25927 -34.963608)
		(end 32.345376 -34.475928)
		(width 0.1651)
		(layer "In2.Cu")
		(net "PE_RX2_DR14_N")
	)
	(segment
		(start 32.345376 -34.475928)
		(end 32.563054 -34.323274)
		(width 0.1651)
		(layer "In2.Cu")
		(net "PE_RX2_DR14_N")
	)
	(segment
		(start 9.54913 -156.03728)
		(end 9.833356 -155.631642)
		(width 0.1651)
		(layer "In2.Cu")
		(net "PE_RX2_DR14_N")
	)
	(segment
		(start 5.309108 -157.76448)
		(end 6.467094 -157.76448)
		(width 0.1651)
		(layer "In2.Cu")
		(net "PE_RX2_DR14_N")
	)
	(segment
		(start 31.784798 -37.654992)
		(end 31.87065 -37.167312)
		(width 0.1651)
		(layer "In2.Cu")
		(net "PE_RX2_DR14_N")
	)
	(segment
		(start 26.438098 -23.987506)
		(end 25.654254 -23.987506)
		(width 0.1651)
		(layer "In2.Cu")
		(net "PE_RX2_DR14_N")
	)
	(segment
		(start 32.088328 -37.014658)
		(end 32.174434 -36.526978)
		(width 0.1651)
		(layer "In2.Cu")
		(net "PE_RX2_DR14_N")
	)
	(segment
		(start 31.14929 -27.296618)
		(end 31.195518 -27.034744)
		(width 0.1651)
		(layer "In2.Cu")
		(net "PE_RX2_DR14_N")
	)
	(segment
		(start 32.022034 -36.3093)
		(end 32.107886 -35.82162)
		(width 0.1651)
		(layer "In2.Cu")
		(net "PE_RX2_DR14_N")
	)
	(segment
		(start 30.649418 -26.582878)
		(end 30.365446 -26.17724)
		(width 0.1651)
		(layer "In2.Cu")
		(net "PE_RX2_DR14_N")
	)
	(segment
		(start 32.563054 -34.323274)
		(end 32.5628 -34.323274)
		(width 0.1651)
		(layer "In2.Cu")
		(net "PE_RX2_DR14_N")
	)
	(segment
		(start 31.699962 -39.218362)
		(end 31.547562 -39.000684)
		(width 0.1651)
		(layer "In2.Cu")
		(net "PE_RX2_DR14_N")
	)
	(segment
		(start 31.433262 -27.702256)
		(end 31.14929 -27.296618)
		(width 0.1651)
		(layer "In2.Cu")
		(net "PE_RX2_DR14_N")
	)
	(segment
		(start 7.289546 -157.619446)
		(end 9.54913 -156.03728)
		(width 0.1651)
		(layer "In2.Cu")
		(net "PE_RX2_DR14_N")
	)
	(segment
		(start 30.127448 -25.509728)
		(end 28.462732 -24.344376)
		(width 0.1651)
		(layer "In2.Cu")
		(net "PE_RX2_DR14_N")
	)
	(segment
		(start 32.954468 -32.10306)
		(end 32.351726 -28.685998)
		(width 0.1651)
		(layer "In2.Cu")
		(net "PE_RX2_DR14_N")
	)
	(segment
		(start 32.41167 -35.181286)
		(end 32.25927 -34.963608)
		(width 0.1651)
		(layer "In2.Cu")
		(net "PE_RX2_DR14_N")
	)
	(segment
		(start 30.411674 -25.915366)
		(end 30.127448 -25.509728)
		(width 0.1651)
		(layer "In2.Cu")
		(net "PE_RX2_DR14_N")
	)
	(segment
		(start 9.833356 -155.631642)
		(end 9.787128 -155.369768)
		(width 0.1651)
		(layer "In2.Cu")
		(net "PE_RX2_DR14_N")
	)
	(segment
		(start 6.467094 -157.76448)
		(end 7.289546 -157.619446)
		(width 0.1651)
		(layer "In2.Cu")
		(net "PE_RX2_DR14_N")
	)
	(segment
		(start 24.866854 -126.657354)
		(end 25.273 -126.251208)
		(width 0.174752)
		(layer "F.Cu")
		(net "PE_RX2_DR13_P")
	)
	(segment
		(start 23.876 -126.409958)
		(end 24.22906 -126.657354)
		(width 0.174752)
		(layer "F.Cu")
		(net "PE_RX2_DR13_P")
	)
	(segment
		(start 24.22906 -126.657354)
		(end 24.866854 -126.657354)
		(width 0.174752)
		(layer "F.Cu")
		(net "PE_RX2_DR13_P")
	)
	(segment
		(start 22.800056 -126.409958)
		(end 23.876 -126.409958)
		(width 0.174752)
		(layer "F.Cu")
		(net "PE_RX2_DR13_P")
	)
	(via
		(at 5.08 -171.148248)
		(size 0.508)
		(drill 0.254)
		(layers "F.Cu" "B.Cu")
		(net "PE_RX2_DR13_P")
	)
	(via
		(at 25.273 -126.251208)
		(size 0.508)
		(drill 0.254)
		(layers "F.Cu" "B.Cu")
		(net "PE_RX2_DR13_P")
	)
	(segment
		(start 3.657854 -171.142152)
		(end 3.905504 -170.894502)
		(width 0.174752)
		(layer "B.Cu")
		(net "PE_RX2_DR13_P")
	)
	(segment
		(start 3.905504 -170.894502)
		(end 4.826254 -170.894502)
		(width 0.174752)
		(layer "B.Cu")
		(net "PE_RX2_DR13_P")
	)
	(segment
		(start 4.826254 -170.894502)
		(end 5.08 -171.148248)
		(width 0.174752)
		(layer "B.Cu")
		(net "PE_RX2_DR13_P")
	)
	(segment
		(start 1.868932 -171.142152)
		(end 3.657854 -171.142152)
		(width 0.174752)
		(layer "B.Cu")
		(net "PE_RX2_DR13_P")
	)
	(segment
		(start 28.02509 -126.89205)
		(end 29.084524 -127.633476)
		(width 0.1651)
		(layer "In2.Cu")
		(net "PE_RX2_DR13_P")
	)
	(segment
		(start 22.665436 -170.471084)
		(end 13.765276 -172.040804)
		(width 0.1651)
		(layer "In2.Cu")
		(net "PE_RX2_DR13_P")
	)
	(segment
		(start 29.084524 -127.633476)
		(end 29.726382 -128.55067)
		(width 0.1651)
		(layer "In2.Cu")
		(net "PE_RX2_DR13_P")
	)
	(segment
		(start 23.976584 -169.295826)
		(end 23.659338 -169.748962)
		(width 0.1651)
		(layer "In2.Cu")
		(net "PE_RX2_DR13_P")
	)
	(segment
		(start 23.659592 -169.749216)
		(end 23.623524 -169.800524)
		(width 0.1651)
		(layer "In2.Cu")
		(net "PE_RX2_DR13_P")
	)
	(segment
		(start 30.0609 -130.447288)
		(end 29.683456 -132.588762)
		(width 0.1651)
		(layer "In2.Cu")
		(net "PE_RX2_DR13_P")
	)
	(segment
		(start 23.659338 -169.748962)
		(end 23.659592 -169.749216)
		(width 0.1651)
		(layer "In2.Cu")
		(net "PE_RX2_DR13_P")
	)
	(segment
		(start 30.291532 -145.807684)
		(end 27.387804 -149.95525)
		(width 0.1651)
		(layer "In2.Cu")
		(net "PE_RX2_DR13_P")
	)
	(segment
		(start 23.623524 -169.800524)
		(end 22.665436 -170.471084)
		(width 0.1651)
		(layer "In2.Cu")
		(net "PE_RX2_DR13_P")
	)
	(segment
		(start 31.153354 -140.920216)
		(end 30.291532 -145.807684)
		(width 0.1651)
		(layer "In2.Cu")
		(net "PE_RX2_DR13_P")
	)
	(segment
		(start 5.308346 -170.919902)
		(end 5.08 -171.148248)
		(width 0.1651)
		(layer "In2.Cu")
		(net "PE_RX2_DR13_P")
	)
	(segment
		(start 7.143242 -170.919902)
		(end 5.308346 -170.919902)
		(width 0.1651)
		(layer "In2.Cu")
		(net "PE_RX2_DR13_P")
	)
	(segment
		(start 29.726382 -128.55067)
		(end 30.0609 -130.447288)
		(width 0.1651)
		(layer "In2.Cu")
		(net "PE_RX2_DR13_P")
	)
	(segment
		(start 26.54935 -126.631954)
		(end 28.02509 -126.89205)
		(width 0.1651)
		(layer "In2.Cu")
		(net "PE_RX2_DR13_P")
	)
	(segment
		(start 13.765276 -172.040804)
		(end 13.61694 -172.061378)
		(width 0.1651)
		(layer "In2.Cu")
		(net "PE_RX2_DR13_P")
	)
	(segment
		(start 25.653746 -126.631954)
		(end 26.54935 -126.631954)
		(width 0.1651)
		(layer "In2.Cu")
		(net "PE_RX2_DR13_P")
	)
	(segment
		(start 25.273 -126.251208)
		(end 25.653746 -126.631954)
		(width 0.1651)
		(layer "In2.Cu")
		(net "PE_RX2_DR13_P")
	)
	(segment
		(start 27.387804 -149.95525)
		(end 23.976584 -169.295826)
		(width 0.1651)
		(layer "In2.Cu")
		(net "PE_RX2_DR13_P")
	)
	(segment
		(start 13.61694 -172.061378)
		(end 7.143242 -170.919902)
		(width 0.1651)
		(layer "In2.Cu")
		(net "PE_RX2_DR13_P")
	)
	(segment
		(start 29.683456 -132.588762)
		(end 31.153354 -140.920216)
		(width 0.1651)
		(layer "In2.Cu")
		(net "PE_RX2_DR13_P")
	)
	(segment
		(start 24.8666 -126.962408)
		(end 25.273 -127.368808)
		(width 0.174752)
		(layer "F.Cu")
		(net "PE_RX2_DR13_N")
	)
	(segment
		(start 23.970742 -127.210058)
		(end 24.218392 -126.962408)
		(width 0.174752)
		(layer "F.Cu")
		(net "PE_RX2_DR13_N")
	)
	(segment
		(start 24.218392 -126.962408)
		(end 24.8666 -126.962408)
		(width 0.174752)
		(layer "F.Cu")
		(net "PE_RX2_DR13_N")
	)
	(segment
		(start 22.800056 -127.210058)
		(end 23.970742 -127.210058)
		(width 0.174752)
		(layer "F.Cu")
		(net "PE_RX2_DR13_N")
	)
	(via
		(at 25.273 -127.368808)
		(size 0.508)
		(drill 0.254)
		(layers "F.Cu" "B.Cu")
		(net "PE_RX2_DR13_N")
	)
	(via
		(at 5.08 -170.335448)
		(size 0.508)
		(drill 0.254)
		(layers "F.Cu" "B.Cu")
		(net "PE_RX2_DR13_N")
	)
	(segment
		(start 1.868932 -170.342052)
		(end 3.658108 -170.342052)
		(width 0.174752)
		(layer "B.Cu")
		(net "PE_RX2_DR13_N")
	)
	(segment
		(start 4.826 -170.589448)
		(end 5.08 -170.335448)
		(width 0.174752)
		(layer "B.Cu")
		(net "PE_RX2_DR13_N")
	)
	(segment
		(start 3.905504 -170.589448)
		(end 4.826 -170.589448)
		(width 0.174752)
		(layer "B.Cu")
		(net "PE_RX2_DR13_N")
	)
	(segment
		(start 3.658108 -170.342052)
		(end 3.905504 -170.589448)
		(width 0.174752)
		(layer "B.Cu")
		(net "PE_RX2_DR13_N")
	)
	(segment
		(start 27.55773 -148.764752)
		(end 27.841702 -148.35886)
		(width 0.1651)
		(layer "In2.Cu")
		(net "PE_RX2_DR13_N")
	)
	(segment
		(start 13.135864 -171.6151)
		(end 13.623544 -171.701206)
		(width 0.1651)
		(layer "In2.Cu")
		(net "PE_RX2_DR13_N")
	)
	(segment
		(start 11.149838 -171.074334)
		(end 11.637518 -171.160186)
		(width 0.1651)
		(layer "In2.Cu")
		(net "PE_RX2_DR13_N")
	)
	(segment
		(start 5.08 -170.335448)
		(end 5.308854 -170.564302)
		(width 0.1651)
		(layer "In2.Cu")
		(net "PE_RX2_DR13_N")
	)
	(segment
		(start 11.637518 -171.160186)
		(end 11.789918 -171.377864)
		(width 0.1651)
		(layer "In2.Cu")
		(net "PE_RX2_DR13_N")
	)
	(segment
		(start 27.051254 -149.815804)
		(end 27.603958 -149.026372)
		(width 0.1651)
		(layer "In2.Cu")
		(net "PE_RX2_DR13_N")
	)
	(segment
		(start 29.263086 -133.335014)
		(end 29.415486 -133.117336)
		(width 0.1651)
		(layer "In2.Cu")
		(net "PE_RX2_DR13_N")
	)
	(segment
		(start 27.885644 -127.2286)
		(end 26.518108 -126.987554)
		(width 0.1651)
		(layer "In2.Cu")
		(net "PE_RX2_DR13_N")
	)
	(segment
		(start 29.409136 -146.120104)
		(end 29.67101 -146.073876)
		(width 0.1651)
		(layer "In2.Cu")
		(net "PE_RX2_DR13_N")
	)
	(segment
		(start 22.947376 -169.83964)
		(end 23.368 -169.545)
		(width 0.1651)
		(layer "In2.Cu")
		(net "PE_RX2_DR13_N")
	)
	(segment
		(start 10.291826 -170.92295)
		(end 10.444226 -171.140628)
		(width 0.1651)
		(layer "In2.Cu")
		(net "PE_RX2_DR13_N")
	)
	(segment
		(start 29.699712 -130.447288)
		(end 29.389832 -128.690116)
		(width 0.1651)
		(layer "In2.Cu")
		(net "PE_RX2_DR13_N")
	)
	(segment
		(start 28.829 -127.889)
		(end 27.885644 -127.2286)
		(width 0.1651)
		(layer "In2.Cu")
		(net "PE_RX2_DR13_N")
	)
	(segment
		(start 28.103576 -148.312632)
		(end 28.387548 -147.906994)
		(width 0.1651)
		(layer "In2.Cu")
		(net "PE_RX2_DR13_N")
	)
	(segment
		(start 13.709904 -171.689268)
		(end 22.52599 -170.134534)
		(width 0.1651)
		(layer "In2.Cu")
		(net "PE_RX2_DR13_N")
	)
	(segment
		(start 27.841702 -148.35886)
		(end 28.103576 -148.312632)
		(width 0.1651)
		(layer "In2.Cu")
		(net "PE_RX2_DR13_N")
	)
	(segment
		(start 28.387548 -147.906994)
		(end 28.34132 -147.645374)
		(width 0.1651)
		(layer "In2.Cu")
		(net "PE_RX2_DR13_N")
	)
	(segment
		(start 25.331928 -159.563816)
		(end 27.051254 -149.815804)
		(width 0.1651)
		(layer "In2.Cu")
		(net "PE_RX2_DR13_N")
	)
	(segment
		(start 23.368 -169.545)
		(end 23.640034 -169.15638)
		(width 0.1651)
		(layer "In2.Cu")
		(net "PE_RX2_DR13_N")
	)
	(segment
		(start 29.125164 -146.525996)
		(end 29.409136 -146.120104)
		(width 0.1651)
		(layer "In2.Cu")
		(net "PE_RX2_DR13_N")
	)
	(segment
		(start 12.98321 -171.397422)
		(end 13.135864 -171.6151)
		(width 0.1651)
		(layer "In2.Cu")
		(net "PE_RX2_DR13_N")
	)
	(segment
		(start 29.648404 -134.437374)
		(end 29.56687 -133.975348)
		(width 0.1651)
		(layer "In2.Cu")
		(net "PE_RX2_DR13_N")
	)
	(segment
		(start 9.586214 -170.989498)
		(end 9.803892 -170.837098)
		(width 0.1651)
		(layer "In2.Cu")
		(net "PE_RX2_DR13_N")
	)
	(segment
		(start 12.277852 -171.46397)
		(end 12.49553 -171.31157)
		(width 0.1651)
		(layer "In2.Cu")
		(net "PE_RX2_DR13_N")
	)
	(segment
		(start 30.792166 -140.920216)
		(end 29.648404 -134.437374)
		(width 0.1651)
		(layer "In2.Cu")
		(net "PE_RX2_DR13_N")
	)
	(segment
		(start 7.174484 -170.564302)
		(end 9.586214 -170.989498)
		(width 0.1651)
		(layer "In2.Cu")
		(net "PE_RX2_DR13_N")
	)
	(segment
		(start 28.34132 -147.645374)
		(end 28.625292 -147.239482)
		(width 0.1651)
		(layer "In2.Cu")
		(net "PE_RX2_DR13_N")
	)
	(segment
		(start 9.803892 -170.837098)
		(end 10.291826 -170.92295)
		(width 0.1651)
		(layer "In2.Cu")
		(net "PE_RX2_DR13_N")
	)
	(segment
		(start 23.640034 -169.15638)
		(end 25.331928 -159.563816)
		(width 0.1651)
		(layer "In2.Cu")
		(net "PE_RX2_DR13_N")
	)
	(segment
		(start 25.654254 -126.987554)
		(end 25.273 -127.368808)
		(width 0.1651)
		(layer "In2.Cu")
		(net "PE_RX2_DR13_N")
	)
	(segment
		(start 29.349192 -133.822948)
		(end 29.263086 -133.335014)
		(width 0.1651)
		(layer "In2.Cu")
		(net "PE_RX2_DR13_N")
	)
	(segment
		(start 29.171138 -146.787616)
		(end 29.125164 -146.525996)
		(width 0.1651)
		(layer "In2.Cu")
		(net "PE_RX2_DR13_N")
	)
	(segment
		(start 13.623544 -171.701206)
		(end 13.709904 -171.689268)
		(width 0.1651)
		(layer "In2.Cu")
		(net "PE_RX2_DR13_N")
	)
	(segment
		(start 29.954982 -145.668238)
		(end 30.792166 -140.920216)
		(width 0.1651)
		(layer "In2.Cu")
		(net "PE_RX2_DR13_N")
	)
	(segment
		(start 10.444226 -171.140628)
		(end 10.931906 -171.226734)
		(width 0.1651)
		(layer "In2.Cu")
		(net "PE_RX2_DR13_N")
	)
	(segment
		(start 29.389832 -128.690116)
		(end 28.829 -127.889)
		(width 0.1651)
		(layer "In2.Cu")
		(net "PE_RX2_DR13_N")
	)
	(segment
		(start 29.67101 -146.073876)
		(end 29.954982 -145.668238)
		(width 0.1651)
		(layer "In2.Cu")
		(net "PE_RX2_DR13_N")
	)
	(segment
		(start 12.49553 -171.31157)
		(end 12.98321 -171.397422)
		(width 0.1651)
		(layer "In2.Cu")
		(net "PE_RX2_DR13_N")
	)
	(segment
		(start 22.52599 -170.134534)
		(end 22.947376 -169.83964)
		(width 0.1651)
		(layer "In2.Cu")
		(net "PE_RX2_DR13_N")
	)
	(segment
		(start 11.789918 -171.377864)
		(end 12.277852 -171.46397)
		(width 0.1651)
		(layer "In2.Cu")
		(net "PE_RX2_DR13_N")
	)
	(segment
		(start 26.518108 -126.987554)
		(end 25.654254 -126.987554)
		(width 0.1651)
		(layer "In2.Cu")
		(net "PE_RX2_DR13_N")
	)
	(segment
		(start 29.415486 -133.117336)
		(end 29.322268 -132.588762)
		(width 0.1651)
		(layer "In2.Cu")
		(net "PE_RX2_DR13_N")
	)
	(segment
		(start 29.322268 -132.588762)
		(end 29.699712 -130.447288)
		(width 0.1651)
		(layer "In2.Cu")
		(net "PE_RX2_DR13_N")
	)
	(segment
		(start 29.56687 -133.975348)
		(end 29.349192 -133.822948)
		(width 0.1651)
		(layer "In2.Cu")
		(net "PE_RX2_DR13_N")
	)
	(segment
		(start 10.931906 -171.226734)
		(end 11.149838 -171.074334)
		(width 0.1651)
		(layer "In2.Cu")
		(net "PE_RX2_DR13_N")
	)
	(segment
		(start 28.625292 -147.239482)
		(end 28.887166 -147.193254)
		(width 0.1651)
		(layer "In2.Cu")
		(net "PE_RX2_DR13_N")
	)
	(segment
		(start 28.887166 -147.193254)
		(end 29.171138 -146.787616)
		(width 0.1651)
		(layer "In2.Cu")
		(net "PE_RX2_DR13_N")
	)
	(segment
		(start 27.603958 -149.026372)
		(end 27.55773 -148.764752)
		(width 0.1651)
		(layer "In2.Cu")
		(net "PE_RX2_DR13_N")
	)
	(segment
		(start 5.308854 -170.564302)
		(end 7.174484 -170.564302)
		(width 0.1651)
		(layer "In2.Cu")
		(net "PE_RX2_DR13_N")
	)
	(segment
		(start 23.876 -229.410006)
		(end 24.123396 -229.657402)
		(width 0.174752)
		(layer "F.Cu")
		(net "PE_RX2_DR12_P")
	)
	(segment
		(start 24.123396 -229.657402)
		(end 24.866854 -229.657402)
		(width 0.174752)
		(layer "F.Cu")
		(net "PE_RX2_DR12_P")
	)
	(segment
		(start 22.800056 -229.410006)
		(end 23.876 -229.410006)
		(width 0.174752)
		(layer "F.Cu")
		(net "PE_RX2_DR12_P")
	)
	(segment
		(start 24.866854 -229.657402)
		(end 25.273 -229.251256)
		(width 0.174752)
		(layer "F.Cu")
		(net "PE_RX2_DR12_P")
	)
	(via
		(at 25.273 -229.251256)
		(size 0.508)
		(drill 0.254)
		(layers "F.Cu" "B.Cu")
		(net "PE_RX2_DR12_P")
	)
	(via
		(at 5.08 -216.748106)
		(size 0.508)
		(drill 0.254)
		(layers "F.Cu" "B.Cu")
		(net "PE_RX2_DR12_P")
	)
	(segment
		(start 3.78333 -216.74201)
		(end 4.030726 -216.494614)
		(width 0.174752)
		(layer "B.Cu")
		(net "PE_RX2_DR12_P")
	)
	(segment
		(start 4.030726 -216.494614)
		(end 4.826508 -216.494614)
		(width 0.174752)
		(layer "B.Cu")
		(net "PE_RX2_DR12_P")
	)
	(segment
		(start 4.826508 -216.494614)
		(end 5.08 -216.748106)
		(width 0.174752)
		(layer "B.Cu")
		(net "PE_RX2_DR12_P")
	)
	(segment
		(start 1.868932 -216.74201)
		(end 3.78333 -216.74201)
		(width 0.174752)
		(layer "B.Cu")
		(net "PE_RX2_DR12_P")
	)
	(segment
		(start 25.653746 -229.632002)
		(end 26.518108 -229.632002)
		(width 0.1651)
		(layer "In2.Cu")
		(net "PE_RX2_DR12_P")
	)
	(segment
		(start 5.308092 -216.520014)
		(end 5.08 -216.748106)
		(width 0.1651)
		(layer "In2.Cu")
		(net "PE_RX2_DR12_P")
	)
	(segment
		(start 35.534092 -223.336612)
		(end 35.818064 -222.930974)
		(width 0.1651)
		(layer "In2.Cu")
		(net "PE_RX2_DR12_P")
	)
	(segment
		(start 14.556994 -205.970886)
		(end 13.434822 -212.328506)
		(width 0.1651)
		(layer "In2.Cu")
		(net "PE_RX2_DR12_P")
	)
	(segment
		(start 13.434822 -212.328506)
		(end 11.574018 -214.986362)
		(width 0.1651)
		(layer "In2.Cu")
		(net "PE_RX2_DR12_P")
	)
	(segment
		(start 17.705324 -201.474578)
		(end 14.556994 -205.970886)
		(width 0.1651)
		(layer "In2.Cu")
		(net "PE_RX2_DR12_P")
	)
	(segment
		(start 22.902164 -199.636634)
		(end 19.46402 -200.243186)
		(width 0.1651)
		(layer "In2.Cu")
		(net "PE_RX2_DR12_P")
	)
	(segment
		(start 35.03422 -224.050352)
		(end 34.988246 -223.788478)
		(width 0.1651)
		(layer "In2.Cu")
		(net "PE_RX2_DR12_P")
	)
	(segment
		(start 29.119576 -228.586792)
		(end 29.525214 -228.30282)
		(width 0.1651)
		(layer "In2.Cu")
		(net "PE_RX2_DR12_P")
	)
	(segment
		(start 28.857702 -228.540564)
		(end 29.119576 -228.586792)
		(width 0.1651)
		(layer "In2.Cu")
		(net "PE_RX2_DR12_P")
	)
	(segment
		(start 31.096458 -226.97313)
		(end 31.358332 -227.019104)
		(width 0.1651)
		(layer "In2.Cu")
		(net "PE_RX2_DR12_P")
	)
	(segment
		(start 35.272218 -223.38284)
		(end 35.534092 -223.336612)
		(width 0.1651)
		(layer "In2.Cu")
		(net "PE_RX2_DR12_P")
	)
	(segment
		(start 37.10178 -221.097856)
		(end 43.402504 -212.099652)
		(width 0.1651)
		(layer "In2.Cu")
		(net "PE_RX2_DR12_P")
	)
	(segment
		(start 38.937692 -202.465178)
		(end 22.902164 -199.636634)
		(width 0.1651)
		(layer "In2.Cu")
		(net "PE_RX2_DR12_P")
	)
	(segment
		(start 35.77209 -222.6691)
		(end 36.056062 -222.263462)
		(width 0.1651)
		(layer "In2.Cu")
		(net "PE_RX2_DR12_P")
	)
	(segment
		(start 43.904408 -209.253582)
		(end 43.47845 -206.837026)
		(width 0.1651)
		(layer "In2.Cu")
		(net "PE_RX2_DR12_P")
	)
	(segment
		(start 41.839896 -204.497432)
		(end 38.937692 -202.465178)
		(width 0.1651)
		(layer "In2.Cu")
		(net "PE_RX2_DR12_P")
	)
	(segment
		(start 35.818064 -222.930974)
		(end 35.77209 -222.6691)
		(width 0.1651)
		(layer "In2.Cu")
		(net "PE_RX2_DR12_P")
	)
	(segment
		(start 36.601908 -221.811596)
		(end 36.555934 -221.549722)
		(width 0.1651)
		(layer "In2.Cu")
		(net "PE_RX2_DR12_P")
	)
	(segment
		(start 28.452064 -228.82479)
		(end 28.857702 -228.540564)
		(width 0.1651)
		(layer "In2.Cu")
		(net "PE_RX2_DR12_P")
	)
	(segment
		(start 31.358332 -227.019104)
		(end 34.491676 -224.825306)
		(width 0.1651)
		(layer "In2.Cu")
		(net "PE_RX2_DR12_P")
	)
	(segment
		(start 25.273 -229.251256)
		(end 25.653746 -229.632002)
		(width 0.1651)
		(layer "In2.Cu")
		(net "PE_RX2_DR12_P")
	)
	(segment
		(start 29.525214 -228.30282)
		(end 29.571442 -228.040946)
		(width 0.1651)
		(layer "In2.Cu")
		(net "PE_RX2_DR12_P")
	)
	(segment
		(start 28.405836 -229.086664)
		(end 28.452064 -228.82479)
		(width 0.1651)
		(layer "In2.Cu")
		(net "PE_RX2_DR12_P")
	)
	(segment
		(start 36.839906 -221.144084)
		(end 37.10178 -221.097856)
		(width 0.1651)
		(layer "In2.Cu")
		(net "PE_RX2_DR12_P")
	)
	(segment
		(start 30.69082 -227.257102)
		(end 31.096458 -226.97313)
		(width 0.1651)
		(layer "In2.Cu")
		(net "PE_RX2_DR12_P")
	)
	(segment
		(start 11.574018 -214.986362)
		(end 10.149078 -215.984074)
		(width 0.1651)
		(layer "In2.Cu")
		(net "PE_RX2_DR12_P")
	)
	(segment
		(start 30.644592 -227.518976)
		(end 30.69082 -227.257102)
		(width 0.1651)
		(layer "In2.Cu")
		(net "PE_RX2_DR12_P")
	)
	(segment
		(start 8.6106 -216.446354)
		(end 8.12292 -216.53246)
		(width 0.1651)
		(layer "In2.Cu")
		(net "PE_RX2_DR12_P")
	)
	(segment
		(start 7.905242 -216.38006)
		(end 7.112 -216.520014)
		(width 0.1651)
		(layer "In2.Cu")
		(net "PE_RX2_DR12_P")
	)
	(segment
		(start 36.056062 -222.263462)
		(end 36.317936 -222.217234)
		(width 0.1651)
		(layer "In2.Cu")
		(net "PE_RX2_DR12_P")
	)
	(segment
		(start 36.317936 -222.217234)
		(end 36.601908 -221.811596)
		(width 0.1651)
		(layer "In2.Cu")
		(net "PE_RX2_DR12_P")
	)
	(segment
		(start 28.000198 -229.370636)
		(end 28.405836 -229.086664)
		(width 0.1651)
		(layer "In2.Cu")
		(net "PE_RX2_DR12_P")
	)
	(segment
		(start 8.12292 -216.53246)
		(end 7.905242 -216.38006)
		(width 0.1651)
		(layer "In2.Cu")
		(net "PE_RX2_DR12_P")
	)
	(segment
		(start 34.491676 -224.825306)
		(end 35.03422 -224.050352)
		(width 0.1651)
		(layer "In2.Cu")
		(net "PE_RX2_DR12_P")
	)
	(segment
		(start 36.555934 -221.549722)
		(end 36.839906 -221.144084)
		(width 0.1651)
		(layer "In2.Cu")
		(net "PE_RX2_DR12_P")
	)
	(segment
		(start 43.402504 -212.099652)
		(end 43.904408 -209.253582)
		(width 0.1651)
		(layer "In2.Cu")
		(net "PE_RX2_DR12_P")
	)
	(segment
		(start 26.518108 -229.632002)
		(end 28.000198 -229.370636)
		(width 0.1651)
		(layer "In2.Cu")
		(net "PE_RX2_DR12_P")
	)
	(segment
		(start 34.988246 -223.788478)
		(end 35.272218 -223.38284)
		(width 0.1651)
		(layer "In2.Cu")
		(net "PE_RX2_DR12_P")
	)
	(segment
		(start 10.149078 -215.984074)
		(end 8.763 -216.228676)
		(width 0.1651)
		(layer "In2.Cu")
		(net "PE_RX2_DR12_P")
	)
	(segment
		(start 29.97708 -227.756974)
		(end 30.238954 -227.802948)
		(width 0.1651)
		(layer "In2.Cu")
		(net "PE_RX2_DR12_P")
	)
	(segment
		(start 7.112 -216.520014)
		(end 5.308092 -216.520014)
		(width 0.1651)
		(layer "In2.Cu")
		(net "PE_RX2_DR12_P")
	)
	(segment
		(start 19.46402 -200.243186)
		(end 17.705324 -201.474578)
		(width 0.1651)
		(layer "In2.Cu")
		(net "PE_RX2_DR12_P")
	)
	(segment
		(start 8.763 -216.228676)
		(end 8.6106 -216.446354)
		(width 0.1651)
		(layer "In2.Cu")
		(net "PE_RX2_DR12_P")
	)
	(segment
		(start 43.47845 -206.837026)
		(end 41.839896 -204.497432)
		(width 0.1651)
		(layer "In2.Cu")
		(net "PE_RX2_DR12_P")
	)
	(segment
		(start 30.238954 -227.802948)
		(end 30.644592 -227.518976)
		(width 0.1651)
		(layer "In2.Cu")
		(net "PE_RX2_DR12_P")
	)
	(segment
		(start 29.571442 -228.040946)
		(end 29.97708 -227.756974)
		(width 0.1651)
		(layer "In2.Cu")
		(net "PE_RX2_DR12_P")
	)
	(segment
		(start 23.88235 -230.210106)
		(end 24.13 -229.962456)
		(width 0.174752)
		(layer "F.Cu")
		(net "PE_RX2_DR12_N")
	)
	(segment
		(start 24.8666 -229.962456)
		(end 25.273 -230.368856)
		(width 0.174752)
		(layer "F.Cu")
		(net "PE_RX2_DR12_N")
	)
	(segment
		(start 22.800056 -230.210106)
		(end 23.88235 -230.210106)
		(width 0.174752)
		(layer "F.Cu")
		(net "PE_RX2_DR12_N")
	)
	(segment
		(start 24.13 -229.962456)
		(end 24.8666 -229.962456)
		(width 0.174752)
		(layer "F.Cu")
		(net "PE_RX2_DR12_N")
	)
	(via
		(at 25.273 -230.368856)
		(size 0.508)
		(drill 0.254)
		(layers "F.Cu" "B.Cu")
		(net "PE_RX2_DR12_N")
	)
	(via
		(at 5.08 -215.935306)
		(size 0.508)
		(drill 0.254)
		(layers "F.Cu" "B.Cu")
		(net "PE_RX2_DR12_N")
	)
	(segment
		(start 4.825746 -216.18956)
		(end 5.08 -215.935306)
		(width 0.174752)
		(layer "B.Cu")
		(net "PE_RX2_DR12_N")
	)
	(segment
		(start 1.868932 -215.942164)
		(end 3.658108 -215.942164)
		(width 0.174752)
		(layer "B.Cu")
		(net "PE_RX2_DR12_N")
	)
	(segment
		(start 3.658108 -215.942164)
		(end 4.03352 -216.18956)
		(width 0.174752)
		(layer "B.Cu")
		(net "PE_RX2_DR12_N")
	)
	(segment
		(start 4.03352 -216.18956)
		(end 4.825746 -216.18956)
		(width 0.174752)
		(layer "B.Cu")
		(net "PE_RX2_DR12_N")
	)
	(segment
		(start 39.077138 -202.128628)
		(end 22.902164 -199.275446)
		(width 0.1651)
		(layer "In2.Cu")
		(net "PE_RX2_DR12_N")
	)
	(segment
		(start 34.7472 -225.08083)
		(end 43.739054 -212.239098)
		(width 0.1651)
		(layer "In2.Cu")
		(net "PE_RX2_DR12_N")
	)
	(segment
		(start 44.265596 -209.253582)
		(end 43.815 -206.69758)
		(width 0.1651)
		(layer "In2.Cu")
		(net "PE_RX2_DR12_N")
	)
	(segment
		(start 43.739054 -212.239098)
		(end 44.265596 -209.253582)
		(width 0.1651)
		(layer "In2.Cu")
		(net "PE_RX2_DR12_N")
	)
	(segment
		(start 25.273 -230.368856)
		(end 25.654254 -229.987602)
		(width 0.1651)
		(layer "In2.Cu")
		(net "PE_RX2_DR12_N")
	)
	(segment
		(start 17.4498 -201.219054)
		(end 14.220444 -205.83144)
		(width 0.1651)
		(layer "In2.Cu")
		(net "PE_RX2_DR12_N")
	)
	(segment
		(start 13.098272 -212.18906)
		(end 11.318494 -214.730838)
		(width 0.1651)
		(layer "In2.Cu")
		(net "PE_RX2_DR12_N")
	)
	(segment
		(start 22.902164 -199.275446)
		(end 19.324574 -199.906636)
		(width 0.1651)
		(layer "In2.Cu")
		(net "PE_RX2_DR12_N")
	)
	(segment
		(start 25.654254 -229.987602)
		(end 26.54935 -229.987602)
		(width 0.1651)
		(layer "In2.Cu")
		(net "PE_RX2_DR12_N")
	)
	(segment
		(start 11.318494 -214.730838)
		(end 10.009632 -215.647524)
		(width 0.1651)
		(layer "In2.Cu")
		(net "PE_RX2_DR12_N")
	)
	(segment
		(start 19.324574 -199.906636)
		(end 17.4498 -201.219054)
		(width 0.1651)
		(layer "In2.Cu")
		(net "PE_RX2_DR12_N")
	)
	(segment
		(start 26.54935 -229.987602)
		(end 28.139644 -229.707186)
		(width 0.1651)
		(layer "In2.Cu")
		(net "PE_RX2_DR12_N")
	)
	(segment
		(start 5.309108 -216.164414)
		(end 5.08 -215.935306)
		(width 0.1651)
		(layer "In2.Cu")
		(net "PE_RX2_DR12_N")
	)
	(segment
		(start 14.220444 -205.83144)
		(end 13.098272 -212.18906)
		(width 0.1651)
		(layer "In2.Cu")
		(net "PE_RX2_DR12_N")
	)
	(segment
		(start 7.080758 -216.164414)
		(end 5.309108 -216.164414)
		(width 0.1651)
		(layer "In2.Cu")
		(net "PE_RX2_DR12_N")
	)
	(segment
		(start 43.815 -206.69758)
		(end 42.09542 -204.241908)
		(width 0.1651)
		(layer "In2.Cu")
		(net "PE_RX2_DR12_N")
	)
	(segment
		(start 42.09542 -204.241908)
		(end 39.077138 -202.128628)
		(width 0.1651)
		(layer "In2.Cu")
		(net "PE_RX2_DR12_N")
	)
	(segment
		(start 28.139898 -229.707186)
		(end 34.7472 -225.08083)
		(width 0.1651)
		(layer "In2.Cu")
		(net "PE_RX2_DR12_N")
	)
	(segment
		(start 28.139644 -229.707186)
		(end 28.139898 -229.707186)
		(width 0.1651)
		(layer "In2.Cu")
		(net "PE_RX2_DR12_N")
	)
	(segment
		(start 10.009632 -215.647524)
		(end 7.080758 -216.164414)
		(width 0.1651)
		(layer "In2.Cu")
		(net "PE_RX2_DR12_N")
	)
	(segment
		(start 24.866854 -332.65745)
		(end 25.273 -332.251304)
		(width 0.174752)
		(layer "F.Cu")
		(net "PE_RX2_DR11_P")
	)
	(segment
		(start 22.800056 -332.410054)
		(end 23.876 -332.410054)
		(width 0.174752)
		(layer "F.Cu")
		(net "PE_RX2_DR11_P")
	)
	(segment
		(start 23.876 -332.410054)
		(end 24.2443 -332.65745)
		(width 0.174752)
		(layer "F.Cu")
		(net "PE_RX2_DR11_P")
	)
	(segment
		(start 24.2443 -332.65745)
		(end 24.866854 -332.65745)
		(width 0.174752)
		(layer "F.Cu")
		(net "PE_RX2_DR11_P")
	)
	(via
		(at 5.08 -339.548216)
		(size 0.508)
		(drill 0.254)
		(layers "F.Cu" "B.Cu")
		(net "PE_RX2_DR11_P")
	)
	(via
		(at 25.273 -332.251304)
		(size 0.508)
		(drill 0.254)
		(layers "F.Cu" "B.Cu")
		(net "PE_RX2_DR11_P")
	)
	(segment
		(start 3.905504 -339.29447)
		(end 4.826254 -339.29447)
		(width 0.174752)
		(layer "B.Cu")
		(net "PE_RX2_DR11_P")
	)
	(segment
		(start 1.868932 -339.54212)
		(end 3.657854 -339.54212)
		(width 0.174752)
		(layer "B.Cu")
		(net "PE_RX2_DR11_P")
	)
	(segment
		(start 4.826254 -339.29447)
		(end 5.08 -339.548216)
		(width 0.174752)
		(layer "B.Cu")
		(net "PE_RX2_DR11_P")
	)
	(segment
		(start 3.657854 -339.54212)
		(end 3.905504 -339.29447)
		(width 0.174752)
		(layer "B.Cu")
		(net "PE_RX2_DR11_P")
	)
	(segment
		(start 28.899612 -340.689692)
		(end 30.151578 -347.79331)
		(width 0.1651)
		(layer "In2.Cu")
		(net "PE_RX2_DR11_P")
	)
	(segment
		(start 26.562812 -352.820224)
		(end 24.155146 -353.244912)
		(width 0.1651)
		(layer "In2.Cu")
		(net "PE_RX2_DR11_P")
	)
	(segment
		(start 12.51331 -342.402922)
		(end 10.485628 -340.982808)
		(width 0.1651)
		(layer "In2.Cu")
		(net "PE_RX2_DR11_P")
	)
	(segment
		(start 29.61894 -336.610198)
		(end 28.899612 -340.689692)
		(width 0.1651)
		(layer "In2.Cu")
		(net "PE_RX2_DR11_P")
	)
	(segment
		(start 10.485628 -340.982808)
		(end 8.457438 -339.562694)
		(width 0.1651)
		(layer "In2.Cu")
		(net "PE_RX2_DR11_P")
	)
	(segment
		(start 29.194252 -334.201516)
		(end 29.61894 -336.610198)
		(width 0.1651)
		(layer "In2.Cu")
		(net "PE_RX2_DR11_P")
	)
	(segment
		(start 7.080758 -339.31987)
		(end 5.308346 -339.31987)
		(width 0.1651)
		(layer "In2.Cu")
		(net "PE_RX2_DR11_P")
	)
	(segment
		(start 28.703524 -333.500476)
		(end 29.194252 -334.201516)
		(width 0.1651)
		(layer "In2.Cu")
		(net "PE_RX2_DR11_P")
	)
	(segment
		(start 8.457438 -339.562694)
		(end 7.080758 -339.31987)
		(width 0.1651)
		(layer "In2.Cu")
		(net "PE_RX2_DR11_P")
	)
	(segment
		(start 25.273 -332.251304)
		(end 25.653746 -332.63205)
		(width 0.1651)
		(layer "In2.Cu")
		(net "PE_RX2_DR11_P")
	)
	(segment
		(start 26.54935 -332.63205)
		(end 27.770074 -332.847188)
		(width 0.1651)
		(layer "In2.Cu")
		(net "PE_RX2_DR11_P")
	)
	(segment
		(start 30.151578 -347.79331)
		(end 29.717492 -350.255586)
		(width 0.1651)
		(layer "In2.Cu")
		(net "PE_RX2_DR11_P")
	)
	(segment
		(start 27.770074 -332.847188)
		(end 28.703524 -333.500476)
		(width 0.1651)
		(layer "In2.Cu")
		(net "PE_RX2_DR11_P")
	)
	(segment
		(start 25.653746 -332.63205)
		(end 26.54935 -332.63205)
		(width 0.1651)
		(layer "In2.Cu")
		(net "PE_RX2_DR11_P")
	)
	(segment
		(start 5.308346 -339.31987)
		(end 5.08 -339.548216)
		(width 0.1651)
		(layer "In2.Cu")
		(net "PE_RX2_DR11_P")
	)
	(segment
		(start 29.228034 -350.954848)
		(end 26.562812 -352.820224)
		(width 0.1651)
		(layer "In2.Cu")
		(net "PE_RX2_DR11_P")
	)
	(segment
		(start 22.602444 -352.9711)
		(end 17.327118 -349.277686)
		(width 0.1651)
		(layer "In2.Cu")
		(net "PE_RX2_DR11_P")
	)
	(segment
		(start 24.155146 -353.244912)
		(end 22.602444 -352.9711)
		(width 0.1651)
		(layer "In2.Cu")
		(net "PE_RX2_DR11_P")
	)
	(segment
		(start 17.327118 -349.277686)
		(end 12.51331 -342.402922)
		(width 0.1651)
		(layer "In2.Cu")
		(net "PE_RX2_DR11_P")
	)
	(segment
		(start 29.717492 -350.255586)
		(end 29.228034 -350.954848)
		(width 0.1651)
		(layer "In2.Cu")
		(net "PE_RX2_DR11_P")
	)
	(segment
		(start 24.245316 -332.962504)
		(end 24.8666 -332.962504)
		(width 0.174752)
		(layer "F.Cu")
		(net "PE_RX2_DR11_N")
	)
	(segment
		(start 24.8666 -332.962504)
		(end 25.273 -333.368904)
		(width 0.174752)
		(layer "F.Cu")
		(net "PE_RX2_DR11_N")
	)
	(segment
		(start 22.800056 -333.210154)
		(end 23.997666 -333.210154)
		(width 0.174752)
		(layer "F.Cu")
		(net "PE_RX2_DR11_N")
	)
	(segment
		(start 23.997666 -333.210154)
		(end 24.245316 -332.962504)
		(width 0.174752)
		(layer "F.Cu")
		(net "PE_RX2_DR11_N")
	)
	(via
		(at 5.08 -338.735416)
		(size 0.508)
		(drill 0.254)
		(layers "F.Cu" "B.Cu")
		(net "PE_RX2_DR11_N")
	)
	(via
		(at 25.273 -333.368904)
		(size 0.508)
		(drill 0.254)
		(layers "F.Cu" "B.Cu")
		(net "PE_RX2_DR11_N")
	)
	(segment
		(start 1.868932 -338.74202)
		(end 3.658108 -338.74202)
		(width 0.174752)
		(layer "B.Cu")
		(net "PE_RX2_DR11_N")
	)
	(segment
		(start 4.826 -338.989416)
		(end 5.08 -338.735416)
		(width 0.174752)
		(layer "B.Cu")
		(net "PE_RX2_DR11_N")
	)
	(segment
		(start 3.658108 -338.74202)
		(end 3.905504 -338.989416)
		(width 0.174752)
		(layer "B.Cu")
		(net "PE_RX2_DR11_N")
	)
	(segment
		(start 3.905504 -338.989416)
		(end 4.826 -338.989416)
		(width 0.174752)
		(layer "B.Cu")
		(net "PE_RX2_DR11_N")
	)
	(segment
		(start 5.308854 -338.96427)
		(end 5.08 -338.735416)
		(width 0.1651)
		(layer "In2.Cu")
		(net "PE_RX2_DR11_N")
	)
	(segment
		(start 7.112 -338.96427)
		(end 5.308854 -338.96427)
		(width 0.1651)
		(layer "In2.Cu")
		(net "PE_RX2_DR11_N")
	)
	(segment
		(start 18.70202 -349.806006)
		(end 18.655792 -349.544132)
		(width 0.1651)
		(layer "In2.Cu")
		(net "PE_RX2_DR11_N")
	)
	(segment
		(start 9.716262 -340.009988)
		(end 9.670034 -339.748114)
		(width 0.1651)
		(layer "In2.Cu")
		(net "PE_RX2_DR11_N")
	)
	(segment
		(start 29.020516 -335.264506)
		(end 28.868116 -335.482184)
		(width 0.1651)
		(layer "In2.Cu")
		(net "PE_RX2_DR11_N")
	)
	(segment
		(start 18.655792 -349.544132)
		(end 18.250154 -349.26016)
		(width 0.1651)
		(layer "In2.Cu")
		(net "PE_RX2_DR11_N")
	)
	(segment
		(start 10.83564 -340.793832)
		(end 10.789412 -340.531958)
		(width 0.1651)
		(layer "In2.Cu")
		(net "PE_RX2_DR11_N")
	)
	(segment
		(start 11.955018 -341.577676)
		(end 11.90879 -341.315802)
		(width 0.1651)
		(layer "In2.Cu")
		(net "PE_RX2_DR11_N")
	)
	(segment
		(start 10.1219 -340.29396)
		(end 9.716262 -340.009988)
		(width 0.1651)
		(layer "In2.Cu")
		(net "PE_RX2_DR11_N")
	)
	(segment
		(start 12.768834 -342.147398)
		(end 11.955018 -341.577676)
		(width 0.1651)
		(layer "In2.Cu")
		(net "PE_RX2_DR11_N")
	)
	(segment
		(start 19.107658 -350.089978)
		(end 18.70202 -349.806006)
		(width 0.1651)
		(layer "In2.Cu")
		(net "PE_RX2_DR11_N")
	)
	(segment
		(start 10.789412 -340.531958)
		(end 10.383774 -340.247986)
		(width 0.1651)
		(layer "In2.Cu")
		(net "PE_RX2_DR11_N")
	)
	(segment
		(start 9.670034 -339.748114)
		(end 9.264396 -339.464142)
		(width 0.1651)
		(layer "In2.Cu")
		(net "PE_RX2_DR11_N")
	)
	(segment
		(start 28.857702 -334.340962)
		(end 29.020516 -335.264506)
		(width 0.1651)
		(layer "In2.Cu")
		(net "PE_RX2_DR11_N")
	)
	(segment
		(start 26.423366 -352.483674)
		(end 24.155146 -352.883724)
		(width 0.1651)
		(layer "In2.Cu")
		(net "PE_RX2_DR11_N")
	)
	(segment
		(start 28.448 -333.756)
		(end 28.857702 -334.340962)
		(width 0.1651)
		(layer "In2.Cu")
		(net "PE_RX2_DR11_N")
	)
	(segment
		(start 17.98828 -349.306134)
		(end 17.582642 -349.022162)
		(width 0.1651)
		(layer "In2.Cu")
		(net "PE_RX2_DR11_N")
	)
	(segment
		(start 20.48891 -350.827594)
		(end 20.22729 -350.873822)
		(width 0.1651)
		(layer "In2.Cu")
		(net "PE_RX2_DR11_N")
	)
	(segment
		(start 11.241278 -341.077804)
		(end 10.83564 -340.793832)
		(width 0.1651)
		(layer "In2.Cu")
		(net "PE_RX2_DR11_N")
	)
	(segment
		(start 17.582642 -349.022162)
		(end 12.768834 -342.147398)
		(width 0.1651)
		(layer "In2.Cu")
		(net "PE_RX2_DR11_N")
	)
	(segment
		(start 29.79039 -347.79331)
		(end 29.380942 -350.11614)
		(width 0.1651)
		(layer "In2.Cu")
		(net "PE_RX2_DR11_N")
	)
	(segment
		(start 29.257752 -336.610198)
		(end 28.538424 -340.689692)
		(width 0.1651)
		(layer "In2.Cu")
		(net "PE_RX2_DR11_N")
	)
	(segment
		(start 26.518108 -332.98765)
		(end 27.630628 -333.183738)
		(width 0.1651)
		(layer "In2.Cu")
		(net "PE_RX2_DR11_N")
	)
	(segment
		(start 9.264396 -339.464142)
		(end 9.002522 -339.510116)
		(width 0.1651)
		(layer "In2.Cu")
		(net "PE_RX2_DR11_N")
	)
	(segment
		(start 28.97251 -350.699324)
		(end 26.423366 -352.483674)
		(width 0.1651)
		(layer "In2.Cu")
		(net "PE_RX2_DR11_N")
	)
	(segment
		(start 11.503152 -341.031576)
		(end 11.241278 -341.077804)
		(width 0.1651)
		(layer "In2.Cu")
		(net "PE_RX2_DR11_N")
	)
	(segment
		(start 20.940776 -351.37344)
		(end 20.894802 -351.11182)
		(width 0.1651)
		(layer "In2.Cu")
		(net "PE_RX2_DR11_N")
	)
	(segment
		(start 8.596884 -339.226144)
		(end 7.112 -338.96427)
		(width 0.1651)
		(layer "In2.Cu")
		(net "PE_RX2_DR11_N")
	)
	(segment
		(start 29.380942 -350.11614)
		(end 28.97251 -350.699324)
		(width 0.1651)
		(layer "In2.Cu")
		(net "PE_RX2_DR11_N")
	)
	(segment
		(start 25.273 -333.368904)
		(end 25.654254 -332.98765)
		(width 0.1651)
		(layer "In2.Cu")
		(net "PE_RX2_DR11_N")
	)
	(segment
		(start 28.538424 -340.689692)
		(end 29.79039 -347.79331)
		(width 0.1651)
		(layer "In2.Cu")
		(net "PE_RX2_DR11_N")
	)
	(segment
		(start 20.894802 -351.11182)
		(end 20.48891 -350.827594)
		(width 0.1651)
		(layer "In2.Cu")
		(net "PE_RX2_DR11_N")
	)
	(segment
		(start 19.369532 -350.04375)
		(end 19.107658 -350.089978)
		(width 0.1651)
		(layer "In2.Cu")
		(net "PE_RX2_DR11_N")
	)
	(segment
		(start 22.74189 -352.63455)
		(end 20.940776 -351.37344)
		(width 0.1651)
		(layer "In2.Cu")
		(net "PE_RX2_DR11_N")
	)
	(segment
		(start 19.821398 -350.58985)
		(end 19.77517 -350.327976)
		(width 0.1651)
		(layer "In2.Cu")
		(net "PE_RX2_DR11_N")
	)
	(segment
		(start 25.654254 -332.98765)
		(end 26.518108 -332.98765)
		(width 0.1651)
		(layer "In2.Cu")
		(net "PE_RX2_DR11_N")
	)
	(segment
		(start 29.171646 -336.122518)
		(end 29.257752 -336.610198)
		(width 0.1651)
		(layer "In2.Cu")
		(net "PE_RX2_DR11_N")
	)
	(segment
		(start 27.630628 -333.183738)
		(end 28.448 -333.756)
		(width 0.1651)
		(layer "In2.Cu")
		(net "PE_RX2_DR11_N")
	)
	(segment
		(start 24.155146 -352.883724)
		(end 22.74189 -352.63455)
		(width 0.1651)
		(layer "In2.Cu")
		(net "PE_RX2_DR11_N")
	)
	(segment
		(start 18.250154 -349.26016)
		(end 17.98828 -349.306134)
		(width 0.1651)
		(layer "In2.Cu")
		(net "PE_RX2_DR11_N")
	)
	(segment
		(start 20.22729 -350.873822)
		(end 19.821398 -350.58985)
		(width 0.1651)
		(layer "In2.Cu")
		(net "PE_RX2_DR11_N")
	)
	(segment
		(start 10.383774 -340.247986)
		(end 10.1219 -340.29396)
		(width 0.1651)
		(layer "In2.Cu")
		(net "PE_RX2_DR11_N")
	)
	(segment
		(start 19.77517 -350.327976)
		(end 19.369532 -350.04375)
		(width 0.1651)
		(layer "In2.Cu")
		(net "PE_RX2_DR11_N")
	)
	(segment
		(start 28.953968 -335.969864)
		(end 29.171646 -336.122518)
		(width 0.1651)
		(layer "In2.Cu")
		(net "PE_RX2_DR11_N")
	)
	(segment
		(start 28.868116 -335.482184)
		(end 28.953968 -335.969864)
		(width 0.1651)
		(layer "In2.Cu")
		(net "PE_RX2_DR11_N")
	)
	(segment
		(start 11.90879 -341.315802)
		(end 11.503152 -341.031576)
		(width 0.1651)
		(layer "In2.Cu")
		(net "PE_RX2_DR11_N")
	)
	(segment
		(start 9.002522 -339.510116)
		(end 8.596884 -339.226144)
		(width 0.1651)
		(layer "In2.Cu")
		(net "PE_RX2_DR11_N")
	)
	(segment
		(start 23.876 -436.210202)
		(end 24.12365 -435.962552)
		(width 0.174752)
		(layer "F.Cu")
		(net "PE_RX2_DR10_P")
	)
	(segment
		(start 22.800056 -436.210202)
		(end 23.876 -436.210202)
		(width 0.174752)
		(layer "F.Cu")
		(net "PE_RX2_DR10_P")
	)
	(segment
		(start 24.8666 -435.962552)
		(end 25.273 -436.368952)
		(width 0.174752)
		(layer "F.Cu")
		(net "PE_RX2_DR10_P")
	)
	(segment
		(start 24.12365 -435.962552)
		(end 24.8666 -435.962552)
		(width 0.174752)
		(layer "F.Cu")
		(net "PE_RX2_DR10_P")
	)
	(via
		(at 25.273 -436.368952)
		(size 0.508)
		(drill 0.254)
		(layers "F.Cu" "B.Cu")
		(net "PE_RX2_DR10_P")
	)
	(via
		(at 5.08 -407.135076)
		(size 0.508)
		(drill 0.254)
		(layers "F.Cu" "B.Cu")
		(net "PE_RX2_DR10_P")
	)
	(segment
		(start 1.868932 -407.141934)
		(end 3.657854 -407.141934)
		(width 0.174752)
		(layer "B.Cu")
		(net "PE_RX2_DR10_P")
	)
	(segment
		(start 3.90525 -407.38933)
		(end 4.825746 -407.38933)
		(width 0.174752)
		(layer "B.Cu")
		(net "PE_RX2_DR10_P")
	)
	(segment
		(start 4.825746 -407.38933)
		(end 5.08 -407.135076)
		(width 0.174752)
		(layer "B.Cu")
		(net "PE_RX2_DR10_P")
	)
	(segment
		(start 3.657854 -407.141934)
		(end 3.90525 -407.38933)
		(width 0.174752)
		(layer "B.Cu")
		(net "PE_RX2_DR10_P")
	)
	(segment
		(start 28.0797 -435.71795)
		(end 26.54935 -435.987698)
		(width 0.1651)
		(layer "In2.Cu")
		(net "PE_RX2_DR10_P")
	)
	(segment
		(start 25.654254 -435.987698)
		(end 25.273 -436.368952)
		(width 0.1651)
		(layer "In2.Cu")
		(net "PE_RX2_DR10_P")
	)
	(segment
		(start 44.203112 -413.788606)
		(end 44.391326 -414.856168)
		(width 0.1651)
		(layer "In2.Cu")
		(net "PE_RX2_DR10_P")
	)
	(segment
		(start 36.794948 -429.6156)
		(end 28.0797 -435.71795)
		(width 0.1651)
		(layer "In2.Cu")
		(net "PE_RX2_DR10_P")
	)
	(segment
		(start 41.456356 -410.588206)
		(end 42.49039 -411.31236)
		(width 0.1651)
		(layer "In2.Cu")
		(net "PE_RX2_DR10_P")
	)
	(segment
		(start 43.420538 -420.21506)
		(end 36.944808 -429.46574)
		(width 0.1651)
		(layer "In2.Cu")
		(net "PE_RX2_DR10_P")
	)
	(segment
		(start 15.296388 -405.925528)
		(end 41.248076 -410.501846)
		(width 0.1651)
		(layer "In2.Cu")
		(net "PE_RX2_DR10_P")
	)
	(segment
		(start 42.618152 -411.440122)
		(end 44.116752 -413.580326)
		(width 0.1651)
		(layer "In2.Cu")
		(net "PE_RX2_DR10_P")
	)
	(segment
		(start 26.54935 -435.987698)
		(end 25.654254 -435.987698)
		(width 0.1651)
		(layer "In2.Cu")
		(net "PE_RX2_DR10_P")
	)
	(segment
		(start 5.08 -407.135076)
		(end 5.309108 -407.364184)
		(width 0.1651)
		(layer "In2.Cu")
		(net "PE_RX2_DR10_P")
	)
	(segment
		(start 5.309108 -407.364184)
		(end 7.143242 -407.364184)
		(width 0.1651)
		(layer "In2.Cu")
		(net "PE_RX2_DR10_P")
	)
	(segment
		(start 7.143242 -407.364184)
		(end 15.296388 -405.925528)
		(width 0.1651)
		(layer "In2.Cu")
		(net "PE_RX2_DR10_P")
	)
	(segment
		(start 44.391326 -415.037016)
		(end 43.521376 -419.97122)
		(width 0.1651)
		(layer "In2.Cu")
		(net "PE_RX2_DR10_P")
	)
	(arc
		(start 42.49039 -411.31236)
		(mid 42.559855 -411.370657)
		(end 42.618152 -411.440122)
		(width 0.1651)
		(layer "In2.Cu")
		(net "PE_RX2_DR10_P")
	)
	(arc
		(start 41.248076 -410.501846)
		(mid 41.356937 -410.533634)
		(end 41.456356 -410.588206)
		(width 0.1651)
		(layer "In2.Cu")
		(net "PE_RX2_DR10_P")
	)
	(arc
		(start 36.944808 -429.46574)
		(mid 36.876441 -429.547233)
		(end 36.794948 -429.6156)
		(width 0.1651)
		(layer "In2.Cu")
		(net "PE_RX2_DR10_P")
	)
	(arc
		(start 44.391326 -414.856168)
		(mid 44.399237 -414.946592)
		(end 44.391326 -415.037016)
		(width 0.1651)
		(layer "In2.Cu")
		(net "PE_RX2_DR10_P")
	)
	(arc
		(start 43.521376 -419.97122)
		(mid 43.484332 -420.098674)
		(end 43.420538 -420.21506)
		(width 0.1651)
		(layer "In2.Cu")
		(net "PE_RX2_DR10_P")
	)
	(arc
		(start 44.116752 -413.580326)
		(mid 44.171356 -413.679731)
		(end 44.203112 -413.788606)
		(width 0.1651)
		(layer "In2.Cu")
		(net "PE_RX2_DR10_P")
	)
	(segment
		(start 23.876 -435.410102)
		(end 24.123396 -435.657498)
		(width 0.174752)
		(layer "F.Cu")
		(net "PE_RX2_DR10_N")
	)
	(segment
		(start 24.123396 -435.657498)
		(end 24.866854 -435.657498)
		(width 0.174752)
		(layer "F.Cu")
		(net "PE_RX2_DR10_N")
	)
	(segment
		(start 22.800056 -435.410102)
		(end 23.876 -435.410102)
		(width 0.174752)
		(layer "F.Cu")
		(net "PE_RX2_DR10_N")
	)
	(segment
		(start 24.866854 -435.657498)
		(end 25.273 -435.251352)
		(width 0.174752)
		(layer "F.Cu")
		(net "PE_RX2_DR10_N")
	)
	(via
		(at 25.273 -435.251352)
		(size 0.508)
		(drill 0.254)
		(layers "F.Cu" "B.Cu")
		(net "PE_RX2_DR10_N")
	)
	(via
		(at 5.08 -407.947876)
		(size 0.508)
		(drill 0.254)
		(layers "F.Cu" "B.Cu")
		(net "PE_RX2_DR10_N")
	)
	(segment
		(start 4.826508 -407.694384)
		(end 5.08 -407.947876)
		(width 0.174752)
		(layer "B.Cu")
		(net "PE_RX2_DR10_N")
	)
	(segment
		(start 1.868932 -407.94178)
		(end 3.657854 -407.94178)
		(width 0.174752)
		(layer "B.Cu")
		(net "PE_RX2_DR10_N")
	)
	(segment
		(start 3.90525 -407.694384)
		(end 4.826508 -407.694384)
		(width 0.174752)
		(layer "B.Cu")
		(net "PE_RX2_DR10_N")
	)
	(segment
		(start 3.657854 -407.94178)
		(end 3.90525 -407.694384)
		(width 0.174752)
		(layer "B.Cu")
		(net "PE_RX2_DR10_N")
	)
	(segment
		(start 30.17901 -433.813712)
		(end 29.917136 -433.767738)
		(width 0.1651)
		(layer "In2.Cu")
		(net "PE_RX2_DR10_N")
	)
	(segment
		(start 33.946592 -431.175668)
		(end 33.684718 -431.12944)
		(width 0.1651)
		(layer "In2.Cu")
		(net "PE_RX2_DR10_N")
	)
	(segment
		(start 33.27908 -431.413666)
		(end 33.232852 -431.67554)
		(width 0.1651)
		(layer "In2.Cu")
		(net "PE_RX2_DR10_N")
	)
	(segment
		(start 26.518108 -435.632098)
		(end 25.653746 -435.632098)
		(width 0.1651)
		(layer "In2.Cu")
		(net "PE_RX2_DR10_N")
	)
	(segment
		(start 43.825414 -413.784288)
		(end 43.825414 -413.784542)
		(width 0.1651)
		(layer "In2.Cu")
		(net "PE_RX2_DR10_N")
	)
	(segment
		(start 27.940254 -435.3814)
		(end 26.518108 -435.632098)
		(width 0.1651)
		(layer "In2.Cu")
		(net "PE_RX2_DR10_N")
	)
	(segment
		(start 35.517836 -429.845978)
		(end 35.471608 -430.107852)
		(width 0.1651)
		(layer "In2.Cu")
		(net "PE_RX2_DR10_N")
	)
	(segment
		(start 34.804096 -430.34585)
		(end 34.398458 -430.629822)
		(width 0.1651)
		(layer "In2.Cu")
		(net "PE_RX2_DR10_N")
	)
	(segment
		(start 5.08 -407.947876)
		(end 5.308092 -407.719784)
		(width 0.1651)
		(layer "In2.Cu")
		(net "PE_RX2_DR10_N")
	)
	(segment
		(start 29.46527 -434.313584)
		(end 29.059632 -434.597556)
		(width 0.1651)
		(layer "In2.Cu")
		(net "PE_RX2_DR10_N")
	)
	(segment
		(start 43.852846 -413.850328)
		(end 44.04106 -414.91789)
		(width 0.1651)
		(layer "In2.Cu")
		(net "PE_RX2_DR10_N")
	)
	(segment
		(start 25.653746 -435.632098)
		(end 25.273 -435.251352)
		(width 0.1651)
		(layer "In2.Cu")
		(net "PE_RX2_DR10_N")
	)
	(segment
		(start 31.298388 -433.029868)
		(end 31.011876 -432.979576)
		(width 0.1651)
		(layer "In2.Cu")
		(net "PE_RX2_DR10_N")
	)
	(segment
		(start 33.232852 -431.67554)
		(end 31.298388 -433.029868)
		(width 0.1651)
		(layer "In2.Cu")
		(net "PE_RX2_DR10_N")
	)
	(segment
		(start 37.175186 -428.188374)
		(end 36.89096 -428.594266)
		(width 0.1651)
		(layer "In2.Cu")
		(net "PE_RX2_DR10_N")
	)
	(segment
		(start 28.39212 -434.835554)
		(end 28.345892 -435.097428)
		(width 0.1651)
		(layer "In2.Cu")
		(net "PE_RX2_DR10_N")
	)
	(segment
		(start 30.635194 -433.243228)
		(end 30.584648 -433.52974)
		(width 0.1651)
		(layer "In2.Cu")
		(net "PE_RX2_DR10_N")
	)
	(segment
		(start 30.584648 -433.52974)
		(end 30.17901 -433.813712)
		(width 0.1651)
		(layer "In2.Cu")
		(net "PE_RX2_DR10_N")
	)
	(segment
		(start 36.590986 -429.324008)
		(end 36.185348 -429.60798)
		(width 0.1651)
		(layer "In2.Cu")
		(net "PE_RX2_DR10_N")
	)
	(segment
		(start 31.011876 -432.979576)
		(end 30.635194 -433.243228)
		(width 0.1651)
		(layer "In2.Cu")
		(net "PE_RX2_DR10_N")
	)
	(segment
		(start 29.511498 -434.05171)
		(end 29.46527 -434.313584)
		(width 0.1651)
		(layer "In2.Cu")
		(net "PE_RX2_DR10_N")
	)
	(segment
		(start 44.04106 -414.975294)
		(end 43.17111 -419.909498)
		(width 0.1651)
		(layer "In2.Cu")
		(net "PE_RX2_DR10_N")
	)
	(segment
		(start 37.436806 -428.1424)
		(end 37.175186 -428.188374)
		(width 0.1651)
		(layer "In2.Cu")
		(net "PE_RX2_DR10_N")
	)
	(segment
		(start 41.252394 -410.879544)
		(end 42.286428 -411.603698)
		(width 0.1651)
		(layer "In2.Cu")
		(net "PE_RX2_DR10_N")
	)
	(segment
		(start 29.917136 -433.767738)
		(end 29.511498 -434.05171)
		(width 0.1651)
		(layer "In2.Cu")
		(net "PE_RX2_DR10_N")
	)
	(segment
		(start 34.398458 -430.629822)
		(end 34.35223 -430.891696)
		(width 0.1651)
		(layer "In2.Cu")
		(net "PE_RX2_DR10_N")
	)
	(segment
		(start 36.89096 -428.594266)
		(end 36.937188 -428.85614)
		(width 0.1651)
		(layer "In2.Cu")
		(net "PE_RX2_DR10_N")
	)
	(segment
		(start 33.684718 -431.12944)
		(end 33.27908 -431.413666)
		(width 0.1651)
		(layer "In2.Cu")
		(net "PE_RX2_DR10_N")
	)
	(segment
		(start 42.326814 -411.644084)
		(end 43.825414 -413.784288)
		(width 0.1651)
		(layer "In2.Cu")
		(net "PE_RX2_DR10_N")
	)
	(segment
		(start 28.797758 -434.551328)
		(end 28.39212 -434.835554)
		(width 0.1651)
		(layer "In2.Cu")
		(net "PE_RX2_DR10_N")
	)
	(segment
		(start 36.185348 -429.60798)
		(end 35.923474 -429.562006)
		(width 0.1651)
		(layer "In2.Cu")
		(net "PE_RX2_DR10_N")
	)
	(segment
		(start 35.471608 -430.107852)
		(end 35.06597 -430.391824)
		(width 0.1651)
		(layer "In2.Cu")
		(net "PE_RX2_DR10_N")
	)
	(segment
		(start 7.174484 -407.719784)
		(end 15.296388 -406.286716)
		(width 0.1651)
		(layer "In2.Cu")
		(net "PE_RX2_DR10_N")
	)
	(segment
		(start 43.1292 -420.011098)
		(end 37.436806 -428.1424)
		(width 0.1651)
		(layer "In2.Cu")
		(net "PE_RX2_DR10_N")
	)
	(segment
		(start 29.059632 -434.597556)
		(end 28.797758 -434.551328)
		(width 0.1651)
		(layer "In2.Cu")
		(net "PE_RX2_DR10_N")
	)
	(segment
		(start 36.937188 -428.85614)
		(end 36.653216 -429.261778)
		(width 0.1651)
		(layer "In2.Cu")
		(net "PE_RX2_DR10_N")
	)
	(segment
		(start 15.296388 -406.286716)
		(end 41.186354 -410.852112)
		(width 0.1651)
		(layer "In2.Cu")
		(net "PE_RX2_DR10_N")
	)
	(segment
		(start 5.308092 -407.719784)
		(end 7.174484 -407.719784)
		(width 0.1651)
		(layer "In2.Cu")
		(net "PE_RX2_DR10_N")
	)
	(segment
		(start 35.06597 -430.391824)
		(end 34.804096 -430.34585)
		(width 0.1651)
		(layer "In2.Cu")
		(net "PE_RX2_DR10_N")
	)
	(segment
		(start 28.345892 -435.097428)
		(end 27.940254 -435.3814)
		(width 0.1651)
		(layer "In2.Cu")
		(net "PE_RX2_DR10_N")
	)
	(segment
		(start 35.923474 -429.562006)
		(end 35.517836 -429.845978)
		(width 0.1651)
		(layer "In2.Cu")
		(net "PE_RX2_DR10_N")
	)
	(segment
		(start 34.35223 -430.891696)
		(end 33.946592 -431.175668)
		(width 0.1651)
		(layer "In2.Cu")
		(net "PE_RX2_DR10_N")
	)
	(arc
		(start 43.17111 -419.909498)
		(mid 43.15573 -419.962599)
		(end 43.1292 -420.011098)
		(width 0.1651)
		(layer "In2.Cu")
		(net "PE_RX2_DR10_N")
	)
	(arc
		(start 41.186354 -410.852112)
		(mid 41.220862 -410.862237)
		(end 41.252394 -410.879544)
		(width 0.1651)
		(layer "In2.Cu")
		(net "PE_RX2_DR10_N")
	)
	(arc
		(start 36.653216 -429.261778)
		(mid 36.624816 -429.295608)
		(end 36.590986 -429.324008)
		(width 0.1651)
		(layer "In2.Cu")
		(net "PE_RX2_DR10_N")
	)
	(arc
		(start 43.825414 -413.784542)
		(mid 43.842728 -413.815936)
		(end 43.852846 -413.850328)
		(width 0.1651)
		(layer "In2.Cu")
		(net "PE_RX2_DR10_N")
	)
	(arc
		(start 44.04106 -414.91789)
		(mid 44.043574 -414.946592)
		(end 44.04106 -414.975294)
		(width 0.1651)
		(layer "In2.Cu")
		(net "PE_RX2_DR10_N")
	)
	(arc
		(start 42.286428 -411.603698)
		(mid 42.308381 -411.622131)
		(end 42.326814 -411.644084)
		(width 0.1651)
		(layer "In2.Cu")
		(net "PE_RX2_DR10_N")
	)
	(segment
		(start 222.891604 -379.34265)
		(end 222.13316 -379.34265)
		(width 0.174752)
		(layer "F.Cu")
		(net "PE_RX2_DR1_P")
	)
	(segment
		(start 224.199958 -379.590046)
		(end 223.139 -379.590046)
		(width 0.174752)
		(layer "F.Cu")
		(net "PE_RX2_DR1_P")
	)
	(segment
		(start 222.13316 -379.34265)
		(end 221.727014 -379.748796)
		(width 0.174752)
		(layer "F.Cu")
		(net "PE_RX2_DR1_P")
	)
	(segment
		(start 223.139 -379.590046)
		(end 222.891604 -379.34265)
		(width 0.174752)
		(layer "F.Cu")
		(net "PE_RX2_DR1_P")
	)
	(via
		(at 221.727014 -379.748796)
		(size 0.508)
		(drill 0.254)
		(layers "F.Cu" "B.Cu")
		(net "PE_RX2_DR1_P")
	)
	(via
		(at 5.08 -392.748008)
		(size 0.508)
		(drill 0.254)
		(layers "F.Cu" "B.Cu")
		(net "PE_RX2_DR1_P")
	)
	(segment
		(start 4.826254 -392.494262)
		(end 5.08 -392.748008)
		(width 0.174752)
		(layer "B.Cu")
		(net "PE_RX2_DR1_P")
	)
	(segment
		(start 3.905504 -392.494262)
		(end 4.826254 -392.494262)
		(width 0.174752)
		(layer "B.Cu")
		(net "PE_RX2_DR1_P")
	)
	(segment
		(start 1.868932 -392.741912)
		(end 3.657854 -392.741912)
		(width 0.174752)
		(layer "B.Cu")
		(net "PE_RX2_DR1_P")
	)
	(segment
		(start 3.657854 -392.741912)
		(end 3.905504 -392.494262)
		(width 0.174752)
		(layer "B.Cu")
		(net "PE_RX2_DR1_P")
	)
	(segment
		(start 5.308346 -392.519662)
		(end 5.08 -392.748008)
		(width 0.1651)
		(layer "In2.Cu")
		(net "PE_RX2_DR1_P")
	)
	(segment
		(start 7.776718 -392.642344)
		(end 7.080758 -392.519662)
		(width 0.1651)
		(layer "In2.Cu")
		(net "PE_RX2_DR1_P")
	)
	(segment
		(start 45.032422 -407.216864)
		(end 23.056342 -403.341332)
		(width 0.1651)
		(layer "In2.Cu")
		(net "PE_RX2_DR1_P")
	)
	(segment
		(start 220.419676 -379.36805)
		(end 211.779612 -377.850908)
		(width 0.1651)
		(layer "In2.Cu")
		(net "PE_RX2_DR1_P")
	)
	(segment
		(start 211.779612 -377.850908)
		(end 45.244004 -407.216864)
		(width 0.1651)
		(layer "In2.Cu")
		(net "PE_RX2_DR1_P")
	)
	(segment
		(start 221.727014 -379.748796)
		(end 221.346268 -379.36805)
		(width 0.1651)
		(layer "In2.Cu")
		(net "PE_RX2_DR1_P")
	)
	(segment
		(start 221.346268 -379.36805)
		(end 220.419676 -379.36805)
		(width 0.1651)
		(layer "In2.Cu")
		(net "PE_RX2_DR1_P")
	)
	(segment
		(start 7.080758 -392.519662)
		(end 5.308346 -392.519662)
		(width 0.1651)
		(layer "In2.Cu")
		(net "PE_RX2_DR1_P")
	)
	(segment
		(start 23.056342 -403.341332)
		(end 7.776718 -392.642344)
		(width 0.1651)
		(layer "In2.Cu")
		(net "PE_RX2_DR1_P")
	)
	(arc
		(start 45.244004 -407.216864)
		(mid 45.138215 -407.226094)
		(end 45.032422 -407.216864)
		(width 0.1651)
		(layer "In2.Cu")
		(net "PE_RX2_DR1_P")
	)
	(segment
		(start 222.89135 -379.037596)
		(end 222.133414 -379.037596)
		(width 0.174752)
		(layer "F.Cu")
		(net "PE_RX2_DR1_N")
	)
	(segment
		(start 222.133414 -379.037596)
		(end 221.727014 -378.631196)
		(width 0.174752)
		(layer "F.Cu")
		(net "PE_RX2_DR1_N")
	)
	(segment
		(start 223.139 -378.789946)
		(end 222.89135 -379.037596)
		(width 0.174752)
		(layer "F.Cu")
		(net "PE_RX2_DR1_N")
	)
	(segment
		(start 224.199958 -378.789946)
		(end 223.139 -378.789946)
		(width 0.174752)
		(layer "F.Cu")
		(net "PE_RX2_DR1_N")
	)
	(via
		(at 221.727014 -378.631196)
		(size 0.508)
		(drill 0.254)
		(layers "F.Cu" "B.Cu")
		(net "PE_RX2_DR1_N")
	)
	(via
		(at 5.08 -391.935208)
		(size 0.508)
		(drill 0.254)
		(layers "F.Cu" "B.Cu")
		(net "PE_RX2_DR1_N")
	)
	(segment
		(start 3.658108 -391.941812)
		(end 3.905504 -392.189208)
		(width 0.174752)
		(layer "B.Cu")
		(net "PE_RX2_DR1_N")
	)
	(segment
		(start 1.868932 -391.941812)
		(end 3.658108 -391.941812)
		(width 0.174752)
		(layer "B.Cu")
		(net "PE_RX2_DR1_N")
	)
	(segment
		(start 4.826 -392.189208)
		(end 5.08 -391.935208)
		(width 0.174752)
		(layer "B.Cu")
		(net "PE_RX2_DR1_N")
	)
	(segment
		(start 3.905504 -392.189208)
		(end 4.826 -392.189208)
		(width 0.174752)
		(layer "B.Cu")
		(net "PE_RX2_DR1_N")
	)
	(segment
		(start 23.195788 -403.004782)
		(end 7.916164 -392.305794)
		(width 0.1651)
		(layer "In2.Cu")
		(net "PE_RX2_DR1_N")
	)
	(segment
		(start 7.916164 -392.305794)
		(end 7.112 -392.164062)
		(width 0.1651)
		(layer "In2.Cu")
		(net "PE_RX2_DR1_N")
	)
	(segment
		(start 220.450664 -379.01245)
		(end 211.779612 -377.48972)
		(width 0.1651)
		(layer "In2.Cu")
		(net "PE_RX2_DR1_N")
	)
	(segment
		(start 7.112 -392.164062)
		(end 5.308854 -392.164062)
		(width 0.1651)
		(layer "In2.Cu")
		(net "PE_RX2_DR1_N")
	)
	(segment
		(start 221.727014 -378.631196)
		(end 221.34576 -379.01245)
		(width 0.1651)
		(layer "In2.Cu")
		(net "PE_RX2_DR1_N")
	)
	(segment
		(start 211.779612 -377.48972)
		(end 45.182282 -406.866598)
		(width 0.1651)
		(layer "In2.Cu")
		(net "PE_RX2_DR1_N")
	)
	(segment
		(start 5.308854 -392.164062)
		(end 5.08 -391.935208)
		(width 0.1651)
		(layer "In2.Cu")
		(net "PE_RX2_DR1_N")
	)
	(segment
		(start 45.182282 -406.866598)
		(end 45.182536 -406.866598)
		(width 0.1651)
		(layer "In2.Cu")
		(net "PE_RX2_DR1_N")
	)
	(segment
		(start 221.34576 -379.01245)
		(end 220.450664 -379.01245)
		(width 0.1651)
		(layer "In2.Cu")
		(net "PE_RX2_DR1_N")
	)
	(segment
		(start 45.094144 -406.866598)
		(end 23.195788 -403.004782)
		(width 0.1651)
		(layer "In2.Cu")
		(net "PE_RX2_DR1_N")
	)
	(arc
		(start 45.182536 -406.866598)
		(mid 45.13834 -406.870472)
		(end 45.094144 -406.866598)
		(width 0.1651)
		(layer "In2.Cu")
		(net "PE_RX2_DR1_N")
	)
	(segment
		(start 222.13316 -482.342698)
		(end 221.727014 -482.748844)
		(width 0.174752)
		(layer "F.Cu")
		(net "PE_RX2_DR0_P")
	)
	(segment
		(start 223.139 -482.590094)
		(end 222.891604 -482.342698)
		(width 0.174752)
		(layer "F.Cu")
		(net "PE_RX2_DR0_P")
	)
	(segment
		(start 224.199958 -482.590094)
		(end 223.139 -482.590094)
		(width 0.174752)
		(layer "F.Cu")
		(net "PE_RX2_DR0_P")
	)
	(segment
		(start 222.891604 -482.342698)
		(end 222.13316 -482.342698)
		(width 0.174752)
		(layer "F.Cu")
		(net "PE_RX2_DR0_P")
	)
	(via
		(at 5.08 -423.948098)
		(size 0.508)
		(drill 0.254)
		(layers "F.Cu" "B.Cu")
		(net "PE_RX2_DR0_P")
	)
	(via
		(at 221.727014 -482.748844)
		(size 0.508)
		(drill 0.254)
		(layers "F.Cu" "B.Cu")
		(net "PE_RX2_DR0_P")
	)
	(segment
		(start 4.826508 -423.694606)
		(end 5.08 -423.948098)
		(width 0.174752)
		(layer "B.Cu")
		(net "PE_RX2_DR0_P")
	)
	(segment
		(start 1.868932 -423.942002)
		(end 3.658108 -423.942002)
		(width 0.174752)
		(layer "B.Cu")
		(net "PE_RX2_DR0_P")
	)
	(segment
		(start 3.905504 -423.694606)
		(end 4.826508 -423.694606)
		(width 0.174752)
		(layer "B.Cu")
		(net "PE_RX2_DR0_P")
	)
	(segment
		(start 3.658108 -423.942002)
		(end 3.905504 -423.694606)
		(width 0.174752)
		(layer "B.Cu")
		(net "PE_RX2_DR0_P")
	)
	(segment
		(start 220.49105 -482.368098)
		(end 218.155266 -481.956364)
		(width 0.1651)
		(layer "In2.Cu")
		(net "PE_RX2_DR0_P")
	)
	(segment
		(start 21.161756 -455.720958)
		(end 21.09978 -455.69505)
		(width 0.1651)
		(layer "In2.Cu")
		(net "PE_RX2_DR0_P")
	)
	(segment
		(start 41.863518 -442.383672)
		(end 39.786814 -442.74994)
		(width 0.1651)
		(layer "In2.Cu")
		(net "PE_RX2_DR0_P")
	)
	(segment
		(start 21.09978 -455.69505)
		(end 21.037296 -455.669396)
		(width 0.1651)
		(layer "In2.Cu")
		(net "PE_RX2_DR0_P")
	)
	(segment
		(start 19.111468 -453.56272)
		(end 17.110964 -452.16191)
		(width 0.1651)
		(layer "In2.Cu")
		(net "PE_RX2_DR0_P")
	)
	(segment
		(start 9.555734 -424.556428)
		(end 9.186164 -424.297348)
		(width 0.1651)
		(layer "In2.Cu")
		(net "PE_RX2_DR0_P")
	)
	(segment
		(start 201.958448 -470.615518)
		(end 41.863518 -442.383672)
		(width 0.1651)
		(layer "In2.Cu")
		(net "PE_RX2_DR0_P")
	)
	(segment
		(start 30.199076 -453.352408)
		(end 27.3812 -455.325226)
		(width 0.1651)
		(layer "In2.Cu")
		(net "PE_RX2_DR0_P")
	)
	(segment
		(start 15.244826 -449.475352)
		(end 11.287252 -427.038516)
		(width 0.1651)
		(layer "In2.Cu")
		(net "PE_RX2_DR0_P")
	)
	(segment
		(start 35.623754 -445.710818)
		(end 30.442408 -453.109076)
		(width 0.1651)
		(layer "In2.Cu")
		(net "PE_RX2_DR0_P")
	)
	(segment
		(start 9.186164 -424.297348)
		(end 8.792972 -424.022012)
		(width 0.1651)
		(layer "In2.Cu")
		(net "PE_RX2_DR0_P")
	)
	(segment
		(start 20.84832 -455.56551)
		(end 20.370546 -455.230738)
		(width 0.1651)
		(layer "In2.Cu")
		(net "PE_RX2_DR0_P")
	)
	(segment
		(start 20.127976 -454.98766)
		(end 19.173698 -453.62495)
		(width 0.1651)
		(layer "In2.Cu")
		(net "PE_RX2_DR0_P")
	)
	(segment
		(start 16.899636 -451.95109)
		(end 15.357856 -449.748656)
		(width 0.1651)
		(layer "In2.Cu")
		(net "PE_RX2_DR0_P")
	)
	(segment
		(start 7.080758 -423.720006)
		(end 5.308092 -423.720006)
		(width 0.1651)
		(layer "In2.Cu")
		(net "PE_RX2_DR0_P")
	)
	(segment
		(start 23.167848 -456.10145)
		(end 21.368512 -455.781664)
		(width 0.1651)
		(layer "In2.Cu")
		(net "PE_RX2_DR0_P")
	)
	(segment
		(start 26.98496 -455.48931)
		(end 23.513542 -456.10145)
		(width 0.1651)
		(layer "In2.Cu")
		(net "PE_RX2_DR0_P")
	)
	(segment
		(start 11.25982 -426.972476)
		(end 9.596374 -424.597068)
		(width 0.1651)
		(layer "In2.Cu")
		(net "PE_RX2_DR0_P")
	)
	(segment
		(start 8.792972 -424.022012)
		(end 7.080758 -423.720006)
		(width 0.1651)
		(layer "In2.Cu")
		(net "PE_RX2_DR0_P")
	)
	(segment
		(start 221.727014 -482.748844)
		(end 221.346268 -482.368098)
		(width 0.1651)
		(layer "In2.Cu")
		(net "PE_RX2_DR0_P")
	)
	(segment
		(start 221.346268 -482.368098)
		(end 220.49105 -482.368098)
		(width 0.1651)
		(layer "In2.Cu")
		(net "PE_RX2_DR0_P")
	)
	(segment
		(start 5.308092 -423.720006)
		(end 5.08 -423.948098)
		(width 0.1651)
		(layer "In2.Cu")
		(net "PE_RX2_DR0_P")
	)
	(segment
		(start 218.155266 -481.956364)
		(end 201.958448 -470.615518)
		(width 0.1651)
		(layer "In2.Cu")
		(net "PE_RX2_DR0_P")
	)
	(segment
		(start 39.786814 -442.74994)
		(end 35.77971 -445.554862)
		(width 0.1651)
		(layer "In2.Cu")
		(net "PE_RX2_DR0_P")
	)
	(arc
		(start 23.513542 -456.10145)
		(mid 23.340697 -456.116621)
		(end 23.167848 -456.10145)
		(width 0.1651)
		(layer "In2.Cu")
		(net "PE_RX2_DR0_P")
	)
	(arc
		(start 16.996664 -452.066152)
		(mid 16.94563 -452.010746)
		(end 16.899636 -451.95109)
		(width 0.1651)
		(layer "In2.Cu")
		(net "PE_RX2_DR0_P")
	)
	(arc
		(start 19.173698 -453.62495)
		(mid 19.145298 -453.59112)
		(end 19.111468 -453.56272)
		(width 0.1651)
		(layer "In2.Cu")
		(net "PE_RX2_DR0_P")
	)
	(arc
		(start 30.442408 -453.109076)
		(mid 30.331388 -453.241388)
		(end 30.199076 -453.352408)
		(width 0.1651)
		(layer "In2.Cu")
		(net "PE_RX2_DR0_P")
	)
	(arc
		(start 21.037296 -455.669396)
		(mid 20.939977 -455.622604)
		(end 20.84832 -455.56551)
		(width 0.1651)
		(layer "In2.Cu")
		(net "PE_RX2_DR0_P")
	)
	(arc
		(start 21.368512 -455.781664)
		(mid 21.263475 -455.756958)
		(end 21.161756 -455.720958)
		(width 0.1651)
		(layer "In2.Cu")
		(net "PE_RX2_DR0_P")
	)
	(arc
		(start 27.3812 -455.325226)
		(mid 27.192068 -455.428977)
		(end 26.98496 -455.48931)
		(width 0.1651)
		(layer "In2.Cu")
		(net "PE_RX2_DR0_P")
	)
	(arc
		(start 20.370546 -455.230738)
		(mid 20.238657 -455.119782)
		(end 20.127976 -454.98766)
		(width 0.1651)
		(layer "In2.Cu")
		(net "PE_RX2_DR0_P")
	)
	(arc
		(start 15.357856 -449.748656)
		(mid 15.318637 -449.685571)
		(end 15.286482 -449.618608)
		(width 0.1651)
		(layer "In2.Cu")
		(net "PE_RX2_DR0_P")
	)
	(arc
		(start 15.286482 -449.618608)
		(mid 15.261704 -449.548128)
		(end 15.244826 -449.475352)
		(width 0.1651)
		(layer "In2.Cu")
		(net "PE_RX2_DR0_P")
	)
	(arc
		(start 11.287252 -427.038516)
		(mid 11.277174 -427.003982)
		(end 11.25982 -426.972476)
		(width 0.1651)
		(layer "In2.Cu")
		(net "PE_RX2_DR0_P")
	)
	(arc
		(start 9.596374 -424.597068)
		(mid 9.577834 -424.574968)
		(end 9.555734 -424.556428)
		(width 0.1651)
		(layer "In2.Cu")
		(net "PE_RX2_DR0_P")
	)
	(arc
		(start 35.77971 -445.554862)
		(mid 35.694909 -445.626017)
		(end 35.623754 -445.710818)
		(width 0.1651)
		(layer "In2.Cu")
		(net "PE_RX2_DR0_P")
	)
	(arc
		(start 17.110964 -452.16191)
		(mid 17.051744 -452.116501)
		(end 16.996664 -452.066152)
		(width 0.1651)
		(layer "In2.Cu")
		(net "PE_RX2_DR0_P")
	)
	(segment
		(start 222.133414 -482.037644)
		(end 221.727014 -481.631244)
		(width 0.174752)
		(layer "F.Cu")
		(net "PE_RX2_DR0_N")
	)
	(segment
		(start 222.89135 -482.037644)
		(end 222.133414 -482.037644)
		(width 0.174752)
		(layer "F.Cu")
		(net "PE_RX2_DR0_N")
	)
	(segment
		(start 224.199958 -481.789994)
		(end 223.139 -481.789994)
		(width 0.174752)
		(layer "F.Cu")
		(net "PE_RX2_DR0_N")
	)
	(segment
		(start 223.139 -481.789994)
		(end 222.89135 -482.037644)
		(width 0.174752)
		(layer "F.Cu")
		(net "PE_RX2_DR0_N")
	)
	(via
		(at 221.727014 -481.631244)
		(size 0.508)
		(drill 0.254)
		(layers "F.Cu" "B.Cu")
		(net "PE_RX2_DR0_N")
	)
	(via
		(at 5.08 -423.135298)
		(size 0.508)
		(drill 0.254)
		(layers "F.Cu" "B.Cu")
		(net "PE_RX2_DR0_N")
	)
	(segment
		(start 1.868932 -423.141902)
		(end 3.657854 -423.141902)
		(width 0.174752)
		(layer "B.Cu")
		(net "PE_RX2_DR0_N")
	)
	(segment
		(start 3.905504 -423.389552)
		(end 4.825746 -423.389552)
		(width 0.174752)
		(layer "B.Cu")
		(net "PE_RX2_DR0_N")
	)
	(segment
		(start 3.657854 -423.141902)
		(end 3.905504 -423.389552)
		(width 0.174752)
		(layer "B.Cu")
		(net "PE_RX2_DR0_N")
	)
	(segment
		(start 4.825746 -423.389552)
		(end 5.08 -423.135298)
		(width 0.174752)
		(layer "B.Cu")
		(net "PE_RX2_DR0_N")
	)
	(segment
		(start 35.332416 -445.506856)
		(end 30.15107 -452.905114)
		(width 0.1651)
		(layer "In2.Cu")
		(net "PE_RX2_DR0_N")
	)
	(segment
		(start 26.923238 -455.139044)
		(end 23.451566 -455.751184)
		(width 0.1651)
		(layer "In2.Cu")
		(net "PE_RX2_DR0_N")
	)
	(segment
		(start 17.190974 -451.746874)
		(end 15.649194 -449.54444)
		(width 0.1651)
		(layer "In2.Cu")
		(net "PE_RX2_DR0_N")
	)
	(segment
		(start 9.835134 -424.317668)
		(end 8.932418 -423.685462)
		(width 0.1651)
		(layer "In2.Cu")
		(net "PE_RX2_DR0_N")
	)
	(segment
		(start 21.298662 -455.392536)
		(end 21.173694 -455.34072)
		(width 0.1651)
		(layer "In2.Cu")
		(net "PE_RX2_DR0_N")
	)
	(segment
		(start 21.052536 -455.274172)
		(end 20.574762 -454.9394)
		(width 0.1651)
		(layer "In2.Cu")
		(net "PE_RX2_DR0_N")
	)
	(segment
		(start 219.408248 -481.815902)
		(end 218.294712 -481.619814)
		(width 0.1651)
		(layer "In2.Cu")
		(net "PE_RX2_DR0_N")
	)
	(segment
		(start 5.309108 -423.364406)
		(end 5.08 -423.135298)
		(width 0.1651)
		(layer "In2.Cu")
		(net "PE_RX2_DR0_N")
	)
	(segment
		(start 15.595092 -449.413884)
		(end 11.617452 -426.863002)
		(width 0.1651)
		(layer "In2.Cu")
		(net "PE_RX2_DR0_N")
	)
	(segment
		(start 41.863518 -442.022484)
		(end 39.647368 -442.41339)
		(width 0.1651)
		(layer "In2.Cu")
		(net "PE_RX2_DR0_N")
	)
	(segment
		(start 218.294712 -481.619814)
		(end 202.097894 -470.278968)
		(width 0.1651)
		(layer "In2.Cu")
		(net "PE_RX2_DR0_N")
	)
	(segment
		(start 29.995114 -453.06107)
		(end 27.177238 -455.033888)
		(width 0.1651)
		(layer "In2.Cu")
		(net "PE_RX2_DR0_N")
	)
	(segment
		(start 20.419314 -454.783698)
		(end 19.465036 -453.420988)
		(width 0.1651)
		(layer "In2.Cu")
		(net "PE_RX2_DR0_N")
	)
	(segment
		(start 221.727014 -481.631244)
		(end 221.34576 -482.012498)
		(width 0.1651)
		(layer "In2.Cu")
		(net "PE_RX2_DR0_N")
	)
	(segment
		(start 7.112 -423.364406)
		(end 5.309108 -423.364406)
		(width 0.1651)
		(layer "In2.Cu")
		(net "PE_RX2_DR0_N")
	)
	(segment
		(start 8.932418 -423.685462)
		(end 7.112 -423.364406)
		(width 0.1651)
		(layer "In2.Cu")
		(net "PE_RX2_DR0_N")
	)
	(segment
		(start 11.617452 -426.863002)
		(end 9.835134 -424.317668)
		(width 0.1651)
		(layer "In2.Cu")
		(net "PE_RX2_DR0_N")
	)
	(segment
		(start 202.097894 -470.278968)
		(end 41.863518 -442.022484)
		(width 0.1651)
		(layer "In2.Cu")
		(net "PE_RX2_DR0_N")
	)
	(segment
		(start 19.31543 -453.271382)
		(end 17.314926 -451.870572)
		(width 0.1651)
		(layer "In2.Cu")
		(net "PE_RX2_DR0_N")
	)
	(segment
		(start 39.647368 -442.41339)
		(end 35.575748 -445.263524)
		(width 0.1651)
		(layer "In2.Cu")
		(net "PE_RX2_DR0_N")
	)
	(segment
		(start 23.230078 -455.751184)
		(end 21.430996 -455.431398)
		(width 0.1651)
		(layer "In2.Cu")
		(net "PE_RX2_DR0_N")
	)
	(segment
		(start 220.522292 -482.012244)
		(end 219.408248 -481.815902)
		(width 0.1651)
		(layer "In2.Cu")
		(net "PE_RX2_DR0_N")
	)
	(segment
		(start 220.522292 -482.012498)
		(end 220.522292 -482.012244)
		(width 0.1651)
		(layer "In2.Cu")
		(net "PE_RX2_DR0_N")
	)
	(segment
		(start 221.34576 -482.012498)
		(end 220.522292 -482.012498)
		(width 0.1651)
		(layer "In2.Cu")
		(net "PE_RX2_DR0_N")
	)
	(arc
		(start 15.614904 -449.48221)
		(mid 15.60311 -449.448594)
		(end 15.595092 -449.413884)
		(width 0.1651)
		(layer "In2.Cu")
		(net "PE_RX2_DR0_N")
	)
	(arc
		(start 17.247616 -451.814184)
		(mid 17.217824 -451.781767)
		(end 17.190974 -451.746874)
		(width 0.1651)
		(layer "In2.Cu")
		(net "PE_RX2_DR0_N")
	)
	(arc
		(start 27.177238 -455.033888)
		(mid 27.056003 -455.100397)
		(end 26.923238 -455.139044)
		(width 0.1651)
		(layer "In2.Cu")
		(net "PE_RX2_DR0_N")
	)
	(arc
		(start 19.465036 -453.420988)
		(mid 19.396772 -453.339646)
		(end 19.31543 -453.271382)
		(width 0.1651)
		(layer "In2.Cu")
		(net "PE_RX2_DR0_N")
	)
	(arc
		(start 15.649194 -449.54444)
		(mid 15.630362 -449.514255)
		(end 15.614904 -449.48221)
		(width 0.1651)
		(layer "In2.Cu")
		(net "PE_RX2_DR0_N")
	)
	(arc
		(start 21.173694 -455.34072)
		(mid 21.111301 -455.310749)
		(end 21.052536 -455.274172)
		(width 0.1651)
		(layer "In2.Cu")
		(net "PE_RX2_DR0_N")
	)
	(arc
		(start 20.574762 -454.9394)
		(mid 20.49026 -454.868319)
		(end 20.419314 -454.783698)
		(width 0.1651)
		(layer "In2.Cu")
		(net "PE_RX2_DR0_N")
	)
	(arc
		(start 21.430996 -455.431398)
		(mid 21.363773 -455.415564)
		(end 21.298662 -455.392536)
		(width 0.1651)
		(layer "In2.Cu")
		(net "PE_RX2_DR0_N")
	)
	(arc
		(start 17.314926 -451.870572)
		(mid 17.280058 -451.843827)
		(end 17.247616 -451.814184)
		(width 0.1651)
		(layer "In2.Cu")
		(net "PE_RX2_DR0_N")
	)
	(arc
		(start 30.15107 -452.905114)
		(mid 30.079915 -452.989915)
		(end 29.995114 -453.06107)
		(width 0.1651)
		(layer "In2.Cu")
		(net "PE_RX2_DR0_N")
	)
	(arc
		(start 35.575748 -445.263524)
		(mid 35.443436 -445.374544)
		(end 35.332416 -445.506856)
		(width 0.1651)
		(layer "In2.Cu")
		(net "PE_RX2_DR0_N")
	)
	(arc
		(start 23.451566 -455.751184)
		(mid 23.340822 -455.760914)
		(end 23.230078 -455.751184)
		(width 0.1651)
		(layer "In2.Cu")
		(net "PE_RX2_DR0_N")
	)
	(segment
		(start 39.200074 -57.789826)
		(end 38.093396 -57.789826)
		(width 0.174752)
		(layer "F.Cu")
		(net "PE_RX1_DR9_P")
	)
	(segment
		(start 37.846 -57.54243)
		(end 37.13353 -57.54243)
		(width 0.174752)
		(layer "F.Cu")
		(net "PE_RX1_DR9_P")
	)
	(segment
		(start 38.093396 -57.789826)
		(end 37.846 -57.54243)
		(width 0.174752)
		(layer "F.Cu")
		(net "PE_RX1_DR9_P")
	)
	(segment
		(start 37.13353 -57.54243)
		(end 36.72713 -57.94883)
		(width 0.174752)
		(layer "F.Cu")
		(net "PE_RX1_DR9_P")
	)
	(via
		(at 36.72713 -57.94883)
		(size 0.508)
		(drill 0.254)
		(layers "F.Cu" "B.Cu")
		(net "PE_RX1_DR9_P")
	)
	(via
		(at 5.08 -180.748178)
		(size 0.508)
		(drill 0.254)
		(layers "F.Cu" "B.Cu")
		(net "PE_RX1_DR9_P")
	)
	(segment
		(start 1.868932 -180.742082)
		(end 3.657854 -180.742082)
		(width 0.174752)
		(layer "B.Cu")
		(net "PE_RX1_DR9_P")
	)
	(segment
		(start 3.657854 -180.742082)
		(end 3.905504 -180.494432)
		(width 0.174752)
		(layer "B.Cu")
		(net "PE_RX1_DR9_P")
	)
	(segment
		(start 4.826254 -180.494432)
		(end 5.08 -180.748178)
		(width 0.174752)
		(layer "B.Cu")
		(net "PE_RX1_DR9_P")
	)
	(segment
		(start 3.905504 -180.494432)
		(end 4.826254 -180.494432)
		(width 0.174752)
		(layer "B.Cu")
		(net "PE_RX1_DR9_P")
	)
	(segment
		(start 26.967688 -170.771312)
		(end 25.015952 -173.559216)
		(width 0.1651)
		(layer "In2.Cu")
		(net "PE_RX1_DR9_P")
	)
	(segment
		(start 19.76755 -84.594446)
		(end 18.953734 -89.209626)
		(width 0.1651)
		(layer "In2.Cu")
		(net "PE_RX1_DR9_P")
	)
	(segment
		(start 5.308346 -180.519832)
		(end 5.08 -180.748178)
		(width 0.1651)
		(layer "In2.Cu")
		(net "PE_RX1_DR9_P")
	)
	(segment
		(start 19.831558 -94.186248)
		(end 21.727414 -96.893126)
		(width 0.1651)
		(layer "In2.Cu")
		(net "PE_RX1_DR9_P")
	)
	(segment
		(start 39.582598 -115.033044)
		(end 34.177986 -145.684494)
		(width 0.1651)
		(layer "In2.Cu")
		(net "PE_RX1_DR9_P")
	)
	(segment
		(start 34.342578 -57.744614)
		(end 33.323784 -58.457846)
		(width 0.1651)
		(layer "In2.Cu")
		(net "PE_RX1_DR9_P")
	)
	(segment
		(start 30.372558 -69.44868)
		(end 19.76755 -84.594446)
		(width 0.1651)
		(layer "In2.Cu")
		(net "PE_RX1_DR9_P")
	)
	(segment
		(start 36.72713 -57.94883)
		(end 36.34613 -57.56783)
		(width 0.1651)
		(layer "In2.Cu")
		(net "PE_RX1_DR9_P")
	)
	(segment
		(start 25.015952 -173.559216)
		(end 17.744694 -178.6509)
		(width 0.1651)
		(layer "In2.Cu")
		(net "PE_RX1_DR9_P")
	)
	(segment
		(start 18.953734 -89.209626)
		(end 19.831558 -94.186248)
		(width 0.1651)
		(layer "In2.Cu")
		(net "PE_RX1_DR9_P")
	)
	(segment
		(start 42.396664 -103.960676)
		(end 42.786554 -106.172254)
		(width 0.1651)
		(layer "In2.Cu")
		(net "PE_RX1_DR9_P")
	)
	(segment
		(start 41.869106 -103.207312)
		(end 42.396664 -103.960676)
		(width 0.1651)
		(layer "In2.Cu")
		(net "PE_RX1_DR9_P")
	)
	(segment
		(start 21.727414 -96.893126)
		(end 24.169624 -98.603308)
		(width 0.1651)
		(layer "In2.Cu")
		(net "PE_RX1_DR9_P")
	)
	(segment
		(start 36.34613 -57.56783)
		(end 35.345116 -57.56783)
		(width 0.1651)
		(layer "In2.Cu")
		(net "PE_RX1_DR9_P")
	)
	(segment
		(start 31.96971 -60.392056)
		(end 30.372558 -69.44868)
		(width 0.1651)
		(layer "In2.Cu")
		(net "PE_RX1_DR9_P")
	)
	(segment
		(start 30.451806 -151.005794)
		(end 26.967688 -170.771312)
		(width 0.1651)
		(layer "In2.Cu")
		(net "PE_RX1_DR9_P")
	)
	(segment
		(start 24.169624 -98.603308)
		(end 24.730964 -98.9965)
		(width 0.1651)
		(layer "In2.Cu")
		(net "PE_RX1_DR9_P")
	)
	(segment
		(start 34.177986 -145.684494)
		(end 34.109406 -145.782284)
		(width 0.1651)
		(layer "In2.Cu")
		(net "PE_RX1_DR9_P")
	)
	(segment
		(start 17.744694 -178.6509)
		(end 7.143242 -180.519832)
		(width 0.1651)
		(layer "In2.Cu")
		(net "PE_RX1_DR9_P")
	)
	(segment
		(start 34.109406 -145.782284)
		(end 30.451806 -151.005794)
		(width 0.1651)
		(layer "In2.Cu")
		(net "PE_RX1_DR9_P")
	)
	(segment
		(start 35.345116 -57.56783)
		(end 34.342578 -57.744614)
		(width 0.1651)
		(layer "In2.Cu")
		(net "PE_RX1_DR9_P")
	)
	(segment
		(start 33.323784 -58.457846)
		(end 31.96971 -60.392056)
		(width 0.1651)
		(layer "In2.Cu")
		(net "PE_RX1_DR9_P")
	)
	(segment
		(start 41.776142 -111.900716)
		(end 39.582598 -115.033044)
		(width 0.1651)
		(layer "In2.Cu")
		(net "PE_RX1_DR9_P")
	)
	(segment
		(start 39.599362 -101.618288)
		(end 41.869106 -103.207312)
		(width 0.1651)
		(layer "In2.Cu")
		(net "PE_RX1_DR9_P")
	)
	(segment
		(start 42.786554 -106.172254)
		(end 41.776142 -111.900716)
		(width 0.1651)
		(layer "In2.Cu")
		(net "PE_RX1_DR9_P")
	)
	(segment
		(start 24.730964 -98.9965)
		(end 39.599362 -101.618288)
		(width 0.1651)
		(layer "In2.Cu")
		(net "PE_RX1_DR9_P")
	)
	(segment
		(start 7.143242 -180.519832)
		(end 5.308346 -180.519832)
		(width 0.1651)
		(layer "In2.Cu")
		(net "PE_RX1_DR9_P")
	)
	(segment
		(start 38.093396 -56.98998)
		(end 37.846 -57.237376)
		(width 0.174752)
		(layer "F.Cu")
		(net "PE_RX1_DR9_N")
	)
	(segment
		(start 39.200074 -56.98998)
		(end 38.093396 -56.98998)
		(width 0.174752)
		(layer "F.Cu")
		(net "PE_RX1_DR9_N")
	)
	(segment
		(start 37.133276 -57.237376)
		(end 36.72713 -56.83123)
		(width 0.174752)
		(layer "F.Cu")
		(net "PE_RX1_DR9_N")
	)
	(segment
		(start 37.846 -57.237376)
		(end 37.133276 -57.237376)
		(width 0.174752)
		(layer "F.Cu")
		(net "PE_RX1_DR9_N")
	)
	(via
		(at 5.08 -179.935378)
		(size 0.508)
		(drill 0.254)
		(layers "F.Cu" "B.Cu")
		(net "PE_RX1_DR9_N")
	)
	(via
		(at 36.72713 -56.83123)
		(size 0.508)
		(drill 0.254)
		(layers "F.Cu" "B.Cu")
		(net "PE_RX1_DR9_N")
	)
	(segment
		(start 3.905504 -180.189378)
		(end 4.826 -180.189378)
		(width 0.174752)
		(layer "B.Cu")
		(net "PE_RX1_DR9_N")
	)
	(segment
		(start 3.658108 -179.941982)
		(end 3.905504 -180.189378)
		(width 0.174752)
		(layer "B.Cu")
		(net "PE_RX1_DR9_N")
	)
	(segment
		(start 1.868932 -179.941982)
		(end 3.658108 -179.941982)
		(width 0.174752)
		(layer "B.Cu")
		(net "PE_RX1_DR9_N")
	)
	(segment
		(start 4.826 -180.189378)
		(end 5.08 -179.935378)
		(width 0.174752)
		(layer "B.Cu")
		(net "PE_RX1_DR9_N")
	)
	(segment
		(start 34.203132 -57.408064)
		(end 33.06826 -58.202322)
		(width 0.1651)
		(layer "In2.Cu")
		(net "PE_RX1_DR9_N")
	)
	(segment
		(start 24.760428 -173.303692)
		(end 17.605248 -178.31435)
		(width 0.1651)
		(layer "In2.Cu")
		(net "PE_RX1_DR9_N")
	)
	(segment
		(start 33.841182 -145.545048)
		(end 30.115256 -150.866348)
		(width 0.1651)
		(layer "In2.Cu")
		(net "PE_RX1_DR9_N")
	)
	(segment
		(start 18.592546 -89.209626)
		(end 19.495008 -94.325694)
		(width 0.1651)
		(layer "In2.Cu")
		(net "PE_RX1_DR9_N")
	)
	(segment
		(start 5.308854 -180.164232)
		(end 5.08 -179.935378)
		(width 0.1651)
		(layer "In2.Cu")
		(net "PE_RX1_DR9_N")
	)
	(segment
		(start 36.72713 -56.83123)
		(end 36.34613 -57.21223)
		(width 0.1651)
		(layer "In2.Cu")
		(net "PE_RX1_DR9_N")
	)
	(segment
		(start 31.63316 -60.25261)
		(end 30.036008 -69.309234)
		(width 0.1651)
		(layer "In2.Cu")
		(net "PE_RX1_DR9_N")
	)
	(segment
		(start 21.47189 -97.14865)
		(end 23.965662 -98.8949)
		(width 0.1651)
		(layer "In2.Cu")
		(net "PE_RX1_DR9_N")
	)
	(segment
		(start 8.081772 -179.99329)
		(end 7.112 -180.164232)
		(width 0.1651)
		(layer "In2.Cu")
		(net "PE_RX1_DR9_N")
	)
	(segment
		(start 39.459916 -101.954838)
		(end 41.613582 -103.462836)
		(width 0.1651)
		(layer "In2.Cu")
		(net "PE_RX1_DR9_N")
	)
	(segment
		(start 23.965662 -98.8949)
		(end 24.591518 -99.33305)
		(width 0.1651)
		(layer "In2.Cu")
		(net "PE_RX1_DR9_N")
	)
	(segment
		(start 30.036008 -69.309234)
		(end 19.431 -84.455)
		(width 0.1651)
		(layer "In2.Cu")
		(net "PE_RX1_DR9_N")
	)
	(segment
		(start 7.112 -180.164232)
		(end 5.308854 -180.164232)
		(width 0.1651)
		(layer "In2.Cu")
		(net "PE_RX1_DR9_N")
	)
	(segment
		(start 17.605248 -178.31435)
		(end 8.081772 -179.99329)
		(width 0.1651)
		(layer "In2.Cu")
		(net "PE_RX1_DR9_N")
	)
	(segment
		(start 41.439592 -111.76127)
		(end 39.246048 -114.893598)
		(width 0.1651)
		(layer "In2.Cu")
		(net "PE_RX1_DR9_N")
	)
	(segment
		(start 36.34613 -57.21223)
		(end 35.313874 -57.21223)
		(width 0.1651)
		(layer "In2.Cu")
		(net "PE_RX1_DR9_N")
	)
	(segment
		(start 41.613582 -103.462836)
		(end 42.060114 -104.100122)
		(width 0.1651)
		(layer "In2.Cu")
		(net "PE_RX1_DR9_N")
	)
	(segment
		(start 33.06826 -58.202322)
		(end 31.63316 -60.25261)
		(width 0.1651)
		(layer "In2.Cu")
		(net "PE_RX1_DR9_N")
	)
	(segment
		(start 26.631138 -170.631866)
		(end 24.760428 -173.303692)
		(width 0.1651)
		(layer "In2.Cu")
		(net "PE_RX1_DR9_N")
	)
	(segment
		(start 30.115256 -150.866348)
		(end 26.631138 -170.631866)
		(width 0.1651)
		(layer "In2.Cu")
		(net "PE_RX1_DR9_N")
	)
	(segment
		(start 39.246048 -114.893598)
		(end 33.841182 -145.545048)
		(width 0.1651)
		(layer "In2.Cu")
		(net "PE_RX1_DR9_N")
	)
	(segment
		(start 19.431 -84.455)
		(end 18.592546 -89.209626)
		(width 0.1651)
		(layer "In2.Cu")
		(net "PE_RX1_DR9_N")
	)
	(segment
		(start 42.425366 -106.172254)
		(end 41.439592 -111.76127)
		(width 0.1651)
		(layer "In2.Cu")
		(net "PE_RX1_DR9_N")
	)
	(segment
		(start 24.591518 -99.33305)
		(end 39.459916 -101.954838)
		(width 0.1651)
		(layer "In2.Cu")
		(net "PE_RX1_DR9_N")
	)
	(segment
		(start 35.313874 -57.21223)
		(end 34.203132 -57.408064)
		(width 0.1651)
		(layer "In2.Cu")
		(net "PE_RX1_DR9_N")
	)
	(segment
		(start 19.495008 -94.325694)
		(end 21.47189 -97.14865)
		(width 0.1651)
		(layer "In2.Cu")
		(net "PE_RX1_DR9_N")
	)
	(segment
		(start 42.060114 -104.100122)
		(end 42.425366 -106.172254)
		(width 0.1651)
		(layer "In2.Cu")
		(net "PE_RX1_DR9_N")
	)
	(segment
		(start 37.846 -160.542478)
		(end 37.13353 -160.542478)
		(width 0.174752)
		(layer "F.Cu")
		(net "PE_RX1_DR8_P")
	)
	(segment
		(start 38.093396 -160.789874)
		(end 37.846 -160.542478)
		(width 0.174752)
		(layer "F.Cu")
		(net "PE_RX1_DR8_P")
	)
	(segment
		(start 37.13353 -160.542478)
		(end 36.72713 -160.948878)
		(width 0.174752)
		(layer "F.Cu")
		(net "PE_RX1_DR8_P")
	)
	(segment
		(start 39.200074 -160.789874)
		(end 38.093396 -160.789874)
		(width 0.174752)
		(layer "F.Cu")
		(net "PE_RX1_DR8_P")
	)
	(via
		(at 36.72713 -160.948878)
		(size 0.508)
		(drill 0.254)
		(layers "F.Cu" "B.Cu")
		(net "PE_RX1_DR8_P")
	)
	(via
		(at 5.08 -200.748138)
		(size 0.508)
		(drill 0.254)
		(layers "F.Cu" "B.Cu")
		(net "PE_RX1_DR8_P")
	)
	(segment
		(start 4.826508 -200.494646)
		(end 5.08 -200.748138)
		(width 0.174752)
		(layer "B.Cu")
		(net "PE_RX1_DR8_P")
	)
	(segment
		(start 1.868932 -200.742042)
		(end 3.658108 -200.742042)
		(width 0.174752)
		(layer "B.Cu")
		(net "PE_RX1_DR8_P")
	)
	(segment
		(start 3.658108 -200.742042)
		(end 3.905504 -200.494646)
		(width 0.174752)
		(layer "B.Cu")
		(net "PE_RX1_DR8_P")
	)
	(segment
		(start 3.905504 -200.494646)
		(end 4.826508 -200.494646)
		(width 0.174752)
		(layer "B.Cu")
		(net "PE_RX1_DR8_P")
	)
	(segment
		(start 32.46374 -163.416488)
		(end 30.873954 -172.43298)
		(width 0.1651)
		(layer "In2.Cu")
		(net "PE_RX1_DR8_P")
	)
	(segment
		(start 14.176248 -196.280024)
		(end 8.449056 -200.289922)
		(width 0.1651)
		(layer "In2.Cu")
		(net "PE_RX1_DR8_P")
	)
	(segment
		(start 34.755328 -160.672018)
		(end 34.029396 -161.180526)
		(width 0.1651)
		(layer "In2.Cu")
		(net "PE_RX1_DR8_P")
	)
	(segment
		(start 30.873954 -172.43298)
		(end 14.176248 -196.280024)
		(width 0.1651)
		(layer "In2.Cu")
		(net "PE_RX1_DR8_P")
	)
	(segment
		(start 8.449056 -200.289922)
		(end 7.143242 -200.520046)
		(width 0.1651)
		(layer "In2.Cu")
		(net "PE_RX1_DR8_P")
	)
	(segment
		(start 34.029396 -161.180526)
		(end 32.46374 -163.416488)
		(width 0.1651)
		(layer "In2.Cu")
		(net "PE_RX1_DR8_P")
	)
	(segment
		(start 36.72713 -160.948878)
		(end 36.34613 -160.567878)
		(width 0.1651)
		(layer "In2.Cu")
		(net "PE_RX1_DR8_P")
	)
	(segment
		(start 5.308092 -200.520046)
		(end 5.08 -200.748138)
		(width 0.1651)
		(layer "In2.Cu")
		(net "PE_RX1_DR8_P")
	)
	(segment
		(start 35.345116 -160.567878)
		(end 34.755328 -160.672018)
		(width 0.1651)
		(layer "In2.Cu")
		(net "PE_RX1_DR8_P")
	)
	(segment
		(start 7.143242 -200.520046)
		(end 5.308092 -200.520046)
		(width 0.1651)
		(layer "In2.Cu")
		(net "PE_RX1_DR8_P")
	)
	(segment
		(start 36.34613 -160.567878)
		(end 35.345116 -160.567878)
		(width 0.1651)
		(layer "In2.Cu")
		(net "PE_RX1_DR8_P")
	)
	(segment
		(start 37.846 -160.237424)
		(end 37.133276 -160.237424)
		(width 0.174752)
		(layer "F.Cu")
		(net "PE_RX1_DR8_N")
	)
	(segment
		(start 37.133276 -160.237424)
		(end 36.72713 -159.831278)
		(width 0.174752)
		(layer "F.Cu")
		(net "PE_RX1_DR8_N")
	)
	(segment
		(start 39.200074 -159.990028)
		(end 38.093396 -159.990028)
		(width 0.174752)
		(layer "F.Cu")
		(net "PE_RX1_DR8_N")
	)
	(segment
		(start 38.093396 -159.990028)
		(end 37.846 -160.237424)
		(width 0.174752)
		(layer "F.Cu")
		(net "PE_RX1_DR8_N")
	)
	(via
		(at 5.08 -199.935338)
		(size 0.508)
		(drill 0.254)
		(layers "F.Cu" "B.Cu")
		(net "PE_RX1_DR8_N")
	)
	(via
		(at 36.72713 -159.831278)
		(size 0.508)
		(drill 0.254)
		(layers "F.Cu" "B.Cu")
		(net "PE_RX1_DR8_N")
	)
	(segment
		(start 1.868932 -199.942196)
		(end 3.658108 -199.942196)
		(width 0.174752)
		(layer "B.Cu")
		(net "PE_RX1_DR8_N")
	)
	(segment
		(start 4.825746 -200.189592)
		(end 5.08 -199.935338)
		(width 0.174752)
		(layer "B.Cu")
		(net "PE_RX1_DR8_N")
	)
	(segment
		(start 3.658108 -199.942196)
		(end 3.905504 -200.189592)
		(width 0.174752)
		(layer "B.Cu")
		(net "PE_RX1_DR8_N")
	)
	(segment
		(start 3.905504 -200.189592)
		(end 4.825746 -200.189592)
		(width 0.174752)
		(layer "B.Cu")
		(net "PE_RX1_DR8_N")
	)
	(segment
		(start 8.30961 -199.953372)
		(end 7.112 -200.164446)
		(width 0.1651)
		(layer "In2.Cu")
		(net "PE_RX1_DR8_N")
	)
	(segment
		(start 13.920724 -196.0245)
		(end 8.30961 -199.953372)
		(width 0.1651)
		(layer "In2.Cu")
		(net "PE_RX1_DR8_N")
	)
	(segment
		(start 36.34613 -160.212278)
		(end 35.313874 -160.212278)
		(width 0.1651)
		(layer "In2.Cu")
		(net "PE_RX1_DR8_N")
	)
	(segment
		(start 35.313874 -160.212278)
		(end 34.615882 -160.335468)
		(width 0.1651)
		(layer "In2.Cu")
		(net "PE_RX1_DR8_N")
	)
	(segment
		(start 5.309108 -200.164446)
		(end 5.08 -199.935338)
		(width 0.1651)
		(layer "In2.Cu")
		(net "PE_RX1_DR8_N")
	)
	(segment
		(start 30.537404 -172.293534)
		(end 13.920724 -196.0245)
		(width 0.1651)
		(layer "In2.Cu")
		(net "PE_RX1_DR8_N")
	)
	(segment
		(start 33.773872 -160.925002)
		(end 32.12719 -163.277042)
		(width 0.1651)
		(layer "In2.Cu")
		(net "PE_RX1_DR8_N")
	)
	(segment
		(start 36.72713 -159.831278)
		(end 36.34613 -160.212278)
		(width 0.1651)
		(layer "In2.Cu")
		(net "PE_RX1_DR8_N")
	)
	(segment
		(start 34.615882 -160.335468)
		(end 33.773872 -160.925002)
		(width 0.1651)
		(layer "In2.Cu")
		(net "PE_RX1_DR8_N")
	)
	(segment
		(start 32.12719 -163.277042)
		(end 30.537404 -172.293534)
		(width 0.1651)
		(layer "In2.Cu")
		(net "PE_RX1_DR8_N")
	)
	(segment
		(start 7.112 -200.164446)
		(end 5.309108 -200.164446)
		(width 0.1651)
		(layer "In2.Cu")
		(net "PE_RX1_DR8_N")
	)
	(segment
		(start 39.200074 -263.789922)
		(end 38.093396 -263.789922)
		(width 0.174752)
		(layer "F.Cu")
		(net "PE_RX1_DR7_P")
	)
	(segment
		(start 37.846 -263.542526)
		(end 37.13353 -263.542526)
		(width 0.174752)
		(layer "F.Cu")
		(net "PE_RX1_DR7_P")
	)
	(segment
		(start 37.13353 -263.542526)
		(end 36.72713 -263.948926)
		(width 0.174752)
		(layer "F.Cu")
		(net "PE_RX1_DR7_P")
	)
	(segment
		(start 38.093396 -263.789922)
		(end 37.846 -263.542526)
		(width 0.174752)
		(layer "F.Cu")
		(net "PE_RX1_DR7_P")
	)
	(via
		(at 36.72713 -263.948926)
		(size 0.508)
		(drill 0.254)
		(layers "F.Cu" "B.Cu")
		(net "PE_RX1_DR7_P")
	)
	(via
		(at 5.08 -303.548288)
		(size 0.508)
		(drill 0.254)
		(layers "F.Cu" "B.Cu")
		(net "PE_RX1_DR7_P")
	)
	(segment
		(start 3.905504 -303.294542)
		(end 4.826254 -303.294542)
		(width 0.174752)
		(layer "B.Cu")
		(net "PE_RX1_DR7_P")
	)
	(segment
		(start 4.826254 -303.294542)
		(end 5.08 -303.548288)
		(width 0.174752)
		(layer "B.Cu")
		(net "PE_RX1_DR7_P")
	)
	(segment
		(start 1.868932 -303.542192)
		(end 3.657854 -303.542192)
		(width 0.174752)
		(layer "B.Cu")
		(net "PE_RX1_DR7_P")
	)
	(segment
		(start 3.657854 -303.542192)
		(end 3.905504 -303.294542)
		(width 0.174752)
		(layer "B.Cu")
		(net "PE_RX1_DR7_P")
	)
	(segment
		(start 35.376358 -263.567926)
		(end 33.482026 -263.90219)
		(width 0.1651)
		(layer "In2.Cu")
		(net "PE_RX1_DR7_P")
	)
	(segment
		(start 7.143242 -303.319942)
		(end 5.308346 -303.319942)
		(width 0.1651)
		(layer "In2.Cu")
		(net "PE_RX1_DR7_P")
	)
	(segment
		(start 7.799324 -303.204372)
		(end 7.143242 -303.319942)
		(width 0.1651)
		(layer "In2.Cu")
		(net "PE_RX1_DR7_P")
	)
	(segment
		(start 5.308346 -303.319942)
		(end 5.08 -303.548288)
		(width 0.1651)
		(layer "In2.Cu")
		(net "PE_RX1_DR7_P")
	)
	(segment
		(start 13.819124 -298.990766)
		(end 7.799324 -303.204372)
		(width 0.1651)
		(layer "In2.Cu")
		(net "PE_RX1_DR7_P")
	)
	(segment
		(start 32.386524 -264.669524)
		(end 31.769558 -265.550396)
		(width 0.1651)
		(layer "In2.Cu")
		(net "PE_RX1_DR7_P")
	)
	(segment
		(start 33.482026 -263.90219)
		(end 32.386524 -264.669524)
		(width 0.1651)
		(layer "In2.Cu")
		(net "PE_RX1_DR7_P")
	)
	(segment
		(start 36.34613 -263.567926)
		(end 35.376358 -263.567926)
		(width 0.1651)
		(layer "In2.Cu")
		(net "PE_RX1_DR7_P")
	)
	(segment
		(start 36.72713 -263.948926)
		(end 36.34613 -263.567926)
		(width 0.1651)
		(layer "In2.Cu")
		(net "PE_RX1_DR7_P")
	)
	(segment
		(start 29.930598 -275.979636)
		(end 13.819124 -298.990766)
		(width 0.1651)
		(layer "In2.Cu")
		(net "PE_RX1_DR7_P")
	)
	(segment
		(start 31.769558 -265.550396)
		(end 29.930598 -275.979636)
		(width 0.1651)
		(layer "In2.Cu")
		(net "PE_RX1_DR7_P")
	)
	(segment
		(start 39.200074 -262.990076)
		(end 38.126924 -262.990076)
		(width 0.174752)
		(layer "F.Cu")
		(net "PE_RX1_DR7_N")
	)
	(segment
		(start 37.133276 -263.237472)
		(end 36.72713 -262.831326)
		(width 0.174752)
		(layer "F.Cu")
		(net "PE_RX1_DR7_N")
	)
	(segment
		(start 37.879528 -263.237472)
		(end 37.133276 -263.237472)
		(width 0.174752)
		(layer "F.Cu")
		(net "PE_RX1_DR7_N")
	)
	(segment
		(start 38.126924 -262.990076)
		(end 37.879528 -263.237472)
		(width 0.174752)
		(layer "F.Cu")
		(net "PE_RX1_DR7_N")
	)
	(via
		(at 36.72713 -262.831326)
		(size 0.508)
		(drill 0.254)
		(layers "F.Cu" "B.Cu")
		(net "PE_RX1_DR7_N")
	)
	(via
		(at 5.08 -302.735488)
		(size 0.508)
		(drill 0.254)
		(layers "F.Cu" "B.Cu")
		(net "PE_RX1_DR7_N")
	)
	(segment
		(start 4.826 -302.989488)
		(end 5.08 -302.735488)
		(width 0.174752)
		(layer "B.Cu")
		(net "PE_RX1_DR7_N")
	)
	(segment
		(start 3.905504 -302.989488)
		(end 4.826 -302.989488)
		(width 0.174752)
		(layer "B.Cu")
		(net "PE_RX1_DR7_N")
	)
	(segment
		(start 3.658108 -302.742092)
		(end 3.905504 -302.989488)
		(width 0.174752)
		(layer "B.Cu")
		(net "PE_RX1_DR7_N")
	)
	(segment
		(start 1.868932 -302.742092)
		(end 3.658108 -302.742092)
		(width 0.174752)
		(layer "B.Cu")
		(net "PE_RX1_DR7_N")
	)
	(segment
		(start 32.131 -264.414)
		(end 31.433008 -265.41095)
		(width 0.1651)
		(layer "In2.Cu")
		(net "PE_RX1_DR7_N")
	)
	(segment
		(start 34.367216 -263.384792)
		(end 33.34258 -263.56564)
		(width 0.1651)
		(layer "In2.Cu")
		(net "PE_RX1_DR7_N")
	)
	(segment
		(start 31.433008 -265.41095)
		(end 29.594048 -275.84019)
		(width 0.1651)
		(layer "In2.Cu")
		(net "PE_RX1_DR7_N")
	)
	(segment
		(start 33.34258 -263.56564)
		(end 32.131 -264.414)
		(width 0.1651)
		(layer "In2.Cu")
		(net "PE_RX1_DR7_N")
	)
	(segment
		(start 36.72713 -262.831326)
		(end 36.34613 -263.212326)
		(width 0.1651)
		(layer "In2.Cu")
		(net "PE_RX1_DR7_N")
	)
	(segment
		(start 7.65937 -302.867822)
		(end 7.112 -302.964342)
		(width 0.1651)
		(layer "In2.Cu")
		(net "PE_RX1_DR7_N")
	)
	(segment
		(start 7.659878 -302.867568)
		(end 7.65937 -302.867822)
		(width 0.1651)
		(layer "In2.Cu")
		(net "PE_RX1_DR7_N")
	)
	(segment
		(start 5.308854 -302.964342)
		(end 5.08 -302.735488)
		(width 0.1651)
		(layer "In2.Cu")
		(net "PE_RX1_DR7_N")
	)
	(segment
		(start 36.34613 -263.212326)
		(end 35.345116 -263.212326)
		(width 0.1651)
		(layer "In2.Cu")
		(net "PE_RX1_DR7_N")
	)
	(segment
		(start 7.112 -302.964342)
		(end 5.308854 -302.964342)
		(width 0.1651)
		(layer "In2.Cu")
		(net "PE_RX1_DR7_N")
	)
	(segment
		(start 29.594048 -275.84019)
		(end 13.5636 -298.735242)
		(width 0.1651)
		(layer "In2.Cu")
		(net "PE_RX1_DR7_N")
	)
	(segment
		(start 13.5636 -298.735242)
		(end 7.659878 -302.867568)
		(width 0.1651)
		(layer "In2.Cu")
		(net "PE_RX1_DR7_N")
	)
	(segment
		(start 35.345116 -263.212326)
		(end 34.367216 -263.384792)
		(width 0.1651)
		(layer "In2.Cu")
		(net "PE_RX1_DR7_N")
	)
	(segment
		(start 37.13353 -366.542574)
		(end 36.72713 -366.948974)
		(width 0.174752)
		(layer "F.Cu")
		(net "PE_RX1_DR6_P")
	)
	(segment
		(start 39.200074 -366.78997)
		(end 38.11397 -366.78997)
		(width 0.174752)
		(layer "F.Cu")
		(net "PE_RX1_DR6_P")
	)
	(segment
		(start 38.11397 -366.78997)
		(end 37.866574 -366.542574)
		(width 0.174752)
		(layer "F.Cu")
		(net "PE_RX1_DR6_P")
	)
	(segment
		(start 37.866574 -366.542574)
		(end 37.13353 -366.542574)
		(width 0.174752)
		(layer "F.Cu")
		(net "PE_RX1_DR6_P")
	)
	(via
		(at 5.08 -349.148146)
		(size 0.508)
		(drill 0.254)
		(layers "F.Cu" "B.Cu")
		(net "PE_RX1_DR6_P")
	)
	(via
		(at 36.72713 -366.948974)
		(size 0.508)
		(drill 0.254)
		(layers "F.Cu" "B.Cu")
		(net "PE_RX1_DR6_P")
	)
	(segment
		(start 3.658108 -349.14205)
		(end 3.905504 -348.894654)
		(width 0.174752)
		(layer "B.Cu")
		(net "PE_RX1_DR6_P")
	)
	(segment
		(start 3.905504 -348.894654)
		(end 4.826508 -348.894654)
		(width 0.174752)
		(layer "B.Cu")
		(net "PE_RX1_DR6_P")
	)
	(segment
		(start 1.868932 -349.14205)
		(end 3.658108 -349.14205)
		(width 0.174752)
		(layer "B.Cu")
		(net "PE_RX1_DR6_P")
	)
	(segment
		(start 4.826508 -348.894654)
		(end 5.08 -349.148146)
		(width 0.174752)
		(layer "B.Cu")
		(net "PE_RX1_DR6_P")
	)
	(segment
		(start 7.770876 -349.04172)
		(end 7.080758 -348.920054)
		(width 0.1651)
		(layer "In2.Cu")
		(net "PE_RX1_DR6_P")
	)
	(segment
		(start 5.308092 -348.920054)
		(end 5.08 -349.148146)
		(width 0.1651)
		(layer "In2.Cu")
		(net "PE_RX1_DR6_P")
	)
	(segment
		(start 15.85341 -359.9815)
		(end 8.599678 -349.62211)
		(width 0.1651)
		(layer "In2.Cu")
		(net "PE_RX1_DR6_P")
	)
	(segment
		(start 21.877528 -364.198916)
		(end 15.85341 -359.9815)
		(width 0.1651)
		(layer "In2.Cu")
		(net "PE_RX1_DR6_P")
	)
	(segment
		(start 35.313874 -366.567974)
		(end 21.877528 -364.198916)
		(width 0.1651)
		(layer "In2.Cu")
		(net "PE_RX1_DR6_P")
	)
	(segment
		(start 7.080758 -348.920054)
		(end 5.308092 -348.920054)
		(width 0.1651)
		(layer "In2.Cu")
		(net "PE_RX1_DR6_P")
	)
	(segment
		(start 36.72713 -366.948974)
		(end 36.34613 -366.567974)
		(width 0.1651)
		(layer "In2.Cu")
		(net "PE_RX1_DR6_P")
	)
	(segment
		(start 8.599678 -349.62211)
		(end 7.770876 -349.04172)
		(width 0.1651)
		(layer "In2.Cu")
		(net "PE_RX1_DR6_P")
	)
	(segment
		(start 36.34613 -366.567974)
		(end 35.313874 -366.567974)
		(width 0.1651)
		(layer "In2.Cu")
		(net "PE_RX1_DR6_P")
	)
	(segment
		(start 39.200074 -365.990124)
		(end 38.093396 -365.990124)
		(width 0.174752)
		(layer "F.Cu")
		(net "PE_RX1_DR6_N")
	)
	(segment
		(start 37.846 -366.23752)
		(end 37.133276 -366.23752)
		(width 0.174752)
		(layer "F.Cu")
		(net "PE_RX1_DR6_N")
	)
	(segment
		(start 37.133276 -366.23752)
		(end 36.72713 -365.831374)
		(width 0.174752)
		(layer "F.Cu")
		(net "PE_RX1_DR6_N")
	)
	(segment
		(start 38.093396 -365.990124)
		(end 37.846 -366.23752)
		(width 0.174752)
		(layer "F.Cu")
		(net "PE_RX1_DR6_N")
	)
	(via
		(at 36.72713 -365.831374)
		(size 0.508)
		(drill 0.254)
		(layers "F.Cu" "B.Cu")
		(net "PE_RX1_DR6_N")
	)
	(via
		(at 5.08 -348.335346)
		(size 0.508)
		(drill 0.254)
		(layers "F.Cu" "B.Cu")
		(net "PE_RX1_DR6_N")
	)
	(segment
		(start 3.905504 -348.5896)
		(end 4.825746 -348.5896)
		(width 0.174752)
		(layer "B.Cu")
		(net "PE_RX1_DR6_N")
	)
	(segment
		(start 1.868932 -348.342204)
		(end 3.658108 -348.342204)
		(width 0.174752)
		(layer "B.Cu")
		(net "PE_RX1_DR6_N")
	)
	(segment
		(start 3.658108 -348.342204)
		(end 3.905504 -348.5896)
		(width 0.174752)
		(layer "B.Cu")
		(net "PE_RX1_DR6_N")
	)
	(segment
		(start 4.825746 -348.5896)
		(end 5.08 -348.335346)
		(width 0.174752)
		(layer "B.Cu")
		(net "PE_RX1_DR6_N")
	)
	(segment
		(start 5.309108 -348.564454)
		(end 5.08 -348.335346)
		(width 0.1651)
		(layer "In2.Cu")
		(net "PE_RX1_DR6_N")
	)
	(segment
		(start 7.112 -348.564454)
		(end 5.309108 -348.564454)
		(width 0.1651)
		(layer "In2.Cu")
		(net "PE_RX1_DR6_N")
	)
	(segment
		(start 22.016974 -363.862366)
		(end 16.108934 -359.725976)
		(width 0.1651)
		(layer "In2.Cu")
		(net "PE_RX1_DR6_N")
	)
	(segment
		(start 7.910322 -348.70517)
		(end 7.112 -348.564454)
		(width 0.1651)
		(layer "In2.Cu")
		(net "PE_RX1_DR6_N")
	)
	(segment
		(start 36.72713 -365.831374)
		(end 36.34613 -366.212374)
		(width 0.1651)
		(layer "In2.Cu")
		(net "PE_RX1_DR6_N")
	)
	(segment
		(start 35.345116 -366.212374)
		(end 22.016974 -363.862366)
		(width 0.1651)
		(layer "In2.Cu")
		(net "PE_RX1_DR6_N")
	)
	(segment
		(start 16.108934 -359.725976)
		(end 8.855202 -349.366586)
		(width 0.1651)
		(layer "In2.Cu")
		(net "PE_RX1_DR6_N")
	)
	(segment
		(start 8.855202 -349.366586)
		(end 7.910322 -348.70517)
		(width 0.1651)
		(layer "In2.Cu")
		(net "PE_RX1_DR6_N")
	)
	(segment
		(start 36.34613 -366.212374)
		(end 35.345116 -366.212374)
		(width 0.1651)
		(layer "In2.Cu")
		(net "PE_RX1_DR6_N")
	)
	(segment
		(start 37.719 -469.237568)
		(end 37.133276 -469.237568)
		(width 0.174752)
		(layer "F.Cu")
		(net "PE_RX1_DR5_P")
	)
	(segment
		(start 37.133276 -469.237568)
		(end 36.72713 -468.831422)
		(width 0.174752)
		(layer "F.Cu")
		(net "PE_RX1_DR5_P")
	)
	(segment
		(start 37.966396 -468.990172)
		(end 37.719 -469.237568)
		(width 0.174752)
		(layer "F.Cu")
		(net "PE_RX1_DR5_P")
	)
	(segment
		(start 39.200074 -468.990172)
		(end 37.966396 -468.990172)
		(width 0.174752)
		(layer "F.Cu")
		(net "PE_RX1_DR5_P")
	)
	(via
		(at 36.72713 -468.831422)
		(size 0.508)
		(drill 0.254)
		(layers "F.Cu" "B.Cu")
		(net "PE_RX1_DR5_P")
	)
	(via
		(at 5.08 -435.135274)
		(size 0.508)
		(drill 0.254)
		(layers "F.Cu" "B.Cu")
		(net "PE_RX1_DR5_P")
	)
	(segment
		(start 1.868932 -435.141878)
		(end 3.657854 -435.141878)
		(width 0.174752)
		(layer "B.Cu")
		(net "PE_RX1_DR5_P")
	)
	(segment
		(start 4.825746 -435.389528)
		(end 5.08 -435.135274)
		(width 0.174752)
		(layer "B.Cu")
		(net "PE_RX1_DR5_P")
	)
	(segment
		(start 3.905504 -435.389528)
		(end 4.825746 -435.389528)
		(width 0.174752)
		(layer "B.Cu")
		(net "PE_RX1_DR5_P")
	)
	(segment
		(start 3.657854 -435.141878)
		(end 3.905504 -435.389528)
		(width 0.174752)
		(layer "B.Cu")
		(net "PE_RX1_DR5_P")
	)
	(segment
		(start 10.381488 -438.321196)
		(end 8.870696 -436.16372)
		(width 0.1651)
		(layer "In2.Cu")
		(net "PE_RX1_DR5_P")
	)
	(segment
		(start 8.870696 -436.16372)
		(end 7.936484 -435.509416)
		(width 0.1651)
		(layer "In2.Cu")
		(net "PE_RX1_DR5_P")
	)
	(segment
		(start 7.936484 -435.509416)
		(end 7.112 -435.364128)
		(width 0.1651)
		(layer "In2.Cu")
		(net "PE_RX1_DR5_P")
	)
	(segment
		(start 35.345116 -469.212422)
		(end 19.846544 -466.479636)
		(width 0.1651)
		(layer "In2.Cu")
		(net "PE_RX1_DR5_P")
	)
	(segment
		(start 7.112 -435.364128)
		(end 5.308854 -435.364128)
		(width 0.1651)
		(layer "In2.Cu")
		(net "PE_RX1_DR5_P")
	)
	(segment
		(start 36.72713 -468.831422)
		(end 36.34613 -469.212422)
		(width 0.1651)
		(layer "In2.Cu")
		(net "PE_RX1_DR5_P")
	)
	(segment
		(start 16.244062 -463.96783)
		(end 14.452092 -461.409288)
		(width 0.1651)
		(layer "In2.Cu")
		(net "PE_RX1_DR5_P")
	)
	(segment
		(start 19.744944 -466.437726)
		(end 16.306292 -464.03006)
		(width 0.1651)
		(layer "In2.Cu")
		(net "PE_RX1_DR5_P")
	)
	(segment
		(start 36.34613 -469.212422)
		(end 35.345116 -469.212422)
		(width 0.1651)
		(layer "In2.Cu")
		(net "PE_RX1_DR5_P")
	)
	(segment
		(start 5.308854 -435.364128)
		(end 5.08 -435.135274)
		(width 0.1651)
		(layer "In2.Cu")
		(net "PE_RX1_DR5_P")
	)
	(segment
		(start 14.452092 -461.409288)
		(end 10.381488 -438.321196)
		(width 0.1651)
		(layer "In2.Cu")
		(net "PE_RX1_DR5_P")
	)
	(arc
		(start 19.846544 -466.479636)
		(mid 19.793443 -466.464256)
		(end 19.744944 -466.437726)
		(width 0.1651)
		(layer "In2.Cu")
		(net "PE_RX1_DR5_P")
	)
	(arc
		(start 16.306292 -464.03006)
		(mid 16.272462 -464.00166)
		(end 16.244062 -463.96783)
		(width 0.1651)
		(layer "In2.Cu")
		(net "PE_RX1_DR5_P")
	)
	(segment
		(start 37.973 -469.790018)
		(end 37.725604 -469.542622)
		(width 0.174752)
		(layer "F.Cu")
		(net "PE_RX1_DR5_N")
	)
	(segment
		(start 39.200074 -469.790018)
		(end 37.973 -469.790018)
		(width 0.174752)
		(layer "F.Cu")
		(net "PE_RX1_DR5_N")
	)
	(segment
		(start 37.13353 -469.542622)
		(end 36.72713 -469.949022)
		(width 0.174752)
		(layer "F.Cu")
		(net "PE_RX1_DR5_N")
	)
	(segment
		(start 37.725604 -469.542622)
		(end 37.13353 -469.542622)
		(width 0.174752)
		(layer "F.Cu")
		(net "PE_RX1_DR5_N")
	)
	(via
		(at 36.72713 -469.949022)
		(size 0.508)
		(drill 0.254)
		(layers "F.Cu" "B.Cu")
		(net "PE_RX1_DR5_N")
	)
	(via
		(at 5.08 -435.948074)
		(size 0.508)
		(drill 0.254)
		(layers "F.Cu" "B.Cu")
		(net "PE_RX1_DR5_N")
	)
	(segment
		(start 4.826508 -435.694582)
		(end 5.08 -435.948074)
		(width 0.174752)
		(layer "B.Cu")
		(net "PE_RX1_DR5_N")
	)
	(segment
		(start 3.658108 -435.941978)
		(end 3.905504 -435.694582)
		(width 0.174752)
		(layer "B.Cu")
		(net "PE_RX1_DR5_N")
	)
	(segment
		(start 1.868932 -435.941978)
		(end 3.658108 -435.941978)
		(width 0.174752)
		(layer "B.Cu")
		(net "PE_RX1_DR5_N")
	)
	(segment
		(start 3.905504 -435.694582)
		(end 4.826508 -435.694582)
		(width 0.174752)
		(layer "B.Cu")
		(net "PE_RX1_DR5_N")
	)
	(segment
		(start 36.34613 -469.568022)
		(end 35.313874 -469.568022)
		(width 0.1651)
		(layer "In2.Cu")
		(net "PE_RX1_DR5_N")
	)
	(segment
		(start 7.797038 -435.845966)
		(end 7.080758 -435.719728)
		(width 0.1651)
		(layer "In2.Cu")
		(net "PE_RX1_DR5_N")
	)
	(segment
		(start 19.540982 -466.729064)
		(end 16.10233 -464.321652)
		(width 0.1651)
		(layer "In2.Cu")
		(net "PE_RX1_DR5_N")
	)
	(segment
		(start 14.115542 -461.548734)
		(end 10.044938 -438.460642)
		(width 0.1651)
		(layer "In2.Cu")
		(net "PE_RX1_DR5_N")
	)
	(segment
		(start 8.615172 -436.419244)
		(end 7.797038 -435.845966)
		(width 0.1651)
		(layer "In2.Cu")
		(net "PE_RX1_DR5_N")
	)
	(segment
		(start 35.313874 -469.568022)
		(end 19.784822 -466.829902)
		(width 0.1651)
		(layer "In2.Cu")
		(net "PE_RX1_DR5_N")
	)
	(segment
		(start 7.080758 -435.719728)
		(end 5.308346 -435.719728)
		(width 0.1651)
		(layer "In2.Cu")
		(net "PE_RX1_DR5_N")
	)
	(segment
		(start 5.308346 -435.719728)
		(end 5.08 -435.948074)
		(width 0.1651)
		(layer "In2.Cu")
		(net "PE_RX1_DR5_N")
	)
	(segment
		(start 15.95247 -464.171792)
		(end 14.115542 -461.548734)
		(width 0.1651)
		(layer "In2.Cu")
		(net "PE_RX1_DR5_N")
	)
	(segment
		(start 36.72713 -469.949022)
		(end 36.34613 -469.568022)
		(width 0.1651)
		(layer "In2.Cu")
		(net "PE_RX1_DR5_N")
	)
	(segment
		(start 10.044938 -438.460642)
		(end 8.615172 -436.419244)
		(width 0.1651)
		(layer "In2.Cu")
		(net "PE_RX1_DR5_N")
	)
	(arc
		(start 19.784822 -466.829902)
		(mid 19.657368 -466.792858)
		(end 19.540982 -466.729064)
		(width 0.1651)
		(layer "In2.Cu")
		(net "PE_RX1_DR5_N")
	)
	(arc
		(start 16.10233 -464.321652)
		(mid 16.020837 -464.253285)
		(end 15.95247 -464.171792)
		(width 0.1651)
		(layer "In2.Cu")
		(net "PE_RX1_DR5_N")
	)
	(segment
		(start 223.016826 -57.789826)
		(end 222.76943 -57.54243)
		(width 0.174752)
		(layer "F.Cu")
		(net "PE_RX1_DR4_P")
	)
	(segment
		(start 224.199958 -57.789826)
		(end 223.016826 -57.789826)
		(width 0.174752)
		(layer "F.Cu")
		(net "PE_RX1_DR4_P")
	)
	(segment
		(start 222.76943 -57.54243)
		(end 222.133414 -57.54243)
		(width 0.174752)
		(layer "F.Cu")
		(net "PE_RX1_DR4_P")
	)
	(segment
		(start 222.133414 -57.54243)
		(end 221.727014 -57.94883)
		(width 0.174752)
		(layer "F.Cu")
		(net "PE_RX1_DR4_P")
	)
	(via
		(at 221.727014 -57.94883)
		(size 0.508)
		(drill 0.254)
		(layers "F.Cu" "B.Cu")
		(net "PE_RX1_DR4_P")
	)
	(via
		(at 5.08 -229.548182)
		(size 0.508)
		(drill 0.254)
		(layers "F.Cu" "B.Cu")
		(net "PE_RX1_DR4_P")
	)
	(segment
		(start 1.868932 -229.542086)
		(end 3.657854 -229.542086)
		(width 0.174752)
		(layer "B.Cu")
		(net "PE_RX1_DR4_P")
	)
	(segment
		(start 4.826254 -229.294436)
		(end 5.08 -229.548182)
		(width 0.174752)
		(layer "B.Cu")
		(net "PE_RX1_DR4_P")
	)
	(segment
		(start 3.905504 -229.294436)
		(end 4.826254 -229.294436)
		(width 0.174752)
		(layer "B.Cu")
		(net "PE_RX1_DR4_P")
	)
	(segment
		(start 3.657854 -229.542086)
		(end 3.905504 -229.294436)
		(width 0.174752)
		(layer "B.Cu")
		(net "PE_RX1_DR4_P")
	)
	(segment
		(start 26.270712 -249.24766)
		(end 24.416766 -249.641868)
		(width 0.1651)
		(layer "In2.Cu")
		(net "PE_RX1_DR4_P")
	)
	(segment
		(start 17.22501 -246.502936)
		(end 15.64386 -244.0686)
		(width 0.1651)
		(layer "In2.Cu")
		(net "PE_RX1_DR4_P")
	)
	(segment
		(start 5.308346 -229.319836)
		(end 5.08 -229.548182)
		(width 0.1651)
		(layer "In2.Cu")
		(net "PE_RX1_DR4_P")
	)
	(segment
		(start 24.416766 -249.641868)
		(end 22.658578 -249.26798)
		(width 0.1651)
		(layer "In2.Cu")
		(net "PE_RX1_DR4_P")
	)
	(segment
		(start 206.903828 -75.005692)
		(end 87.622888 -158.531052)
		(width 0.1651)
		(layer "In2.Cu")
		(net "PE_RX1_DR4_P")
	)
	(segment
		(start 22.658578 -249.26798)
		(end 20.910042 -248.896124)
		(width 0.1651)
		(layer "In2.Cu")
		(net "PE_RX1_DR4_P")
	)
	(segment
		(start 29.399484 -247.21566)
		(end 26.270712 -249.24766)
		(width 0.1651)
		(layer "In2.Cu")
		(net "PE_RX1_DR4_P")
	)
	(segment
		(start 221.346014 -57.56783)
		(end 220.345 -57.56783)
		(width 0.1651)
		(layer "In2.Cu")
		(net "PE_RX1_DR4_P")
	)
	(segment
		(start 14.259814 -236.219492)
		(end 9.986264 -230.115618)
		(width 0.1651)
		(layer "In2.Cu")
		(net "PE_RX1_DR4_P")
	)
	(segment
		(start 220.345 -57.56783)
		(end 219.789502 -57.665874)
		(width 0.1651)
		(layer "In2.Cu")
		(net "PE_RX1_DR4_P")
	)
	(segment
		(start 87.622888 -158.531052)
		(end 31.835598 -238.181388)
		(width 0.1651)
		(layer "In2.Cu")
		(net "PE_RX1_DR4_P")
	)
	(segment
		(start 218.32951 -58.68797)
		(end 206.903828 -75.005692)
		(width 0.1651)
		(layer "In2.Cu")
		(net "PE_RX1_DR4_P")
	)
	(segment
		(start 221.727014 -57.94883)
		(end 221.346014 -57.56783)
		(width 0.1651)
		(layer "In2.Cu")
		(net "PE_RX1_DR4_P")
	)
	(segment
		(start 30.52826 -245.60276)
		(end 29.399484 -247.21566)
		(width 0.1651)
		(layer "In2.Cu")
		(net "PE_RX1_DR4_P")
	)
	(segment
		(start 15.64386 -244.0686)
		(end 14.259814 -236.219492)
		(width 0.1651)
		(layer "In2.Cu")
		(net "PE_RX1_DR4_P")
	)
	(segment
		(start 20.910042 -248.896124)
		(end 17.22501 -246.502936)
		(width 0.1651)
		(layer "In2.Cu")
		(net "PE_RX1_DR4_P")
	)
	(segment
		(start 8.120888 -229.319836)
		(end 5.308346 -229.319836)
		(width 0.1651)
		(layer "In2.Cu")
		(net "PE_RX1_DR4_P")
	)
	(segment
		(start 31.835598 -238.181388)
		(end 30.52826 -245.60276)
		(width 0.1651)
		(layer "In2.Cu")
		(net "PE_RX1_DR4_P")
	)
	(segment
		(start 9.094978 -229.49154)
		(end 8.120888 -229.319836)
		(width 0.1651)
		(layer "In2.Cu")
		(net "PE_RX1_DR4_P")
	)
	(segment
		(start 9.986264 -230.115618)
		(end 9.094978 -229.49154)
		(width 0.1651)
		(layer "In2.Cu")
		(net "PE_RX1_DR4_P")
	)
	(segment
		(start 219.789502 -57.665874)
		(end 218.32951 -58.68797)
		(width 0.1651)
		(layer "In2.Cu")
		(net "PE_RX1_DR4_P")
	)
	(segment
		(start 223.005396 -56.98998)
		(end 222.758 -57.237376)
		(width 0.174752)
		(layer "F.Cu")
		(net "PE_RX1_DR4_N")
	)
	(segment
		(start 222.13316 -57.237376)
		(end 221.727014 -56.83123)
		(width 0.174752)
		(layer "F.Cu")
		(net "PE_RX1_DR4_N")
	)
	(segment
		(start 222.758 -57.237376)
		(end 222.13316 -57.237376)
		(width 0.174752)
		(layer "F.Cu")
		(net "PE_RX1_DR4_N")
	)
	(segment
		(start 224.199958 -56.98998)
		(end 223.005396 -56.98998)
		(width 0.174752)
		(layer "F.Cu")
		(net "PE_RX1_DR4_N")
	)
	(via
		(at 5.08 -228.735382)
		(size 0.508)
		(drill 0.254)
		(layers "F.Cu" "B.Cu")
		(net "PE_RX1_DR4_N")
	)
	(via
		(at 221.727014 -56.83123)
		(size 0.508)
		(drill 0.254)
		(layers "F.Cu" "B.Cu")
		(net "PE_RX1_DR4_N")
	)
	(segment
		(start 3.658108 -228.741986)
		(end 3.905504 -228.989382)
		(width 0.174752)
		(layer "B.Cu")
		(net "PE_RX1_DR4_N")
	)
	(segment
		(start 4.826 -228.989382)
		(end 5.08 -228.735382)
		(width 0.174752)
		(layer "B.Cu")
		(net "PE_RX1_DR4_N")
	)
	(segment
		(start 3.905504 -228.989382)
		(end 4.826 -228.989382)
		(width 0.174752)
		(layer "B.Cu")
		(net "PE_RX1_DR4_N")
	)
	(segment
		(start 1.868932 -228.741986)
		(end 3.658108 -228.741986)
		(width 0.174752)
		(layer "B.Cu")
		(net "PE_RX1_DR4_N")
	)
	(segment
		(start 31.499048 -238.041942)
		(end 30.191456 -245.463314)
		(width 0.1651)
		(layer "In2.Cu")
		(net "PE_RX1_DR4_N")
	)
	(segment
		(start 9.234424 -229.15499)
		(end 8.15213 -228.964236)
		(width 0.1651)
		(layer "In2.Cu")
		(net "PE_RX1_DR4_N")
	)
	(segment
		(start 15.98168 -243.935504)
		(end 14.596364 -236.080046)
		(width 0.1651)
		(layer "In2.Cu")
		(net "PE_RX1_DR4_N")
	)
	(segment
		(start 29.14777 -246.955056)
		(end 26.132282 -248.913396)
		(width 0.1651)
		(layer "In2.Cu")
		(net "PE_RX1_DR4_N")
	)
	(segment
		(start 220.313758 -57.21223)
		(end 219.650056 -57.329324)
		(width 0.1651)
		(layer "In2.Cu")
		(net "PE_RX1_DR4_N")
	)
	(segment
		(start 206.648304 -74.750168)
		(end 87.367364 -158.275528)
		(width 0.1651)
		(layer "In2.Cu")
		(net "PE_RX1_DR4_N")
	)
	(segment
		(start 87.367364 -158.275528)
		(end 31.499048 -238.041942)
		(width 0.1651)
		(layer "In2.Cu")
		(net "PE_RX1_DR4_N")
	)
	(segment
		(start 10.241788 -229.860094)
		(end 9.234424 -229.15499)
		(width 0.1651)
		(layer "In2.Cu")
		(net "PE_RX1_DR4_N")
	)
	(segment
		(start 221.727014 -56.83123)
		(end 221.346014 -57.21223)
		(width 0.1651)
		(layer "In2.Cu")
		(net "PE_RX1_DR4_N")
	)
	(segment
		(start 221.346014 -57.21223)
		(end 220.313758 -57.21223)
		(width 0.1651)
		(layer "In2.Cu")
		(net "PE_RX1_DR4_N")
	)
	(segment
		(start 24.416766 -249.27814)
		(end 21.048472 -248.56186)
		(width 0.1651)
		(layer "In2.Cu")
		(net "PE_RX1_DR4_N")
	)
	(segment
		(start 21.048472 -248.56186)
		(end 17.482312 -246.245634)
		(width 0.1651)
		(layer "In2.Cu")
		(net "PE_RX1_DR4_N")
	)
	(segment
		(start 30.191456 -245.463314)
		(end 29.14777 -246.955056)
		(width 0.1651)
		(layer "In2.Cu")
		(net "PE_RX1_DR4_N")
	)
	(segment
		(start 14.596364 -236.080046)
		(end 10.241788 -229.860094)
		(width 0.1651)
		(layer "In2.Cu")
		(net "PE_RX1_DR4_N")
	)
	(segment
		(start 5.308854 -228.964236)
		(end 5.08 -228.735382)
		(width 0.1651)
		(layer "In2.Cu")
		(net "PE_RX1_DR4_N")
	)
	(segment
		(start 219.650056 -57.329324)
		(end 218.073986 -58.432446)
		(width 0.1651)
		(layer "In2.Cu")
		(net "PE_RX1_DR4_N")
	)
	(segment
		(start 17.482312 -246.245634)
		(end 15.98168 -243.935504)
		(width 0.1651)
		(layer "In2.Cu")
		(net "PE_RX1_DR4_N")
	)
	(segment
		(start 218.073986 -58.432446)
		(end 206.648304 -74.750168)
		(width 0.1651)
		(layer "In2.Cu")
		(net "PE_RX1_DR4_N")
	)
	(segment
		(start 26.132282 -248.913396)
		(end 24.416766 -249.27814)
		(width 0.1651)
		(layer "In2.Cu")
		(net "PE_RX1_DR4_N")
	)
	(segment
		(start 8.15213 -228.964236)
		(end 5.308854 -228.964236)
		(width 0.1651)
		(layer "In2.Cu")
		(net "PE_RX1_DR4_N")
	)
	(segment
		(start 224.199958 -160.789874)
		(end 223.132396 -160.789874)
		(width 0.174752)
		(layer "F.Cu")
		(net "PE_RX1_DR3_P")
	)
	(segment
		(start 222.885 -160.542478)
		(end 222.133414 -160.542478)
		(width 0.174752)
		(layer "F.Cu")
		(net "PE_RX1_DR3_P")
	)
	(segment
		(start 223.132396 -160.789874)
		(end 222.885 -160.542478)
		(width 0.174752)
		(layer "F.Cu")
		(net "PE_RX1_DR3_P")
	)
	(segment
		(start 222.133414 -160.542478)
		(end 221.727014 -160.948878)
		(width 0.174752)
		(layer "F.Cu")
		(net "PE_RX1_DR3_P")
	)
	(via
		(at 221.727014 -160.948878)
		(size 0.508)
		(drill 0.254)
		(layers "F.Cu" "B.Cu")
		(net "PE_RX1_DR3_P")
	)
	(via
		(at 5.08 -290.748212)
		(size 0.508)
		(drill 0.254)
		(layers "F.Cu" "B.Cu")
		(net "PE_RX1_DR3_P")
	)
	(segment
		(start 1.868932 -290.742116)
		(end 3.657854 -290.742116)
		(width 0.174752)
		(layer "B.Cu")
		(net "PE_RX1_DR3_P")
	)
	(segment
		(start 3.657854 -290.742116)
		(end 3.905504 -290.494466)
		(width 0.174752)
		(layer "B.Cu")
		(net "PE_RX1_DR3_P")
	)
	(segment
		(start 3.905504 -290.494466)
		(end 4.826254 -290.494466)
		(width 0.174752)
		(layer "B.Cu")
		(net "PE_RX1_DR3_P")
	)
	(segment
		(start 4.826254 -290.494466)
		(end 5.08 -290.748212)
		(width 0.174752)
		(layer "B.Cu")
		(net "PE_RX1_DR3_P")
	)
	(segment
		(start 29.427678 -255.502156)
		(end 29.427932 -255.502156)
		(width 0.1651)
		(layer "In2.Cu")
		(net "PE_RX1_DR3_P")
	)
	(segment
		(start 26.731722 -270.804132)
		(end 17.921986 -283.38526)
		(width 0.1651)
		(layer "In2.Cu")
		(net "PE_RX1_DR3_P")
	)
	(segment
		(start 29.42844 -255.500886)
		(end 29.428186 -255.501394)
		(width 0.1651)
		(layer "In2.Cu")
		(net "PE_RX1_DR3_P")
	)
	(segment
		(start 221.727014 -160.948878)
		(end 221.346014 -160.567878)
		(width 0.1651)
		(layer "In2.Cu")
		(net "PE_RX1_DR3_P")
	)
	(segment
		(start 34.177224 -248.71807)
		(end 29.42844 -255.500886)
		(width 0.1651)
		(layer "In2.Cu")
		(net "PE_RX1_DR3_P")
	)
	(segment
		(start 29.427932 -255.502156)
		(end 26.731722 -270.804132)
		(width 0.1651)
		(layer "In2.Cu")
		(net "PE_RX1_DR3_P")
	)
	(segment
		(start 5.308346 -290.519866)
		(end 5.08 -290.748212)
		(width 0.1651)
		(layer "In2.Cu")
		(net "PE_RX1_DR3_P")
	)
	(segment
		(start 203.87945 -172.099478)
		(end 81.670398 -193.649092)
		(width 0.1651)
		(layer "In2.Cu")
		(net "PE_RX1_DR3_P")
	)
	(segment
		(start 29.428186 -255.501394)
		(end 29.427678 -255.502156)
		(width 0.1651)
		(layer "In2.Cu")
		(net "PE_RX1_DR3_P")
	)
	(segment
		(start 6.467602 -290.519866)
		(end 5.308346 -290.519866)
		(width 0.1651)
		(layer "In2.Cu")
		(net "PE_RX1_DR3_P")
	)
	(segment
		(start 220.349318 -160.567878)
		(end 203.87945 -172.099478)
		(width 0.1651)
		(layer "In2.Cu")
		(net "PE_RX1_DR3_P")
	)
	(segment
		(start 81.670398 -193.649092)
		(end 54.796944 -212.465412)
		(width 0.1651)
		(layer "In2.Cu")
		(net "PE_RX1_DR3_P")
	)
	(segment
		(start 54.796944 -212.465412)
		(end 35.781742 -239.622076)
		(width 0.1651)
		(layer "In2.Cu")
		(net "PE_RX1_DR3_P")
	)
	(segment
		(start 221.346014 -160.567878)
		(end 220.349318 -160.567878)
		(width 0.1651)
		(layer "In2.Cu")
		(net "PE_RX1_DR3_P")
	)
	(segment
		(start 8.15467 -290.222432)
		(end 6.467602 -290.519866)
		(width 0.1651)
		(layer "In2.Cu")
		(net "PE_RX1_DR3_P")
	)
	(segment
		(start 35.781742 -239.622076)
		(end 34.177224 -248.71807)
		(width 0.1651)
		(layer "In2.Cu")
		(net "PE_RX1_DR3_P")
	)
	(segment
		(start 17.921986 -283.38526)
		(end 8.15467 -290.222432)
		(width 0.1651)
		(layer "In2.Cu")
		(net "PE_RX1_DR3_P")
	)
	(segment
		(start 223.132396 -159.990028)
		(end 222.885 -160.237424)
		(width 0.174752)
		(layer "F.Cu")
		(net "PE_RX1_DR3_N")
	)
	(segment
		(start 222.885 -160.237424)
		(end 222.13316 -160.237424)
		(width 0.174752)
		(layer "F.Cu")
		(net "PE_RX1_DR3_N")
	)
	(segment
		(start 224.199958 -159.990028)
		(end 223.132396 -159.990028)
		(width 0.174752)
		(layer "F.Cu")
		(net "PE_RX1_DR3_N")
	)
	(segment
		(start 222.13316 -160.237424)
		(end 221.727014 -159.831278)
		(width 0.174752)
		(layer "F.Cu")
		(net "PE_RX1_DR3_N")
	)
	(via
		(at 221.727014 -159.831278)
		(size 0.508)
		(drill 0.254)
		(layers "F.Cu" "B.Cu")
		(net "PE_RX1_DR3_N")
	)
	(via
		(at 5.08 -289.935412)
		(size 0.508)
		(drill 0.254)
		(layers "F.Cu" "B.Cu")
		(net "PE_RX1_DR3_N")
	)
	(segment
		(start 1.868932 -289.942016)
		(end 3.658108 -289.942016)
		(width 0.174752)
		(layer "B.Cu")
		(net "PE_RX1_DR3_N")
	)
	(segment
		(start 3.905504 -290.189412)
		(end 4.826 -290.189412)
		(width 0.174752)
		(layer "B.Cu")
		(net "PE_RX1_DR3_N")
	)
	(segment
		(start 3.658108 -289.942016)
		(end 3.905504 -290.189412)
		(width 0.174752)
		(layer "B.Cu")
		(net "PE_RX1_DR3_N")
	)
	(segment
		(start 4.826 -290.189412)
		(end 5.08 -289.935412)
		(width 0.174752)
		(layer "B.Cu")
		(net "PE_RX1_DR3_N")
	)
	(segment
		(start 221.727014 -159.831278)
		(end 221.346014 -160.212278)
		(width 0.1651)
		(layer "In2.Cu")
		(net "PE_RX1_DR3_N")
	)
	(segment
		(start 203.740004 -171.762928)
		(end 81.530952 -193.312542)
		(width 0.1651)
		(layer "In2.Cu")
		(net "PE_RX1_DR3_N")
	)
	(segment
		(start 220.23705 -160.212278)
		(end 203.740004 -171.762928)
		(width 0.1651)
		(layer "In2.Cu")
		(net "PE_RX1_DR3_N")
	)
	(segment
		(start 17.666462 -283.129736)
		(end 8.015224 -289.885882)
		(width 0.1651)
		(layer "In2.Cu")
		(net "PE_RX1_DR3_N")
	)
	(segment
		(start 8.015224 -289.885882)
		(end 6.43636 -290.164266)
		(width 0.1651)
		(layer "In2.Cu")
		(net "PE_RX1_DR3_N")
	)
	(segment
		(start 81.530952 -193.312542)
		(end 54.54142 -212.209888)
		(width 0.1651)
		(layer "In2.Cu")
		(net "PE_RX1_DR3_N")
	)
	(segment
		(start 29.09189 -255.36144)
		(end 29.091636 -255.361694)
		(width 0.1651)
		(layer "In2.Cu")
		(net "PE_RX1_DR3_N")
	)
	(segment
		(start 33.840674 -248.578624)
		(end 29.09189 -255.36144)
		(width 0.1651)
		(layer "In2.Cu")
		(net "PE_RX1_DR3_N")
	)
	(segment
		(start 26.395172 -270.664686)
		(end 17.666462 -283.129736)
		(width 0.1651)
		(layer "In2.Cu")
		(net "PE_RX1_DR3_N")
	)
	(segment
		(start 54.54142 -212.209888)
		(end 35.445192 -239.48263)
		(width 0.1651)
		(layer "In2.Cu")
		(net "PE_RX1_DR3_N")
	)
	(segment
		(start 221.346014 -160.212278)
		(end 220.23705 -160.212278)
		(width 0.1651)
		(layer "In2.Cu")
		(net "PE_RX1_DR3_N")
	)
	(segment
		(start 29.091636 -255.361694)
		(end 29.091382 -255.361694)
		(width 0.1651)
		(layer "In2.Cu")
		(net "PE_RX1_DR3_N")
	)
	(segment
		(start 29.091382 -255.361694)
		(end 26.395172 -270.664686)
		(width 0.1651)
		(layer "In2.Cu")
		(net "PE_RX1_DR3_N")
	)
	(segment
		(start 35.445192 -239.48263)
		(end 33.840674 -248.578624)
		(width 0.1651)
		(layer "In2.Cu")
		(net "PE_RX1_DR3_N")
	)
	(segment
		(start 6.43636 -290.164266)
		(end 5.308854 -290.164266)
		(width 0.1651)
		(layer "In2.Cu")
		(net "PE_RX1_DR3_N")
	)
	(segment
		(start 5.308854 -290.164266)
		(end 5.08 -289.935412)
		(width 0.1651)
		(layer "In2.Cu")
		(net "PE_RX1_DR3_N")
	)
	(segment
		(start 224.199958 -263.789922)
		(end 223.132396 -263.789922)
		(width 0.174752)
		(layer "F.Cu")
		(net "PE_RX1_DR2_P")
	)
	(segment
		(start 222.133414 -263.542526)
		(end 221.727014 -263.948926)
		(width 0.174752)
		(layer "F.Cu")
		(net "PE_RX1_DR2_P")
	)
	(segment
		(start 223.132396 -263.789922)
		(end 222.885 -263.542526)
		(width 0.174752)
		(layer "F.Cu")
		(net "PE_RX1_DR2_P")
	)
	(segment
		(start 222.885 -263.542526)
		(end 222.133414 -263.542526)
		(width 0.174752)
		(layer "F.Cu")
		(net "PE_RX1_DR2_P")
	)
	(via
		(at 221.727014 -263.948926)
		(size 0.508)
		(drill 0.254)
		(layers "F.Cu" "B.Cu")
		(net "PE_RX1_DR2_P")
	)
	(via
		(at 5.08 -321.148202)
		(size 0.508)
		(drill 0.254)
		(layers "F.Cu" "B.Cu")
		(net "PE_RX1_DR2_P")
	)
	(segment
		(start 1.868932 -321.142106)
		(end 3.657854 -321.142106)
		(width 0.174752)
		(layer "B.Cu")
		(net "PE_RX1_DR2_P")
	)
	(segment
		(start 3.657854 -321.142106)
		(end 3.905504 -320.894456)
		(width 0.174752)
		(layer "B.Cu")
		(net "PE_RX1_DR2_P")
	)
	(segment
		(start 3.905504 -320.894456)
		(end 4.826254 -320.894456)
		(width 0.174752)
		(layer "B.Cu")
		(net "PE_RX1_DR2_P")
	)
	(segment
		(start 4.826254 -320.894456)
		(end 5.08 -321.148202)
		(width 0.174752)
		(layer "B.Cu")
		(net "PE_RX1_DR2_P")
	)
	(segment
		(start 20.302474 -301.979076)
		(end 23.114 -301.483268)
		(width 0.1651)
		(layer "In2.Cu")
		(net "PE_RX1_DR2_P")
	)
	(segment
		(start 13.844524 -307.664104)
		(end 15.44193 -305.38293)
		(width 0.1651)
		(layer "In2.Cu")
		(net "PE_RX1_DR2_P")
	)
	(segment
		(start 12.149328 -317.280036)
		(end 13.844524 -307.664104)
		(width 0.1651)
		(layer "In2.Cu")
		(net "PE_RX1_DR2_P")
	)
	(segment
		(start 66.980816 -287.97123)
		(end 212.863176 -262.254238)
		(width 0.1651)
		(layer "In2.Cu")
		(net "PE_RX1_DR2_P")
	)
	(segment
		(start 221.346014 -263.567926)
		(end 221.727014 -263.948926)
		(width 0.1651)
		(layer "In2.Cu")
		(net "PE_RX1_DR2_P")
	)
	(segment
		(start 5.308346 -320.919856)
		(end 7.112 -320.919856)
		(width 0.1651)
		(layer "In2.Cu")
		(net "PE_RX1_DR2_P")
	)
	(segment
		(start 45.21962 -303.207674)
		(end 66.980816 -287.97123)
		(width 0.1651)
		(layer "In2.Cu")
		(net "PE_RX1_DR2_P")
	)
	(segment
		(start 212.863176 -262.254238)
		(end 220.313758 -263.567926)
		(width 0.1651)
		(layer "In2.Cu")
		(net "PE_RX1_DR2_P")
	)
	(segment
		(start 15.44193 -305.38293)
		(end 20.302474 -301.979076)
		(width 0.1651)
		(layer "In2.Cu")
		(net "PE_RX1_DR2_P")
	)
	(segment
		(start 10.660126 -319.40627)
		(end 12.149328 -317.280036)
		(width 0.1651)
		(layer "In2.Cu")
		(net "PE_RX1_DR2_P")
	)
	(segment
		(start 23.114 -301.483268)
		(end 39.056564 -304.29454)
		(width 0.1651)
		(layer "In2.Cu")
		(net "PE_RX1_DR2_P")
	)
	(segment
		(start 39.056564 -304.29454)
		(end 45.21962 -303.207674)
		(width 0.1651)
		(layer "In2.Cu")
		(net "PE_RX1_DR2_P")
	)
	(segment
		(start 5.08 -321.148202)
		(end 5.308346 -320.919856)
		(width 0.1651)
		(layer "In2.Cu")
		(net "PE_RX1_DR2_P")
	)
	(segment
		(start 8.965184 -320.593212)
		(end 10.660126 -319.40627)
		(width 0.1651)
		(layer "In2.Cu")
		(net "PE_RX1_DR2_P")
	)
	(segment
		(start 7.112 -320.919856)
		(end 8.965184 -320.593212)
		(width 0.1651)
		(layer "In2.Cu")
		(net "PE_RX1_DR2_P")
	)
	(segment
		(start 220.313758 -263.567926)
		(end 221.346014 -263.567926)
		(width 0.1651)
		(layer "In2.Cu")
		(net "PE_RX1_DR2_P")
	)
	(segment
		(start 223.132396 -262.990076)
		(end 222.885 -263.237472)
		(width 0.174752)
		(layer "F.Cu")
		(net "PE_RX1_DR2_N")
	)
	(segment
		(start 222.885 -263.237472)
		(end 222.13316 -263.237472)
		(width 0.174752)
		(layer "F.Cu")
		(net "PE_RX1_DR2_N")
	)
	(segment
		(start 224.199958 -262.990076)
		(end 223.132396 -262.990076)
		(width 0.174752)
		(layer "F.Cu")
		(net "PE_RX1_DR2_N")
	)
	(segment
		(start 222.13316 -263.237472)
		(end 221.727014 -262.831326)
		(width 0.174752)
		(layer "F.Cu")
		(net "PE_RX1_DR2_N")
	)
	(via
		(at 221.727014 -262.831326)
		(size 0.508)
		(drill 0.254)
		(layers "F.Cu" "B.Cu")
		(net "PE_RX1_DR2_N")
	)
	(via
		(at 5.08 -320.335402)
		(size 0.508)
		(drill 0.254)
		(layers "F.Cu" "B.Cu")
		(net "PE_RX1_DR2_N")
	)
	(segment
		(start 3.658108 -320.342006)
		(end 3.905504 -320.589402)
		(width 0.174752)
		(layer "B.Cu")
		(net "PE_RX1_DR2_N")
	)
	(segment
		(start 3.905504 -320.589402)
		(end 4.826 -320.589402)
		(width 0.174752)
		(layer "B.Cu")
		(net "PE_RX1_DR2_N")
	)
	(segment
		(start 1.868932 -320.342006)
		(end 3.658108 -320.342006)
		(width 0.174752)
		(layer "B.Cu")
		(net "PE_RX1_DR2_N")
	)
	(segment
		(start 4.826 -320.589402)
		(end 5.08 -320.335402)
		(width 0.174752)
		(layer "B.Cu")
		(net "PE_RX1_DR2_N")
	)
	(segment
		(start 13.507974 -307.524658)
		(end 15.186406 -305.127406)
		(width 0.1651)
		(layer "In2.Cu")
		(net "PE_RX1_DR2_N")
	)
	(segment
		(start 11.812778 -317.14059)
		(end 13.507974 -307.524658)
		(width 0.1651)
		(layer "In2.Cu")
		(net "PE_RX1_DR2_N")
	)
	(segment
		(start 5.308854 -320.564256)
		(end 7.080758 -320.564256)
		(width 0.1651)
		(layer "In2.Cu")
		(net "PE_RX1_DR2_N")
	)
	(segment
		(start 10.404602 -319.150746)
		(end 11.812778 -317.14059)
		(width 0.1651)
		(layer "In2.Cu")
		(net "PE_RX1_DR2_N")
	)
	(segment
		(start 66.84137 -287.63468)
		(end 212.863176 -261.89305)
		(width 0.1651)
		(layer "In2.Cu")
		(net "PE_RX1_DR2_N")
	)
	(segment
		(start 5.08 -320.335402)
		(end 5.308854 -320.564256)
		(width 0.1651)
		(layer "In2.Cu")
		(net "PE_RX1_DR2_N")
	)
	(segment
		(start 221.346014 -263.212326)
		(end 221.727014 -262.831326)
		(width 0.1651)
		(layer "In2.Cu")
		(net "PE_RX1_DR2_N")
	)
	(segment
		(start 15.186406 -305.127406)
		(end 20.163028 -301.642526)
		(width 0.1651)
		(layer "In2.Cu")
		(net "PE_RX1_DR2_N")
	)
	(segment
		(start 45.080174 -302.871124)
		(end 66.84137 -287.63468)
		(width 0.1651)
		(layer "In2.Cu")
		(net "PE_RX1_DR2_N")
	)
	(segment
		(start 20.163028 -301.642526)
		(end 23.114 -301.12208)
		(width 0.1651)
		(layer "In2.Cu")
		(net "PE_RX1_DR2_N")
	)
	(segment
		(start 8.825738 -320.256662)
		(end 10.404602 -319.150746)
		(width 0.1651)
		(layer "In2.Cu")
		(net "PE_RX1_DR2_N")
	)
	(segment
		(start 23.114 -301.12208)
		(end 39.056564 -303.933352)
		(width 0.1651)
		(layer "In2.Cu")
		(net "PE_RX1_DR2_N")
	)
	(segment
		(start 39.056564 -303.933352)
		(end 45.080174 -302.871124)
		(width 0.1651)
		(layer "In2.Cu")
		(net "PE_RX1_DR2_N")
	)
	(segment
		(start 220.345 -263.212326)
		(end 221.346014 -263.212326)
		(width 0.1651)
		(layer "In2.Cu")
		(net "PE_RX1_DR2_N")
	)
	(segment
		(start 212.863176 -261.89305)
		(end 220.345 -263.212326)
		(width 0.1651)
		(layer "In2.Cu")
		(net "PE_RX1_DR2_N")
	)
	(segment
		(start 7.080758 -320.564256)
		(end 8.825738 -320.256662)
		(width 0.1651)
		(layer "In2.Cu")
		(net "PE_RX1_DR2_N")
	)
	(segment
		(start 24.24176 -36.457382)
		(end 24.8666 -36.457382)
		(width 0.174752)
		(layer "F.Cu")
		(net "PE_RX1_DR14_P")
	)
	(segment
		(start 23.876 -36.209986)
		(end 24.24176 -36.457382)
		(width 0.174752)
		(layer "F.Cu")
		(net "PE_RX1_DR14_P")
	)
	(segment
		(start 24.8666 -36.457382)
		(end 25.273 -36.050982)
		(width 0.174752)
		(layer "F.Cu")
		(net "PE_RX1_DR14_P")
	)
	(segment
		(start 22.800056 -36.209986)
		(end 23.876 -36.209986)
		(width 0.174752)
		(layer "F.Cu")
		(net "PE_RX1_DR14_P")
	)
	(via
		(at 25.273 -36.050982)
		(size 0.508)
		(drill 0.254)
		(layers "F.Cu" "B.Cu")
		(net "PE_RX1_DR14_P")
	)
	(via
		(at 5.08 -155.14828)
		(size 0.508)
		(drill 0.254)
		(layers "F.Cu" "B.Cu")
		(net "PE_RX1_DR14_P")
	)
	(segment
		(start 4.826254 -154.894534)
		(end 5.08 -155.14828)
		(width 0.174752)
		(layer "B.Cu")
		(net "PE_RX1_DR14_P")
	)
	(segment
		(start 3.905504 -154.894534)
		(end 4.826254 -154.894534)
		(width 0.174752)
		(layer "B.Cu")
		(net "PE_RX1_DR14_P")
	)
	(segment
		(start 3.657854 -155.142184)
		(end 3.905504 -154.894534)
		(width 0.174752)
		(layer "B.Cu")
		(net "PE_RX1_DR14_P")
	)
	(segment
		(start 1.868932 -155.142184)
		(end 3.657854 -155.142184)
		(width 0.174752)
		(layer "B.Cu")
		(net "PE_RX1_DR14_P")
	)
	(segment
		(start 30.282134 -38.23081)
		(end 29.56306 -37.203634)
		(width 0.1651)
		(layer "In2.Cu")
		(net "PE_RX1_DR14_P")
	)
	(segment
		(start 6.833362 -104.557576)
		(end 9.478264 -89.545414)
		(width 0.1651)
		(layer "In2.Cu")
		(net "PE_RX1_DR14_P")
	)
	(segment
		(start 9.004808 -154.747214)
		(end 10.014966 -154.040332)
		(width 0.1651)
		(layer "In2.Cu")
		(net "PE_RX1_DR14_P")
	)
	(segment
		(start 13.17117 -140.503402)
		(end 6.833362 -104.557576)
		(width 0.1651)
		(layer "In2.Cu")
		(net "PE_RX1_DR14_P")
	)
	(segment
		(start 30.757622 -40.928544)
		(end 30.282134 -38.23081)
		(width 0.1651)
		(layer "In2.Cu")
		(net "PE_RX1_DR14_P")
	)
	(segment
		(start 8.02513 -154.919934)
		(end 9.004808 -154.747214)
		(width 0.1651)
		(layer "In2.Cu")
		(net "PE_RX1_DR14_P")
	)
	(segment
		(start 28.926282 -36.757864)
		(end 27.426158 -36.493196)
		(width 0.1651)
		(layer "In2.Cu")
		(net "PE_RX1_DR14_P")
	)
	(segment
		(start 5.08 -155.14828)
		(end 5.308346 -154.919934)
		(width 0.1651)
		(layer "In2.Cu")
		(net "PE_RX1_DR14_P")
	)
	(segment
		(start 11.043666 -152.569926)
		(end 13.17117 -140.503402)
		(width 0.1651)
		(layer "In2.Cu")
		(net "PE_RX1_DR14_P")
	)
	(segment
		(start 10.014966 -154.040332)
		(end 11.043666 -152.569926)
		(width 0.1651)
		(layer "In2.Cu")
		(net "PE_RX1_DR14_P")
	)
	(segment
		(start 9.478264 -89.545414)
		(end 26.462736 -65.289176)
		(width 0.1651)
		(layer "In2.Cu")
		(net "PE_RX1_DR14_P")
	)
	(segment
		(start 25.654 -36.431982)
		(end 25.273 -36.050982)
		(width 0.1651)
		(layer "In2.Cu")
		(net "PE_RX1_DR14_P")
	)
	(segment
		(start 29.56306 -37.203634)
		(end 28.926282 -36.757864)
		(width 0.1651)
		(layer "In2.Cu")
		(net "PE_RX1_DR14_P")
	)
	(segment
		(start 27.078178 -36.431982)
		(end 25.654 -36.431982)
		(width 0.1651)
		(layer "In2.Cu")
		(net "PE_RX1_DR14_P")
	)
	(segment
		(start 5.308346 -154.919934)
		(end 8.02513 -154.919934)
		(width 0.1651)
		(layer "In2.Cu")
		(net "PE_RX1_DR14_P")
	)
	(segment
		(start 26.462736 -65.289176)
		(end 30.757622 -40.928544)
		(width 0.1651)
		(layer "In2.Cu")
		(net "PE_RX1_DR14_P")
	)
	(segment
		(start 27.426158 -36.493196)
		(end 27.078178 -36.431982)
		(width 0.1651)
		(layer "In2.Cu")
		(net "PE_RX1_DR14_P")
	)
	(segment
		(start 24.225504 -36.762436)
		(end 24.866854 -36.762436)
		(width 0.174752)
		(layer "F.Cu")
		(net "PE_RX1_DR14_N")
	)
	(segment
		(start 23.978108 -37.009832)
		(end 24.225504 -36.762436)
		(width 0.174752)
		(layer "F.Cu")
		(net "PE_RX1_DR14_N")
	)
	(segment
		(start 24.866854 -36.762436)
		(end 25.273 -37.168582)
		(width 0.174752)
		(layer "F.Cu")
		(net "PE_RX1_DR14_N")
	)
	(segment
		(start 22.800056 -37.009832)
		(end 23.978108 -37.009832)
		(width 0.174752)
		(layer "F.Cu")
		(net "PE_RX1_DR14_N")
	)
	(via
		(at 5.08 -154.33548)
		(size 0.508)
		(drill 0.254)
		(layers "F.Cu" "B.Cu")
		(net "PE_RX1_DR14_N")
	)
	(via
		(at 25.273 -37.168582)
		(size 0.508)
		(drill 0.254)
		(layers "F.Cu" "B.Cu")
		(net "PE_RX1_DR14_N")
	)
	(segment
		(start 1.868932 -154.342084)
		(end 3.658108 -154.342084)
		(width 0.174752)
		(layer "B.Cu")
		(net "PE_RX1_DR14_N")
	)
	(segment
		(start 3.658108 -154.342084)
		(end 3.905504 -154.58948)
		(width 0.174752)
		(layer "B.Cu")
		(net "PE_RX1_DR14_N")
	)
	(segment
		(start 4.826 -154.58948)
		(end 5.08 -154.33548)
		(width 0.174752)
		(layer "B.Cu")
		(net "PE_RX1_DR14_N")
	)
	(segment
		(start 3.905504 -154.58948)
		(end 4.826 -154.58948)
		(width 0.174752)
		(layer "B.Cu")
		(net "PE_RX1_DR14_N")
	)
	(segment
		(start 12.506198 -141.143736)
		(end 12.723876 -140.991082)
		(width 0.1651)
		(layer "In2.Cu")
		(net "PE_RX1_DR14_N")
	)
	(segment
		(start 29.945584 -38.370256)
		(end 29.307536 -37.459158)
		(width 0.1651)
		(layer "In2.Cu")
		(net "PE_RX1_DR14_N")
	)
	(segment
		(start 5.308854 -154.564334)
		(end 7.993888 -154.564334)
		(width 0.1651)
		(layer "In2.Cu")
		(net "PE_RX1_DR14_N")
	)
	(segment
		(start 9.759442 -153.784808)
		(end 10.706862 -152.43048)
		(width 0.1651)
		(layer "In2.Cu")
		(net "PE_RX1_DR14_N")
	)
	(segment
		(start 29.18587 -47.79518)
		(end 29.033216 -47.577248)
		(width 0.1651)
		(layer "In2.Cu")
		(net "PE_RX1_DR14_N")
	)
	(segment
		(start 10.983976 -149.77618)
		(end 11.201654 -149.62378)
		(width 0.1651)
		(layer "In2.Cu")
		(net "PE_RX1_DR14_N")
	)
	(segment
		(start 28.786836 -37.094414)
		(end 27.046936 -36.787582)
		(width 0.1651)
		(layer "In2.Cu")
		(net "PE_RX1_DR14_N")
	)
	(segment
		(start 27.046936 -36.787582)
		(end 25.654 -36.787582)
		(width 0.1651)
		(layer "In2.Cu")
		(net "PE_RX1_DR14_N")
	)
	(segment
		(start 29.099764 -48.28286)
		(end 29.18587 -47.79518)
		(width 0.1651)
		(layer "In2.Cu")
		(net "PE_RX1_DR14_N")
	)
	(segment
		(start 10.813288 -151.827484)
		(end 10.660634 -151.609552)
		(width 0.1651)
		(layer "In2.Cu")
		(net "PE_RX1_DR14_N")
	)
	(segment
		(start 28.948634 -49.140872)
		(end 28.79598 -48.923194)
		(width 0.1651)
		(layer "In2.Cu")
		(net "PE_RX1_DR14_N")
	)
	(segment
		(start 10.706862 -152.43048)
		(end 10.743692 -152.2222)
		(width 0.1651)
		(layer "In2.Cu")
		(net "PE_RX1_DR14_N")
	)
	(segment
		(start 10.743692 -152.2222)
		(end 10.812526 -151.830786)
		(width 0.1651)
		(layer "In2.Cu")
		(net "PE_RX1_DR14_N")
	)
	(segment
		(start 11.050524 -150.481792)
		(end 10.89787 -150.26386)
		(width 0.1651)
		(layer "In2.Cu")
		(net "PE_RX1_DR14_N")
	)
	(segment
		(start 11.221212 -148.430488)
		(end 11.43889 -148.278088)
		(width 0.1651)
		(layer "In2.Cu")
		(net "PE_RX1_DR14_N")
	)
	(segment
		(start 10.89787 -150.26386)
		(end 10.983976 -149.77618)
		(width 0.1651)
		(layer "In2.Cu")
		(net "PE_RX1_DR14_N")
	)
	(segment
		(start 28.79598 -48.923194)
		(end 28.882086 -48.435514)
		(width 0.1651)
		(layer "In2.Cu")
		(net "PE_RX1_DR14_N")
	)
	(segment
		(start 28.242768 -53.142896)
		(end 28.94838 -49.140872)
		(width 0.1651)
		(layer "In2.Cu")
		(net "PE_RX1_DR14_N")
	)
	(segment
		(start 10.74674 -151.121872)
		(end 10.964418 -150.969472)
		(width 0.1651)
		(layer "In2.Cu")
		(net "PE_RX1_DR14_N")
	)
	(segment
		(start 12.723876 -140.991082)
		(end 12.809982 -140.503402)
		(width 0.1651)
		(layer "In2.Cu")
		(net "PE_RX1_DR14_N")
	)
	(segment
		(start 29.337 -46.937168)
		(end 29.337508 -46.936914)
		(width 0.1651)
		(layer "In2.Cu")
		(net "PE_RX1_DR14_N")
	)
	(segment
		(start 12.33551 -143.194786)
		(end 12.182856 -142.977108)
		(width 0.1651)
		(layer "In2.Cu")
		(net "PE_RX1_DR14_N")
	)
	(segment
		(start 10.964418 -150.969472)
		(end 11.050524 -150.481792)
		(width 0.1651)
		(layer "In2.Cu")
		(net "PE_RX1_DR14_N")
	)
	(segment
		(start 9.141714 -89.405968)
		(end 26.126186 -65.14973)
		(width 0.1651)
		(layer "In2.Cu")
		(net "PE_RX1_DR14_N")
	)
	(segment
		(start 12.572746 -141.849094)
		(end 12.420092 -141.631416)
		(width 0.1651)
		(layer "In2.Cu")
		(net "PE_RX1_DR14_N")
	)
	(segment
		(start 30.396434 -40.928544)
		(end 29.945584 -38.370256)
		(width 0.1651)
		(layer "In2.Cu")
		(net "PE_RX1_DR14_N")
	)
	(segment
		(start 28.882086 -48.435514)
		(end 29.099764 -48.28286)
		(width 0.1651)
		(layer "In2.Cu")
		(net "PE_RX1_DR14_N")
	)
	(segment
		(start 12.48664 -142.336774)
		(end 12.572746 -141.849094)
		(width 0.1651)
		(layer "In2.Cu")
		(net "PE_RX1_DR14_N")
	)
	(segment
		(start 26.126186 -65.14973)
		(end 28.242768 -53.142896)
		(width 0.1651)
		(layer "In2.Cu")
		(net "PE_RX1_DR14_N")
	)
	(segment
		(start 12.268962 -142.489428)
		(end 12.48664 -142.336774)
		(width 0.1651)
		(layer "In2.Cu")
		(net "PE_RX1_DR14_N")
	)
	(segment
		(start 12.420092 -141.631416)
		(end 12.506198 -141.143736)
		(width 0.1651)
		(layer "In2.Cu")
		(net "PE_RX1_DR14_N")
	)
	(segment
		(start 28.94838 -49.140872)
		(end 28.948634 -49.140872)
		(width 0.1651)
		(layer "In2.Cu")
		(net "PE_RX1_DR14_N")
	)
	(segment
		(start 29.337508 -46.936914)
		(end 29.337508 -46.93666)
		(width 0.1651)
		(layer "In2.Cu")
		(net "PE_RX1_DR14_N")
	)
	(segment
		(start 12.809728 -140.503148)
		(end 12.809982 -140.503148)
		(width 0.1651)
		(layer "In2.Cu")
		(net "PE_RX1_DR14_N")
	)
	(segment
		(start 12.809982 -140.503148)
		(end 6.472174 -104.557576)
		(width 0.1651)
		(layer "In2.Cu")
		(net "PE_RX1_DR14_N")
	)
	(segment
		(start 11.135106 -148.918168)
		(end 11.221212 -148.430488)
		(width 0.1651)
		(layer "In2.Cu")
		(net "PE_RX1_DR14_N")
	)
	(segment
		(start 29.307536 -37.459158)
		(end 28.786836 -37.094414)
		(width 0.1651)
		(layer "In2.Cu")
		(net "PE_RX1_DR14_N")
	)
	(segment
		(start 29.119322 -47.089568)
		(end 29.337 -46.937168)
		(width 0.1651)
		(layer "In2.Cu")
		(net "PE_RX1_DR14_N")
	)
	(segment
		(start 11.43889 -148.278088)
		(end 12.33551 -143.194786)
		(width 0.1651)
		(layer "In2.Cu")
		(net "PE_RX1_DR14_N")
	)
	(segment
		(start 25.654 -36.787582)
		(end 25.273 -37.168582)
		(width 0.1651)
		(layer "In2.Cu")
		(net "PE_RX1_DR14_N")
	)
	(segment
		(start 6.472174 -104.557576)
		(end 9.141714 -89.405968)
		(width 0.1651)
		(layer "In2.Cu")
		(net "PE_RX1_DR14_N")
	)
	(segment
		(start 29.337508 -46.93666)
		(end 29.337254 -46.93666)
		(width 0.1651)
		(layer "In2.Cu")
		(net "PE_RX1_DR14_N")
	)
	(segment
		(start 12.182856 -142.977108)
		(end 12.268962 -142.489428)
		(width 0.1651)
		(layer "In2.Cu")
		(net "PE_RX1_DR14_N")
	)
	(segment
		(start 29.337254 -46.93666)
		(end 30.396434 -40.928544)
		(width 0.1651)
		(layer "In2.Cu")
		(net "PE_RX1_DR14_N")
	)
	(segment
		(start 8.865362 -154.410664)
		(end 9.759442 -153.784808)
		(width 0.1651)
		(layer "In2.Cu")
		(net "PE_RX1_DR14_N")
	)
	(segment
		(start 5.08 -154.33548)
		(end 5.308854 -154.564334)
		(width 0.1651)
		(layer "In2.Cu")
		(net "PE_RX1_DR14_N")
	)
	(segment
		(start 11.28776 -149.1361)
		(end 11.135106 -148.918168)
		(width 0.1651)
		(layer "In2.Cu")
		(net "PE_RX1_DR14_N")
	)
	(segment
		(start 12.809982 -140.503402)
		(end 12.809728 -140.503148)
		(width 0.1651)
		(layer "In2.Cu")
		(net "PE_RX1_DR14_N")
	)
	(segment
		(start 10.660634 -151.609552)
		(end 10.74674 -151.121872)
		(width 0.1651)
		(layer "In2.Cu")
		(net "PE_RX1_DR14_N")
	)
	(segment
		(start 10.812526 -151.830786)
		(end 10.813288 -151.827484)
		(width 0.1651)
		(layer "In2.Cu")
		(net "PE_RX1_DR14_N")
	)
	(segment
		(start 29.033216 -47.577248)
		(end 29.119322 -47.089568)
		(width 0.1651)
		(layer "In2.Cu")
		(net "PE_RX1_DR14_N")
	)
	(segment
		(start 11.201654 -149.62378)
		(end 11.28776 -149.1361)
		(width 0.1651)
		(layer "In2.Cu")
		(net "PE_RX1_DR14_N")
	)
	(segment
		(start 7.993888 -154.564334)
		(end 8.865362 -154.410664)
		(width 0.1651)
		(layer "In2.Cu")
		(net "PE_RX1_DR14_N")
	)
	(segment
		(start 24.104346 -139.420346)
		(end 23.894034 -139.210034)
		(width 0.174752)
		(layer "F.Cu")
		(net "PE_RX1_DR13_P")
	)
	(segment
		(start 23.894034 -139.210034)
		(end 22.800056 -139.210034)
		(width 0.174752)
		(layer "F.Cu")
		(net "PE_RX1_DR13_P")
	)
	(segment
		(start 25.273 -139.05103)
		(end 24.903684 -139.420346)
		(width 0.174752)
		(layer "F.Cu")
		(net "PE_RX1_DR13_P")
	)
	(segment
		(start 24.903684 -139.420346)
		(end 24.104346 -139.420346)
		(width 0.174752)
		(layer "F.Cu")
		(net "PE_RX1_DR13_P")
	)
	(via
		(at 5.08 -167.948102)
		(size 0.508)
		(drill 0.254)
		(layers "F.Cu" "B.Cu")
		(net "PE_RX1_DR13_P")
	)
	(via
		(at 25.273 -139.05103)
		(size 0.508)
		(drill 0.254)
		(layers "F.Cu" "B.Cu")
		(net "PE_RX1_DR13_P")
	)
	(segment
		(start 3.658108 -167.942006)
		(end 3.905504 -167.69461)
		(width 0.174752)
		(layer "B.Cu")
		(net "PE_RX1_DR13_P")
	)
	(segment
		(start 3.905504 -167.69461)
		(end 4.826508 -167.69461)
		(width 0.174752)
		(layer "B.Cu")
		(net "PE_RX1_DR13_P")
	)
	(segment
		(start 4.826508 -167.69461)
		(end 5.08 -167.948102)
		(width 0.174752)
		(layer "B.Cu")
		(net "PE_RX1_DR13_P")
	)
	(segment
		(start 1.868932 -167.942006)
		(end 3.658108 -167.942006)
		(width 0.174752)
		(layer "B.Cu")
		(net "PE_RX1_DR13_P")
	)
	(segment
		(start 24.900382 -137.79754)
		(end 21.968968 -138.389106)
		(width 0.1651)
		(layer "In2.Cu")
		(net "PE_RX1_DR13_P")
	)
	(segment
		(start 25.825196 -153.079704)
		(end 25.672796 -153.297382)
		(width 0.1651)
		(layer "In2.Cu")
		(net "PE_RX1_DR13_P")
	)
	(segment
		(start 15.314676 -169.732198)
		(end 14.826996 -169.646092)
		(width 0.1651)
		(layer "In2.Cu")
		(net "PE_RX1_DR13_P")
	)
	(segment
		(start 26.389838 -138.388852)
		(end 25.910286 -138.10107)
		(width 0.1651)
		(layer "In2.Cu")
		(net "PE_RX1_DR13_P")
	)
	(segment
		(start 20.627848 -141.1224)
		(end 20.845526 -141.2748)
		(width 0.1651)
		(layer "In2.Cu")
		(net "PE_RX1_DR13_P")
	)
	(segment
		(start 13.968984 -169.494962)
		(end 13.481304 -169.408856)
		(width 0.1651)
		(layer "In2.Cu")
		(net "PE_RX1_DR13_P")
	)
	(segment
		(start 9.709912 -168.178226)
		(end 7.143242 -167.72001)
		(width 0.1651)
		(layer "In2.Cu")
		(net "PE_RX1_DR13_P")
	)
	(segment
		(start 21.083016 -142.620492)
		(end 21.169122 -143.108426)
		(width 0.1651)
		(layer "In2.Cu")
		(net "PE_RX1_DR13_P")
	)
	(segment
		(start 25.672796 -153.297382)
		(end 25.768554 -153.840434)
		(width 0.1651)
		(layer "In2.Cu")
		(net "PE_RX1_DR13_P")
	)
	(segment
		(start 25.61717 -139.3952)
		(end 26.3652 -139.3952)
		(width 0.1651)
		(layer "In2.Cu")
		(net "PE_RX1_DR13_P")
	)
	(segment
		(start 20.931632 -141.762734)
		(end 20.779232 -141.980412)
		(width 0.1651)
		(layer "In2.Cu")
		(net "PE_RX1_DR13_P")
	)
	(segment
		(start 26.6192 -139.1412)
		(end 26.6192 -138.78179)
		(width 0.1651)
		(layer "In2.Cu")
		(net "PE_RX1_DR13_P")
	)
	(segment
		(start 12.775946 -169.475404)
		(end 12.623292 -169.257726)
		(width 0.1651)
		(layer "In2.Cu")
		(net "PE_RX1_DR13_P")
	)
	(segment
		(start 14.609318 -169.798746)
		(end 14.121638 -169.71264)
		(width 0.1651)
		(layer "In2.Cu")
		(net "PE_RX1_DR13_P")
	)
	(segment
		(start 5.308092 -167.72001)
		(end 5.08 -167.948102)
		(width 0.1651)
		(layer "In2.Cu")
		(net "PE_RX1_DR13_P")
	)
	(segment
		(start 22.734524 -169.165524)
		(end 22.073108 -169.628566)
		(width 0.1651)
		(layer "In2.Cu")
		(net "PE_RX1_DR13_P")
	)
	(segment
		(start 11.917934 -169.32402)
		(end 11.430254 -169.238168)
		(width 0.1651)
		(layer "In2.Cu")
		(net "PE_RX1_DR13_P")
	)
	(segment
		(start 15.95501 -170.035982)
		(end 15.46733 -169.949876)
		(width 0.1651)
		(layer "In2.Cu")
		(net "PE_RX1_DR13_P")
	)
	(segment
		(start 25.768554 -153.840434)
		(end 23.178008 -168.531794)
		(width 0.1651)
		(layer "In2.Cu")
		(net "PE_RX1_DR13_P")
	)
	(segment
		(start 22.073108 -169.628566)
		(end 18.401792 -170.27652)
		(width 0.1651)
		(layer "In2.Cu")
		(net "PE_RX1_DR13_P")
	)
	(segment
		(start 10.78992 -168.934384)
		(end 9.709912 -168.178226)
		(width 0.1651)
		(layer "In2.Cu")
		(net "PE_RX1_DR13_P")
	)
	(segment
		(start 25.521666 -152.43937)
		(end 25.739344 -152.592024)
		(width 0.1651)
		(layer "In2.Cu")
		(net "PE_RX1_DR13_P")
	)
	(segment
		(start 25.43556 -151.95169)
		(end 25.521666 -152.43937)
		(width 0.1651)
		(layer "In2.Cu")
		(net "PE_RX1_DR13_P")
	)
	(segment
		(start 12.135612 -169.17162)
		(end 11.917934 -169.32402)
		(width 0.1651)
		(layer "In2.Cu")
		(net "PE_RX1_DR13_P")
	)
	(segment
		(start 11.430254 -169.238168)
		(end 11.2776 -169.02049)
		(width 0.1651)
		(layer "In2.Cu")
		(net "PE_RX1_DR13_P")
	)
	(segment
		(start 21.968968 -138.389106)
		(end 21.375624 -138.809476)
		(width 0.1651)
		(layer "In2.Cu")
		(net "PE_RX1_DR13_P")
	)
	(segment
		(start 20.845526 -141.2748)
		(end 20.931632 -141.762734)
		(width 0.1651)
		(layer "In2.Cu")
		(net "PE_RX1_DR13_P")
	)
	(segment
		(start 14.826996 -169.646092)
		(end 14.609318 -169.798746)
		(width 0.1651)
		(layer "In2.Cu")
		(net "PE_RX1_DR13_P")
	)
	(segment
		(start 25.910286 -138.10107)
		(end 24.900382 -137.79754)
		(width 0.1651)
		(layer "In2.Cu")
		(net "PE_RX1_DR13_P")
	)
	(segment
		(start 15.46733 -169.949876)
		(end 15.314676 -169.732198)
		(width 0.1651)
		(layer "In2.Cu")
		(net "PE_RX1_DR13_P")
	)
	(segment
		(start 25.502108 -151.246078)
		(end 25.58796 -151.733758)
		(width 0.1651)
		(layer "In2.Cu")
		(net "PE_RX1_DR13_P")
	)
	(segment
		(start 23.178008 -168.531794)
		(end 22.734524 -169.165524)
		(width 0.1651)
		(layer "In2.Cu")
		(net "PE_RX1_DR13_P")
	)
	(segment
		(start 21.169122 -143.108426)
		(end 21.016722 -143.326104)
		(width 0.1651)
		(layer "In2.Cu")
		(net "PE_RX1_DR13_P")
	)
	(segment
		(start 16.172688 -169.883328)
		(end 15.95501 -170.035982)
		(width 0.1651)
		(layer "In2.Cu")
		(net "PE_RX1_DR13_P")
	)
	(segment
		(start 12.623292 -169.257726)
		(end 12.135612 -169.17162)
		(width 0.1651)
		(layer "In2.Cu")
		(net "PE_RX1_DR13_P")
	)
	(segment
		(start 23.666196 -146.853402)
		(end 24.829516 -148.515324)
		(width 0.1651)
		(layer "In2.Cu")
		(net "PE_RX1_DR13_P")
	)
	(segment
		(start 21.375624 -138.809476)
		(end 20.90547 -139.544044)
		(width 0.1651)
		(layer "In2.Cu")
		(net "PE_RX1_DR13_P")
	)
	(segment
		(start 25.739344 -152.592024)
		(end 25.825196 -153.079704)
		(width 0.1651)
		(layer "In2.Cu")
		(net "PE_RX1_DR13_P")
	)
	(segment
		(start 26.3652 -139.3952)
		(end 26.6192 -139.1412)
		(width 0.1651)
		(layer "In2.Cu")
		(net "PE_RX1_DR13_P")
	)
	(segment
		(start 20.865338 -142.468092)
		(end 21.083016 -142.620492)
		(width 0.1651)
		(layer "In2.Cu")
		(net "PE_RX1_DR13_P")
	)
	(segment
		(start 21.668994 -145.454878)
		(end 23.666196 -146.853402)
		(width 0.1651)
		(layer "In2.Cu")
		(net "PE_RX1_DR13_P")
	)
	(segment
		(start 26.6192 -138.78179)
		(end 26.389838 -138.388852)
		(width 0.1651)
		(layer "In2.Cu")
		(net "PE_RX1_DR13_P")
	)
	(segment
		(start 24.829516 -148.515324)
		(end 25.284176 -151.093678)
		(width 0.1651)
		(layer "In2.Cu")
		(net "PE_RX1_DR13_P")
	)
	(segment
		(start 20.541742 -140.63472)
		(end 20.627848 -141.1224)
		(width 0.1651)
		(layer "In2.Cu")
		(net "PE_RX1_DR13_P")
	)
	(segment
		(start 13.481304 -169.408856)
		(end 13.263626 -169.561256)
		(width 0.1651)
		(layer "In2.Cu")
		(net "PE_RX1_DR13_P")
	)
	(segment
		(start 25.58796 -151.733758)
		(end 25.43556 -151.95169)
		(width 0.1651)
		(layer "In2.Cu")
		(net "PE_RX1_DR13_P")
	)
	(segment
		(start 21.016722 -143.326104)
		(end 21.29917 -144.927066)
		(width 0.1651)
		(layer "In2.Cu")
		(net "PE_RX1_DR13_P")
	)
	(segment
		(start 25.273 -139.05103)
		(end 25.61717 -139.3952)
		(width 0.1651)
		(layer "In2.Cu")
		(net "PE_RX1_DR13_P")
	)
	(segment
		(start 25.284176 -151.093678)
		(end 25.502108 -151.246078)
		(width 0.1651)
		(layer "In2.Cu")
		(net "PE_RX1_DR13_P")
	)
	(segment
		(start 14.121638 -169.71264)
		(end 13.968984 -169.494962)
		(width 0.1651)
		(layer "In2.Cu")
		(net "PE_RX1_DR13_P")
	)
	(segment
		(start 7.143242 -167.72001)
		(end 5.308092 -167.72001)
		(width 0.1651)
		(layer "In2.Cu")
		(net "PE_RX1_DR13_P")
	)
	(segment
		(start 11.2776 -169.02049)
		(end 10.78992 -168.934384)
		(width 0.1651)
		(layer "In2.Cu")
		(net "PE_RX1_DR13_P")
	)
	(segment
		(start 18.401792 -170.27652)
		(end 16.172688 -169.883328)
		(width 0.1651)
		(layer "In2.Cu")
		(net "PE_RX1_DR13_P")
	)
	(segment
		(start 21.29917 -144.927066)
		(end 21.668994 -145.454878)
		(width 0.1651)
		(layer "In2.Cu")
		(net "PE_RX1_DR13_P")
	)
	(segment
		(start 13.263626 -169.561256)
		(end 12.775946 -169.475404)
		(width 0.1651)
		(layer "In2.Cu")
		(net "PE_RX1_DR13_P")
	)
	(segment
		(start 20.779232 -141.980412)
		(end 20.865338 -142.468092)
		(width 0.1651)
		(layer "In2.Cu")
		(net "PE_RX1_DR13_P")
	)
	(segment
		(start 20.90547 -139.544044)
		(end 20.541742 -140.63472)
		(width 0.1651)
		(layer "In2.Cu")
		(net "PE_RX1_DR13_P")
	)
	(segment
		(start 24.167084 -139.7254)
		(end 23.882604 -140.00988)
		(width 0.174752)
		(layer "F.Cu")
		(net "PE_RX1_DR13_N")
	)
	(segment
		(start 23.882604 -140.00988)
		(end 22.800056 -140.00988)
		(width 0.174752)
		(layer "F.Cu")
		(net "PE_RX1_DR13_N")
	)
	(segment
		(start 25.273 -140.16863)
		(end 24.82977 -139.7254)
		(width 0.174752)
		(layer "F.Cu")
		(net "PE_RX1_DR13_N")
	)
	(segment
		(start 24.82977 -139.7254)
		(end 24.167084 -139.7254)
		(width 0.174752)
		(layer "F.Cu")
		(net "PE_RX1_DR13_N")
	)
	(via
		(at 5.08 -167.135302)
		(size 0.508)
		(drill 0.254)
		(layers "F.Cu" "B.Cu")
		(net "PE_RX1_DR13_N")
	)
	(via
		(at 25.273 -140.16863)
		(size 0.508)
		(drill 0.254)
		(layers "F.Cu" "B.Cu")
		(net "PE_RX1_DR13_N")
	)
	(segment
		(start 3.905504 -167.389556)
		(end 4.825746 -167.389556)
		(width 0.174752)
		(layer "B.Cu")
		(net "PE_RX1_DR13_N")
	)
	(segment
		(start 3.658108 -167.14216)
		(end 3.905504 -167.389556)
		(width 0.174752)
		(layer "B.Cu")
		(net "PE_RX1_DR13_N")
	)
	(segment
		(start 1.868932 -167.14216)
		(end 3.658108 -167.14216)
		(width 0.174752)
		(layer "B.Cu")
		(net "PE_RX1_DR13_N")
	)
	(segment
		(start 4.825746 -167.389556)
		(end 5.08 -167.135302)
		(width 0.174752)
		(layer "B.Cu")
		(net "PE_RX1_DR13_N")
	)
	(segment
		(start 9.849612 -167.84193)
		(end 7.174738 -167.36441)
		(width 0.1651)
		(layer "In2.Cu")
		(net "PE_RX1_DR13_N")
	)
	(segment
		(start 5.309108 -167.36441)
		(end 5.08 -167.135302)
		(width 0.1651)
		(layer "In2.Cu")
		(net "PE_RX1_DR13_N")
	)
	(segment
		(start 21.113496 -138.559286)
		(end 20.581874 -139.389612)
		(width 0.1651)
		(layer "In2.Cu")
		(net "PE_RX1_DR13_N")
	)
	(segment
		(start 24.492966 -148.65477)
		(end 25.407366 -153.840434)
		(width 0.1651)
		(layer "In2.Cu")
		(net "PE_RX1_DR13_N")
	)
	(segment
		(start 20.96262 -145.066512)
		(end 21.41347 -145.710402)
		(width 0.1651)
		(layer "In2.Cu")
		(net "PE_RX1_DR13_N")
	)
	(segment
		(start 22.841458 -168.392348)
		(end 22.479 -168.91)
		(width 0.1651)
		(layer "In2.Cu")
		(net "PE_RX1_DR13_N")
	)
	(segment
		(start 7.174738 -167.36441)
		(end 5.309108 -167.36441)
		(width 0.1651)
		(layer "In2.Cu")
		(net "PE_RX1_DR13_N")
	)
	(segment
		(start 10.929366 -168.597834)
		(end 9.849612 -167.84193)
		(width 0.1651)
		(layer "In2.Cu")
		(net "PE_RX1_DR13_N")
	)
	(segment
		(start 23.410672 -147.108926)
		(end 24.492966 -148.65477)
		(width 0.1651)
		(layer "In2.Cu")
		(net "PE_RX1_DR13_N")
	)
	(segment
		(start 26.651204 -138.130788)
		(end 26.05532 -137.773156)
		(width 0.1651)
		(layer "In2.Cu")
		(net "PE_RX1_DR13_N")
	)
	(segment
		(start 22.479 -168.91)
		(end 21.933662 -169.292016)
		(width 0.1651)
		(layer "In2.Cu")
		(net "PE_RX1_DR13_N")
	)
	(segment
		(start 20.175728 -140.607796)
		(end 20.96262 -145.066512)
		(width 0.1651)
		(layer "In2.Cu")
		(net "PE_RX1_DR13_N")
	)
	(segment
		(start 21.41347 -145.710402)
		(end 23.410672 -147.108926)
		(width 0.1651)
		(layer "In2.Cu")
		(net "PE_RX1_DR13_N")
	)
	(segment
		(start 25.273 -140.16863)
		(end 25.69083 -139.7508)
		(width 0.1651)
		(layer "In2.Cu")
		(net "PE_RX1_DR13_N")
	)
	(segment
		(start 18.4023 -169.915078)
		(end 10.929366 -168.597834)
		(width 0.1651)
		(layer "In2.Cu")
		(net "PE_RX1_DR13_N")
	)
	(segment
		(start 20.581874 -139.389612)
		(end 20.175728 -140.607796)
		(width 0.1651)
		(layer "In2.Cu")
		(net "PE_RX1_DR13_N")
	)
	(segment
		(start 21.824696 -138.055096)
		(end 21.113496 -138.559286)
		(width 0.1651)
		(layer "In2.Cu")
		(net "PE_RX1_DR13_N")
	)
	(segment
		(start 25.407366 -153.840434)
		(end 22.841458 -168.392348)
		(width 0.1651)
		(layer "In2.Cu")
		(net "PE_RX1_DR13_N")
	)
	(segment
		(start 26.51252 -139.7508)
		(end 26.9748 -139.28852)
		(width 0.1651)
		(layer "In2.Cu")
		(net "PE_RX1_DR13_N")
	)
	(segment
		(start 26.05532 -137.773156)
		(end 24.9174 -137.431272)
		(width 0.1651)
		(layer "In2.Cu")
		(net "PE_RX1_DR13_N")
	)
	(segment
		(start 24.9174 -137.431272)
		(end 21.824696 -138.055096)
		(width 0.1651)
		(layer "In2.Cu")
		(net "PE_RX1_DR13_N")
	)
	(segment
		(start 26.9748 -139.28852)
		(end 26.9748 -138.685524)
		(width 0.1651)
		(layer "In2.Cu")
		(net "PE_RX1_DR13_N")
	)
	(segment
		(start 21.933662 -169.292016)
		(end 18.4023 -169.915078)
		(width 0.1651)
		(layer "In2.Cu")
		(net "PE_RX1_DR13_N")
	)
	(segment
		(start 26.9748 -138.685524)
		(end 26.651204 -138.130788)
		(width 0.1651)
		(layer "In2.Cu")
		(net "PE_RX1_DR13_N")
	)
	(segment
		(start 25.69083 -139.7508)
		(end 26.51252 -139.7508)
		(width 0.1651)
		(layer "In2.Cu")
		(net "PE_RX1_DR13_N")
	)
	(segment
		(start 22.800056 -242.210082)
		(end 23.876 -242.210082)
		(width 0.174752)
		(layer "F.Cu")
		(net "PE_RX1_DR12_P")
	)
	(segment
		(start 24.123396 -242.457478)
		(end 24.8666 -242.457478)
		(width 0.174752)
		(layer "F.Cu")
		(net "PE_RX1_DR12_P")
	)
	(segment
		(start 24.8666 -242.457478)
		(end 25.273 -242.051078)
		(width 0.174752)
		(layer "F.Cu")
		(net "PE_RX1_DR12_P")
	)
	(segment
		(start 23.876 -242.210082)
		(end 24.123396 -242.457478)
		(width 0.174752)
		(layer "F.Cu")
		(net "PE_RX1_DR12_P")
	)
	(via
		(at 5.08 -213.548214)
		(size 0.508)
		(drill 0.254)
		(layers "F.Cu" "B.Cu")
		(net "PE_RX1_DR12_P")
	)
	(via
		(at 25.273 -242.051078)
		(size 0.508)
		(drill 0.254)
		(layers "F.Cu" "B.Cu")
		(net "PE_RX1_DR12_P")
	)
	(segment
		(start 3.992372 -213.294468)
		(end 4.826254 -213.294468)
		(width 0.174752)
		(layer "B.Cu")
		(net "PE_RX1_DR12_P")
	)
	(segment
		(start 1.868932 -213.542118)
		(end 3.744722 -213.542118)
		(width 0.174752)
		(layer "B.Cu")
		(net "PE_RX1_DR12_P")
	)
	(segment
		(start 3.744722 -213.542118)
		(end 3.992372 -213.294468)
		(width 0.174752)
		(layer "B.Cu")
		(net "PE_RX1_DR12_P")
	)
	(segment
		(start 4.826254 -213.294468)
		(end 5.08 -213.548214)
		(width 0.174752)
		(layer "B.Cu")
		(net "PE_RX1_DR12_P")
	)
	(segment
		(start 10.43051 -211.349336)
		(end 10.692384 -211.395564)
		(width 0.1651)
		(layer "In2.Cu")
		(net "PE_RX1_DR12_P")
	)
	(segment
		(start 28.076652 -240.903252)
		(end 27.792426 -241.30889)
		(width 0.1651)
		(layer "In2.Cu")
		(net "PE_RX1_DR12_P")
	)
	(segment
		(start 30.418024 -232.714546)
		(end 30.200346 -232.8672)
		(width 0.1651)
		(layer "In2.Cu")
		(net "PE_RX1_DR12_P")
	)
	(segment
		(start 13.571728 -205.70952)
		(end 16.966438 -200.861422)
		(width 0.1651)
		(layer "In2.Cu")
		(net "PE_RX1_DR12_P")
	)
	(segment
		(start 8.859266 -212.679026)
		(end 8.905494 -212.417152)
		(width 0.1651)
		(layer "In2.Cu")
		(net "PE_RX1_DR12_P")
	)
	(segment
		(start 27.838654 -241.570764)
		(end 27.554428 -241.976402)
		(width 0.1651)
		(layer "In2.Cu")
		(net "PE_RX1_DR12_P")
	)
	(segment
		(start 44.298616 -212.525356)
		(end 30.50413 -232.226866)
		(width 0.1651)
		(layer "In2.Cu")
		(net "PE_RX1_DR12_P")
	)
	(segment
		(start 44.868084 -209.296)
		(end 44.298616 -212.525356)
		(width 0.1651)
		(layer "In2.Cu")
		(net "PE_RX1_DR12_P")
	)
	(segment
		(start 8.191754 -212.917024)
		(end 8.453628 -212.962998)
		(width 0.1651)
		(layer "In2.Cu")
		(net "PE_RX1_DR12_P")
	)
	(segment
		(start 5.08 -213.548214)
		(end 5.308346 -213.319868)
		(width 0.1651)
		(layer "In2.Cu")
		(net "PE_RX1_DR12_P")
	)
	(segment
		(start 29.198824 -239.628426)
		(end 28.338272 -240.857024)
		(width 0.1651)
		(layer "In2.Cu")
		(net "PE_RX1_DR12_P")
	)
	(segment
		(start 39.373556 -201.614532)
		(end 42.644568 -203.905104)
		(width 0.1651)
		(layer "In2.Cu")
		(net "PE_RX1_DR12_P")
	)
	(segment
		(start 26.986992 -242.373658)
		(end 26.655014 -242.432078)
		(width 0.1651)
		(layer "In2.Cu")
		(net "PE_RX1_DR12_P")
	)
	(segment
		(start 9.978644 -211.895182)
		(end 10.024872 -211.633308)
		(width 0.1651)
		(layer "In2.Cu")
		(net "PE_RX1_DR12_P")
	)
	(segment
		(start 8.453628 -212.962998)
		(end 8.859266 -212.679026)
		(width 0.1651)
		(layer "In2.Cu")
		(net "PE_RX1_DR12_P")
	)
	(segment
		(start 30.266894 -233.572558)
		(end 30.180788 -234.060492)
		(width 0.1651)
		(layer "In2.Cu")
		(net "PE_RX1_DR12_P")
	)
	(segment
		(start 29.639768 -236.046264)
		(end 29.792168 -236.264196)
		(width 0.1651)
		(layer "In2.Cu")
		(net "PE_RX1_DR12_P")
	)
	(segment
		(start 7.786116 -213.200996)
		(end 8.191754 -212.917024)
		(width 0.1651)
		(layer "In2.Cu")
		(net "PE_RX1_DR12_P")
	)
	(segment
		(start 44.34586 -206.33436)
		(end 44.868084 -209.296)
		(width 0.1651)
		(layer "In2.Cu")
		(net "PE_RX1_DR12_P")
	)
	(segment
		(start 7.112 -213.319868)
		(end 7.786116 -213.200996)
		(width 0.1651)
		(layer "In2.Cu")
		(net "PE_RX1_DR12_P")
	)
	(segment
		(start 22.71141 -198.677022)
		(end 24.7777 -199.041258)
		(width 0.1651)
		(layer "In2.Cu")
		(net "PE_RX1_DR12_P")
	)
	(segment
		(start 42.644568 -203.905104)
		(end 44.34586 -206.33436)
		(width 0.1651)
		(layer "In2.Cu")
		(net "PE_RX1_DR12_P")
	)
	(segment
		(start 19.202654 -199.295512)
		(end 22.71141 -198.677022)
		(width 0.1651)
		(layer "In2.Cu")
		(net "PE_RX1_DR12_P")
	)
	(segment
		(start 11.14425 -210.849464)
		(end 12.112244 -210.171792)
		(width 0.1651)
		(layer "In2.Cu")
		(net "PE_RX1_DR12_P")
	)
	(segment
		(start 29.877004 -234.700572)
		(end 30.029404 -234.91825)
		(width 0.1651)
		(layer "In2.Cu")
		(net "PE_RX1_DR12_P")
	)
	(segment
		(start 10.024872 -211.633308)
		(end 10.43051 -211.349336)
		(width 0.1651)
		(layer "In2.Cu")
		(net "PE_RX1_DR12_P")
	)
	(segment
		(start 28.338272 -240.857024)
		(end 28.076652 -240.903252)
		(width 0.1651)
		(layer "In2.Cu")
		(net "PE_RX1_DR12_P")
	)
	(segment
		(start 8.905494 -212.417152)
		(end 9.311132 -212.13318)
		(width 0.1651)
		(layer "In2.Cu")
		(net "PE_RX1_DR12_P")
	)
	(segment
		(start 9.311132 -212.13318)
		(end 9.573006 -212.179154)
		(width 0.1651)
		(layer "In2.Cu")
		(net "PE_RX1_DR12_P")
	)
	(segment
		(start 30.11424 -233.35488)
		(end 30.266894 -233.572558)
		(width 0.1651)
		(layer "In2.Cu")
		(net "PE_RX1_DR12_P")
	)
	(segment
		(start 5.308346 -213.319868)
		(end 7.112 -213.319868)
		(width 0.1651)
		(layer "In2.Cu")
		(net "PE_RX1_DR12_P")
	)
	(segment
		(start 12.112244 -210.171792)
		(end 13.01115 -208.888076)
		(width 0.1651)
		(layer "In2.Cu")
		(net "PE_RX1_DR12_P")
	)
	(segment
		(start 16.966438 -200.861422)
		(end 19.202654 -199.295512)
		(width 0.1651)
		(layer "In2.Cu")
		(net "PE_RX1_DR12_P")
	)
	(segment
		(start 30.180788 -234.060492)
		(end 29.96311 -234.212892)
		(width 0.1651)
		(layer "In2.Cu")
		(net "PE_RX1_DR12_P")
	)
	(segment
		(start 30.50413 -232.226866)
		(end 30.418024 -232.714546)
		(width 0.1651)
		(layer "In2.Cu")
		(net "PE_RX1_DR12_P")
	)
	(segment
		(start 10.692384 -211.395564)
		(end 11.098022 -211.111338)
		(width 0.1651)
		(layer "In2.Cu")
		(net "PE_RX1_DR12_P")
	)
	(segment
		(start 29.72562 -235.558584)
		(end 29.639768 -236.046264)
		(width 0.1651)
		(layer "In2.Cu")
		(net "PE_RX1_DR12_P")
	)
	(segment
		(start 30.200346 -232.8672)
		(end 30.11424 -233.35488)
		(width 0.1651)
		(layer "In2.Cu")
		(net "PE_RX1_DR12_P")
	)
	(segment
		(start 9.573006 -212.179154)
		(end 9.978644 -211.895182)
		(width 0.1651)
		(layer "In2.Cu")
		(net "PE_RX1_DR12_P")
	)
	(segment
		(start 29.96311 -234.212892)
		(end 29.877004 -234.700572)
		(width 0.1651)
		(layer "In2.Cu")
		(net "PE_RX1_DR12_P")
	)
	(segment
		(start 11.098022 -211.111338)
		(end 11.14425 -210.849464)
		(width 0.1651)
		(layer "In2.Cu")
		(net "PE_RX1_DR12_P")
	)
	(segment
		(start 13.01115 -208.888076)
		(end 13.571728 -205.70952)
		(width 0.1651)
		(layer "In2.Cu")
		(net "PE_RX1_DR12_P")
	)
	(segment
		(start 29.943298 -235.406184)
		(end 29.72562 -235.558584)
		(width 0.1651)
		(layer "In2.Cu")
		(net "PE_RX1_DR12_P")
	)
	(segment
		(start 26.655014 -242.432078)
		(end 25.654 -242.432078)
		(width 0.1651)
		(layer "In2.Cu")
		(net "PE_RX1_DR12_P")
	)
	(segment
		(start 27.792426 -241.30889)
		(end 27.838654 -241.570764)
		(width 0.1651)
		(layer "In2.Cu")
		(net "PE_RX1_DR12_P")
	)
	(segment
		(start 27.554428 -241.976402)
		(end 26.986992 -242.373658)
		(width 0.1651)
		(layer "In2.Cu")
		(net "PE_RX1_DR12_P")
	)
	(segment
		(start 25.654 -242.432078)
		(end 25.273 -242.051078)
		(width 0.1651)
		(layer "In2.Cu")
		(net "PE_RX1_DR12_P")
	)
	(segment
		(start 29.792168 -236.264196)
		(end 29.198824 -239.628426)
		(width 0.1651)
		(layer "In2.Cu")
		(net "PE_RX1_DR12_P")
	)
	(segment
		(start 30.029404 -234.91825)
		(end 29.943298 -235.406184)
		(width 0.1651)
		(layer "In2.Cu")
		(net "PE_RX1_DR12_P")
	)
	(segment
		(start 24.7777 -199.041258)
		(end 39.373556 -201.614532)
		(width 0.1651)
		(layer "In2.Cu")
		(net "PE_RX1_DR12_P")
	)
	(segment
		(start 24.191468 -242.762532)
		(end 24.866854 -242.762532)
		(width 0.174752)
		(layer "F.Cu")
		(net "PE_RX1_DR12_N")
	)
	(segment
		(start 22.800056 -243.009928)
		(end 23.944072 -243.009928)
		(width 0.174752)
		(layer "F.Cu")
		(net "PE_RX1_DR12_N")
	)
	(segment
		(start 24.866854 -242.762532)
		(end 25.273 -243.168678)
		(width 0.174752)
		(layer "F.Cu")
		(net "PE_RX1_DR12_N")
	)
	(segment
		(start 23.944072 -243.009928)
		(end 24.191468 -242.762532)
		(width 0.174752)
		(layer "F.Cu")
		(net "PE_RX1_DR12_N")
	)
	(via
		(at 25.273 -243.168678)
		(size 0.508)
		(drill 0.254)
		(layers "F.Cu" "B.Cu")
		(net "PE_RX1_DR12_N")
	)
	(via
		(at 5.08 -212.735414)
		(size 0.508)
		(drill 0.254)
		(layers "F.Cu" "B.Cu")
		(net "PE_RX1_DR12_N")
	)
	(segment
		(start 1.868932 -212.742018)
		(end 3.658108 -212.742018)
		(width 0.174752)
		(layer "B.Cu")
		(net "PE_RX1_DR12_N")
	)
	(segment
		(start 3.658108 -212.742018)
		(end 4.00558 -212.989414)
		(width 0.174752)
		(layer "B.Cu")
		(net "PE_RX1_DR12_N")
	)
	(segment
		(start 4.826 -212.989414)
		(end 5.08 -212.735414)
		(width 0.174752)
		(layer "B.Cu")
		(net "PE_RX1_DR12_N")
	)
	(segment
		(start 4.00558 -212.989414)
		(end 4.826 -212.989414)
		(width 0.174752)
		(layer "B.Cu")
		(net "PE_RX1_DR12_N")
	)
	(segment
		(start 19.063208 -198.958962)
		(end 16.710914 -200.605898)
		(width 0.1651)
		(layer "In2.Cu")
		(net "PE_RX1_DR12_N")
	)
	(segment
		(start 27.126438 -242.710208)
		(end 27.809952 -242.231926)
		(width 0.1651)
		(layer "In2.Cu")
		(net "PE_RX1_DR12_N")
	)
	(segment
		(start 26.686256 -242.787678)
		(end 27.126438 -242.710208)
		(width 0.1651)
		(layer "In2.Cu")
		(net "PE_RX1_DR12_N")
	)
	(segment
		(start 30.142434 -236.325918)
		(end 30.142688 -236.325918)
		(width 0.1651)
		(layer "In2.Cu")
		(net "PE_RX1_DR12_N")
	)
	(segment
		(start 25.654 -242.787678)
		(end 26.686256 -242.787678)
		(width 0.1651)
		(layer "In2.Cu")
		(net "PE_RX1_DR12_N")
	)
	(segment
		(start 29.535374 -239.767872)
		(end 30.142434 -236.325918)
		(width 0.1651)
		(layer "In2.Cu")
		(net "PE_RX1_DR12_N")
	)
	(segment
		(start 45.229272 -209.296)
		(end 44.68241 -206.194914)
		(width 0.1651)
		(layer "In2.Cu")
		(net "PE_RX1_DR12_N")
	)
	(segment
		(start 27.809952 -242.231926)
		(end 29.535374 -239.767872)
		(width 0.1651)
		(layer "In2.Cu")
		(net "PE_RX1_DR12_N")
	)
	(segment
		(start 22.71141 -198.315834)
		(end 19.063208 -198.958962)
		(width 0.1651)
		(layer "In2.Cu")
		(net "PE_RX1_DR12_N")
	)
	(segment
		(start 12.6746 -208.74863)
		(end 11.85672 -209.916268)
		(width 0.1651)
		(layer "In2.Cu")
		(net "PE_RX1_DR12_N")
	)
	(segment
		(start 25.273 -243.168678)
		(end 25.654 -242.787678)
		(width 0.1651)
		(layer "In2.Cu")
		(net "PE_RX1_DR12_N")
	)
	(segment
		(start 44.68241 -206.194914)
		(end 42.900092 -203.64958)
		(width 0.1651)
		(layer "In2.Cu")
		(net "PE_RX1_DR12_N")
	)
	(segment
		(start 24.839676 -198.690992)
		(end 22.71141 -198.315834)
		(width 0.1651)
		(layer "In2.Cu")
		(net "PE_RX1_DR12_N")
	)
	(segment
		(start 11.85672 -209.916268)
		(end 7.64667 -212.864446)
		(width 0.1651)
		(layer "In2.Cu")
		(net "PE_RX1_DR12_N")
	)
	(segment
		(start 13.235178 -205.570074)
		(end 12.6746 -208.74863)
		(width 0.1651)
		(layer "In2.Cu")
		(net "PE_RX1_DR12_N")
	)
	(segment
		(start 5.308854 -212.964268)
		(end 5.08 -212.735414)
		(width 0.1651)
		(layer "In2.Cu")
		(net "PE_RX1_DR12_N")
	)
	(segment
		(start 7.64667 -212.864446)
		(end 7.080758 -212.964268)
		(width 0.1651)
		(layer "In2.Cu")
		(net "PE_RX1_DR12_N")
	)
	(segment
		(start 42.900092 -203.64958)
		(end 39.513002 -201.277982)
		(width 0.1651)
		(layer "In2.Cu")
		(net "PE_RX1_DR12_N")
	)
	(segment
		(start 7.080758 -212.964268)
		(end 5.308854 -212.964268)
		(width 0.1651)
		(layer "In2.Cu")
		(net "PE_RX1_DR12_N")
	)
	(segment
		(start 30.142688 -236.325918)
		(end 30.84068 -232.366312)
		(width 0.1651)
		(layer "In2.Cu")
		(net "PE_RX1_DR12_N")
	)
	(segment
		(start 16.710914 -200.605898)
		(end 13.235178 -205.570074)
		(width 0.1651)
		(layer "In2.Cu")
		(net "PE_RX1_DR12_N")
	)
	(segment
		(start 39.513002 -201.277982)
		(end 24.839676 -198.690992)
		(width 0.1651)
		(layer "In2.Cu")
		(net "PE_RX1_DR12_N")
	)
	(segment
		(start 30.84068 -232.366312)
		(end 44.635166 -212.664802)
		(width 0.1651)
		(layer "In2.Cu")
		(net "PE_RX1_DR12_N")
	)
	(segment
		(start 44.635166 -212.664802)
		(end 45.229272 -209.296)
		(width 0.1651)
		(layer "In2.Cu")
		(net "PE_RX1_DR12_N")
	)
	(segment
		(start 24.131016 -345.465146)
		(end 23.876 -345.21013)
		(width 0.174752)
		(layer "F.Cu")
		(net "PE_RX1_DR11_P")
	)
	(segment
		(start 23.876 -345.21013)
		(end 22.800056 -345.21013)
		(width 0.174752)
		(layer "F.Cu")
		(net "PE_RX1_DR11_P")
	)
	(segment
		(start 24.85898 -345.465146)
		(end 24.131016 -345.465146)
		(width 0.174752)
		(layer "F.Cu")
		(net "PE_RX1_DR11_P")
	)
	(segment
		(start 25.273 -345.051126)
		(end 24.85898 -345.465146)
		(width 0.174752)
		(layer "F.Cu")
		(net "PE_RX1_DR11_P")
	)
	(via
		(at 5.08 -336.348324)
		(size 0.508)
		(drill 0.254)
		(layers "F.Cu" "B.Cu")
		(net "PE_RX1_DR11_P")
	)
	(via
		(at 25.273 -345.051126)
		(size 0.508)
		(drill 0.254)
		(layers "F.Cu" "B.Cu")
		(net "PE_RX1_DR11_P")
	)
	(segment
		(start 3.905504 -336.094578)
		(end 4.826254 -336.094578)
		(width 0.174752)
		(layer "B.Cu")
		(net "PE_RX1_DR11_P")
	)
	(segment
		(start 4.826254 -336.094578)
		(end 5.08 -336.348324)
		(width 0.174752)
		(layer "B.Cu")
		(net "PE_RX1_DR11_P")
	)
	(segment
		(start 3.657854 -336.342228)
		(end 3.905504 -336.094578)
		(width 0.174752)
		(layer "B.Cu")
		(net "PE_RX1_DR11_P")
	)
	(segment
		(start 1.868932 -336.342228)
		(end 3.657854 -336.342228)
		(width 0.174752)
		(layer "B.Cu")
		(net "PE_RX1_DR11_P")
	)
	(segment
		(start 24.736806 -343.826084)
		(end 19.569176 -344.962988)
		(width 0.1651)
		(layer "In2.Cu")
		(net "PE_RX1_DR11_P")
	)
	(segment
		(start 7.080758 -336.119978)
		(end 5.308346 -336.119978)
		(width 0.1651)
		(layer "In2.Cu")
		(net "PE_RX1_DR11_P")
	)
	(segment
		(start 12.693396 -340.138004)
		(end 12.73937 -339.87613)
		(width 0.1651)
		(layer "In2.Cu")
		(net "PE_RX1_DR11_P")
	)
	(segment
		(start 8.355838 -336.811112)
		(end 8.30961 -336.549238)
		(width 0.1651)
		(layer "In2.Cu")
		(net "PE_RX1_DR11_P")
	)
	(segment
		(start 25.273 -345.051126)
		(end 25.712674 -345.4908)
		(width 0.1651)
		(layer "In2.Cu")
		(net "PE_RX1_DR11_P")
	)
	(segment
		(start 16.397224 -344.436192)
		(end 15.48511 -343.797636)
		(width 0.1651)
		(layer "In2.Cu")
		(net "PE_RX1_DR11_P")
	)
	(segment
		(start 24.73706 -343.826084)
		(end 24.73706 -343.826338)
		(width 0.1651)
		(layer "In2.Cu")
		(net "PE_RX1_DR11_P")
	)
	(segment
		(start 11.262106 -338.616544)
		(end 11.000486 -338.662772)
		(width 0.1651)
		(layer "In2.Cu")
		(net "PE_RX1_DR11_P")
	)
	(segment
		(start 14.023086 -341.709248)
		(end 13.761212 -341.66302)
		(width 0.1651)
		(layer "In2.Cu")
		(net "PE_RX1_DR11_P")
	)
	(segment
		(start 10.548366 -338.116926)
		(end 10.142728 -337.832954)
		(width 0.1651)
		(layer "In2.Cu")
		(net "PE_RX1_DR11_P")
	)
	(segment
		(start 13.761212 -341.66302)
		(end 13.47724 -341.257382)
		(width 0.1651)
		(layer "In2.Cu")
		(net "PE_RX1_DR11_P")
	)
	(segment
		(start 9.475216 -337.594956)
		(end 9.428988 -337.333082)
		(width 0.1651)
		(layer "In2.Cu")
		(net "PE_RX1_DR11_P")
	)
	(segment
		(start 26.2382 -345.4908)
		(end 26.416 -345.313)
		(width 0.1651)
		(layer "In2.Cu")
		(net "PE_RX1_DR11_P")
	)
	(segment
		(start 16.88592 -344.517472)
		(end 16.397224 -344.436192)
		(width 0.1651)
		(layer "In2.Cu")
		(net "PE_RX1_DR11_P")
	)
	(segment
		(start 14.545056 -342.782398)
		(end 14.261084 -342.37676)
		(width 0.1651)
		(layer "In2.Cu")
		(net "PE_RX1_DR11_P")
	)
	(segment
		(start 8.30961 -336.549238)
		(end 7.903972 -336.265266)
		(width 0.1651)
		(layer "In2.Cu")
		(net "PE_RX1_DR11_P")
	)
	(segment
		(start 8.76173 -337.095084)
		(end 8.355838 -336.811112)
		(width 0.1651)
		(layer "In2.Cu")
		(net "PE_RX1_DR11_P")
	)
	(segment
		(start 25.712674 -345.4908)
		(end 26.2382 -345.4908)
		(width 0.1651)
		(layer "In2.Cu")
		(net "PE_RX1_DR11_P")
	)
	(segment
		(start 14.806676 -342.828626)
		(end 14.545056 -342.782398)
		(width 0.1651)
		(layer "In2.Cu")
		(net "PE_RX1_DR11_P")
	)
	(segment
		(start 12.392914 -339.408262)
		(end 11.262106 -338.616544)
		(width 0.1651)
		(layer "In2.Cu")
		(net "PE_RX1_DR11_P")
	)
	(segment
		(start 17.745202 -344.66022)
		(end 17.529048 -344.814906)
		(width 0.1651)
		(layer "In2.Cu")
		(net "PE_RX1_DR11_P")
	)
	(segment
		(start 10.594594 -338.3788)
		(end 10.548366 -338.116926)
		(width 0.1651)
		(layer "In2.Cu")
		(net "PE_RX1_DR11_P")
	)
	(segment
		(start 13.523214 -340.995508)
		(end 13.239242 -340.58987)
		(width 0.1651)
		(layer "In2.Cu")
		(net "PE_RX1_DR11_P")
	)
	(segment
		(start 14.261084 -342.37676)
		(end 14.307058 -342.114886)
		(width 0.1651)
		(layer "In2.Cu")
		(net "PE_RX1_DR11_P")
	)
	(segment
		(start 15.48511 -343.797636)
		(end 14.806676 -342.828626)
		(width 0.1651)
		(layer "In2.Cu")
		(net "PE_RX1_DR11_P")
	)
	(segment
		(start 26.117804 -344.34399)
		(end 24.73706 -343.826084)
		(width 0.1651)
		(layer "In2.Cu")
		(net "PE_RX1_DR11_P")
	)
	(segment
		(start 24.73706 -343.826338)
		(end 24.736806 -343.826084)
		(width 0.1651)
		(layer "In2.Cu")
		(net "PE_RX1_DR11_P")
	)
	(segment
		(start 9.428988 -337.333082)
		(end 9.02335 -337.04911)
		(width 0.1651)
		(layer "In2.Cu")
		(net "PE_RX1_DR11_P")
	)
	(segment
		(start 26.416 -345.313)
		(end 26.416 -344.88374)
		(width 0.1651)
		(layer "In2.Cu")
		(net "PE_RX1_DR11_P")
	)
	(segment
		(start 17.529048 -344.814906)
		(end 17.040352 -344.733626)
		(width 0.1651)
		(layer "In2.Cu")
		(net "PE_RX1_DR11_P")
	)
	(segment
		(start 13.239242 -340.58987)
		(end 12.977368 -340.543642)
		(width 0.1651)
		(layer "In2.Cu")
		(net "PE_RX1_DR11_P")
	)
	(segment
		(start 13.47724 -341.257382)
		(end 13.523214 -340.995508)
		(width 0.1651)
		(layer "In2.Cu")
		(net "PE_RX1_DR11_P")
	)
	(segment
		(start 17.040352 -344.733626)
		(end 16.88592 -344.517472)
		(width 0.1651)
		(layer "In2.Cu")
		(net "PE_RX1_DR11_P")
	)
	(segment
		(start 19.569176 -344.962988)
		(end 17.745202 -344.66022)
		(width 0.1651)
		(layer "In2.Cu")
		(net "PE_RX1_DR11_P")
	)
	(segment
		(start 9.881108 -337.878928)
		(end 9.475216 -337.594956)
		(width 0.1651)
		(layer "In2.Cu")
		(net "PE_RX1_DR11_P")
	)
	(segment
		(start 11.000486 -338.662772)
		(end 10.594594 -338.3788)
		(width 0.1651)
		(layer "In2.Cu")
		(net "PE_RX1_DR11_P")
	)
	(segment
		(start 12.73937 -339.87613)
		(end 12.455398 -339.470492)
		(width 0.1651)
		(layer "In2.Cu")
		(net "PE_RX1_DR11_P")
	)
	(segment
		(start 12.977368 -340.543642)
		(end 12.693396 -340.138004)
		(width 0.1651)
		(layer "In2.Cu")
		(net "PE_RX1_DR11_P")
	)
	(segment
		(start 14.307058 -342.114886)
		(end 14.023086 -341.709248)
		(width 0.1651)
		(layer "In2.Cu")
		(net "PE_RX1_DR11_P")
	)
	(segment
		(start 26.416 -344.88374)
		(end 26.117804 -344.34399)
		(width 0.1651)
		(layer "In2.Cu")
		(net "PE_RX1_DR11_P")
	)
	(segment
		(start 9.02335 -337.04911)
		(end 8.76173 -337.095084)
		(width 0.1651)
		(layer "In2.Cu")
		(net "PE_RX1_DR11_P")
	)
	(segment
		(start 5.308346 -336.119978)
		(end 5.08 -336.348324)
		(width 0.1651)
		(layer "In2.Cu")
		(net "PE_RX1_DR11_P")
	)
	(segment
		(start 10.142728 -337.832954)
		(end 9.881108 -337.878928)
		(width 0.1651)
		(layer "In2.Cu")
		(net "PE_RX1_DR11_P")
	)
	(segment
		(start 7.903972 -336.265266)
		(end 7.080758 -336.119978)
		(width 0.1651)
		(layer "In2.Cu")
		(net "PE_RX1_DR11_P")
	)
	(arc
		(start 12.455398 -339.470492)
		(mid 12.426885 -339.436636)
		(end 12.392914 -339.408262)
		(width 0.1651)
		(layer "In2.Cu")
		(net "PE_RX1_DR11_P")
	)
	(segment
		(start 25.273 -346.168726)
		(end 24.874474 -345.7702)
		(width 0.174752)
		(layer "F.Cu")
		(net "PE_RX1_DR11_N")
	)
	(segment
		(start 23.876 -346.009976)
		(end 22.800056 -346.009976)
		(width 0.174752)
		(layer "F.Cu")
		(net "PE_RX1_DR11_N")
	)
	(segment
		(start 24.115776 -345.7702)
		(end 23.876 -346.009976)
		(width 0.174752)
		(layer "F.Cu")
		(net "PE_RX1_DR11_N")
	)
	(segment
		(start 24.874474 -345.7702)
		(end 24.115776 -345.7702)
		(width 0.174752)
		(layer "F.Cu")
		(net "PE_RX1_DR11_N")
	)
	(via
		(at 25.273 -346.168726)
		(size 0.508)
		(drill 0.254)
		(layers "F.Cu" "B.Cu")
		(net "PE_RX1_DR11_N")
	)
	(via
		(at 5.08 -335.535524)
		(size 0.508)
		(drill 0.254)
		(layers "F.Cu" "B.Cu")
		(net "PE_RX1_DR11_N")
	)
	(segment
		(start 1.868932 -335.542128)
		(end 3.658108 -335.542128)
		(width 0.174752)
		(layer "B.Cu")
		(net "PE_RX1_DR11_N")
	)
	(segment
		(start 4.826 -335.789524)
		(end 5.08 -335.535524)
		(width 0.174752)
		(layer "B.Cu")
		(net "PE_RX1_DR11_N")
	)
	(segment
		(start 3.905504 -335.789524)
		(end 4.826 -335.789524)
		(width 0.174752)
		(layer "B.Cu")
		(net "PE_RX1_DR11_N")
	)
	(segment
		(start 3.658108 -335.542128)
		(end 3.905504 -335.789524)
		(width 0.174752)
		(layer "B.Cu")
		(net "PE_RX1_DR11_N")
	)
	(segment
		(start 19.559778 -344.600784)
		(end 16.536162 -344.098626)
		(width 0.1651)
		(layer "In2.Cu")
		(net "PE_RX1_DR11_N")
	)
	(segment
		(start 8.043418 -335.928716)
		(end 7.112 -335.764378)
		(width 0.1651)
		(layer "In2.Cu")
		(net "PE_RX1_DR11_N")
	)
	(segment
		(start 26.7716 -344.791792)
		(end 26.365708 -344.056716)
		(width 0.1651)
		(layer "In2.Cu")
		(net "PE_RX1_DR11_N")
	)
	(segment
		(start 24.763222 -343.456006)
		(end 19.559778 -344.600784)
		(width 0.1651)
		(layer "In2.Cu")
		(net "PE_RX1_DR11_N")
	)
	(segment
		(start 7.112 -335.764378)
		(end 5.308854 -335.764378)
		(width 0.1651)
		(layer "In2.Cu")
		(net "PE_RX1_DR11_N")
	)
	(segment
		(start 26.365708 -344.056716)
		(end 24.763222 -343.456006)
		(width 0.1651)
		(layer "In2.Cu")
		(net "PE_RX1_DR11_N")
	)
	(segment
		(start 26.7716 -345.46032)
		(end 26.7716 -344.791792)
		(width 0.1651)
		(layer "In2.Cu")
		(net "PE_RX1_DR11_N")
	)
	(segment
		(start 15.740888 -343.542366)
		(end 15.740634 -343.542112)
		(width 0.1651)
		(layer "In2.Cu")
		(net "PE_RX1_DR11_N")
	)
	(segment
		(start 26.38552 -345.8464)
		(end 26.7716 -345.46032)
		(width 0.1651)
		(layer "In2.Cu")
		(net "PE_RX1_DR11_N")
	)
	(segment
		(start 12.746736 -339.26653)
		(end 12.746228 -339.265768)
		(width 0.1651)
		(layer "In2.Cu")
		(net "PE_RX1_DR11_N")
	)
	(segment
		(start 12.596622 -339.116162)
		(end 8.043418 -335.928716)
		(width 0.1651)
		(layer "In2.Cu")
		(net "PE_RX1_DR11_N")
	)
	(segment
		(start 25.595326 -345.8464)
		(end 26.38552 -345.8464)
		(width 0.1651)
		(layer "In2.Cu")
		(net "PE_RX1_DR11_N")
	)
	(segment
		(start 25.273 -346.168726)
		(end 25.595326 -345.8464)
		(width 0.1651)
		(layer "In2.Cu")
		(net "PE_RX1_DR11_N")
	)
	(segment
		(start 16.536162 -344.098626)
		(end 15.740888 -343.542366)
		(width 0.1651)
		(layer "In2.Cu")
		(net "PE_RX1_DR11_N")
	)
	(segment
		(start 5.308854 -335.764378)
		(end 5.08 -335.535524)
		(width 0.1651)
		(layer "In2.Cu")
		(net "PE_RX1_DR11_N")
	)
	(segment
		(start 12.74699 -339.266276)
		(end 12.746736 -339.26653)
		(width 0.1651)
		(layer "In2.Cu")
		(net "PE_RX1_DR11_N")
	)
	(segment
		(start 15.740634 -343.542112)
		(end 12.74699 -339.266276)
		(width 0.1651)
		(layer "In2.Cu")
		(net "PE_RX1_DR11_N")
	)
	(arc
		(start 12.746228 -339.265768)
		(mid 12.677964 -339.184426)
		(end 12.596622 -339.116162)
		(width 0.1651)
		(layer "In2.Cu")
		(net "PE_RX1_DR11_N")
	)
	(segment
		(start 24.892254 -448.788028)
		(end 24.1046 -448.788028)
		(width 0.174752)
		(layer "F.Cu")
		(net "PE_RX1_DR10_P")
	)
	(segment
		(start 24.1046 -448.788028)
		(end 23.882604 -449.010024)
		(width 0.174752)
		(layer "F.Cu")
		(net "PE_RX1_DR10_P")
	)
	(segment
		(start 25.273 -449.168774)
		(end 24.892254 -448.788028)
		(width 0.174752)
		(layer "F.Cu")
		(net "PE_RX1_DR10_P")
	)
	(segment
		(start 23.882604 -449.010024)
		(end 22.800056 -449.010024)
		(width 0.174752)
		(layer "F.Cu")
		(net "PE_RX1_DR10_P")
	)
	(via
		(at 25.273 -449.168774)
		(size 0.508)
		(drill 0.254)
		(layers "F.Cu" "B.Cu")
		(net "PE_RX1_DR10_P")
	)
	(via
		(at 5.08 -403.935184)
		(size 0.508)
		(drill 0.254)
		(layers "F.Cu" "B.Cu")
		(net "PE_RX1_DR10_P")
	)
	(segment
		(start 4.826 -404.189184)
		(end 5.08 -403.935184)
		(width 0.174752)
		(layer "B.Cu")
		(net "PE_RX1_DR10_P")
	)
	(segment
		(start 3.905504 -404.189184)
		(end 4.826 -404.189184)
		(width 0.174752)
		(layer "B.Cu")
		(net "PE_RX1_DR10_P")
	)
	(segment
		(start 3.658108 -403.941788)
		(end 3.905504 -404.189184)
		(width 0.174752)
		(layer "B.Cu")
		(net "PE_RX1_DR10_P")
	)
	(segment
		(start 1.868932 -403.941788)
		(end 3.658108 -403.941788)
		(width 0.174752)
		(layer "B.Cu")
		(net "PE_RX1_DR10_P")
	)
	(segment
		(start 29.326078 -446.229486)
		(end 29.416248 -445.718184)
		(width 0.1651)
		(layer "In2.Cu")
		(net "PE_RX1_DR10_P")
	)
	(segment
		(start 41.65854 -409.64104)
		(end 14.912848 -404.923752)
		(width 0.1651)
		(layer "In2.Cu")
		(net "PE_RX1_DR10_P")
	)
	(segment
		(start 13.181838 -405.22906)
		(end 7.143242 -404.164038)
		(width 0.1651)
		(layer "In2.Cu")
		(net "PE_RX1_DR10_P")
	)
	(segment
		(start 43.095926 -410.588206)
		(end 41.866566 -409.7274)
		(width 0.1651)
		(layer "In2.Cu")
		(net "PE_RX1_DR10_P")
	)
	(segment
		(start 44.373292 -420.382192)
		(end 45.327824 -414.967928)
		(width 0.1651)
		(layer "In2.Cu")
		(net "PE_RX1_DR10_P")
	)
	(segment
		(start 25.273 -449.168774)
		(end 25.654 -448.787774)
		(width 0.1651)
		(layer "In2.Cu")
		(net "PE_RX1_DR10_P")
	)
	(segment
		(start 5.308854 -404.164038)
		(end 5.08 -403.935184)
		(width 0.1651)
		(layer "In2.Cu")
		(net "PE_RX1_DR10_P")
	)
	(segment
		(start 30.35046 -440.55411)
		(end 44.272708 -420.625524)
		(width 0.1651)
		(layer "In2.Cu")
		(net "PE_RX1_DR10_P")
	)
	(segment
		(start 7.143242 -404.164038)
		(end 5.308854 -404.164038)
		(width 0.1651)
		(layer "In2.Cu")
		(net "PE_RX1_DR10_P")
	)
	(segment
		(start 29.417264 -445.712342)
		(end 30.30855 -440.655456)
		(width 0.1651)
		(layer "In2.Cu")
		(net "PE_RX1_DR10_P")
	)
	(segment
		(start 45.010324 -413.267652)
		(end 43.223688 -410.715968)
		(width 0.1651)
		(layer "In2.Cu")
		(net "PE_RX1_DR10_P")
	)
	(segment
		(start 45.327824 -414.78708)
		(end 45.096684 -413.475932)
		(width 0.1651)
		(layer "In2.Cu")
		(net "PE_RX1_DR10_P")
	)
	(segment
		(start 28.156662 -447.980308)
		(end 28.233624 -447.903346)
		(width 0.1651)
		(layer "In2.Cu")
		(net "PE_RX1_DR10_P")
	)
	(segment
		(start 27.32532 -448.581018)
		(end 28.024328 -448.091814)
		(width 0.1651)
		(layer "In2.Cu")
		(net "PE_RX1_DR10_P")
	)
	(segment
		(start 28.344622 -447.771012)
		(end 29.184092 -446.572386)
		(width 0.1651)
		(layer "In2.Cu")
		(net "PE_RX1_DR10_P")
	)
	(segment
		(start 26.761948 -448.774566)
		(end 26.929588 -448.744848)
		(width 0.1651)
		(layer "In2.Cu")
		(net "PE_RX1_DR10_P")
	)
	(segment
		(start 25.654 -448.787774)
		(end 26.609294 -448.787774)
		(width 0.1651)
		(layer "In2.Cu")
		(net "PE_RX1_DR10_P")
	)
	(segment
		(start 14.912848 -404.923752)
		(end 13.181838 -405.22906)
		(width 0.1651)
		(layer "In2.Cu")
		(net "PE_RX1_DR10_P")
	)
	(arc
		(start 28.024328 -448.091814)
		(mid 28.092938 -448.03896)
		(end 28.156662 -447.980308)
		(width 0.1651)
		(layer "In2.Cu")
		(net "PE_RX1_DR10_P")
	)
	(arc
		(start 26.609294 -448.787774)
		(mid 26.68591 -448.784509)
		(end 26.761948 -448.774566)
		(width 0.1651)
		(layer "In2.Cu")
		(net "PE_RX1_DR10_P")
	)
	(arc
		(start 43.223688 -410.715968)
		(mid 43.165391 -410.646503)
		(end 43.095926 -410.588206)
		(width 0.1651)
		(layer "In2.Cu")
		(net "PE_RX1_DR10_P")
	)
	(arc
		(start 29.184092 -446.572386)
		(mid 29.233507 -446.492918)
		(end 29.274008 -446.408556)
		(width 0.1651)
		(layer "In2.Cu")
		(net "PE_RX1_DR10_P")
	)
	(arc
		(start 44.272708 -420.625524)
		(mid 44.336276 -420.509348)
		(end 44.373292 -420.382192)
		(width 0.1651)
		(layer "In2.Cu")
		(net "PE_RX1_DR10_P")
	)
	(arc
		(start 41.866566 -409.7274)
		(mid 41.767284 -409.672819)
		(end 41.65854 -409.64104)
		(width 0.1651)
		(layer "In2.Cu")
		(net "PE_RX1_DR10_P")
	)
	(arc
		(start 29.274008 -446.408556)
		(mid 29.304905 -446.320435)
		(end 29.326078 -446.229486)
		(width 0.1651)
		(layer "In2.Cu")
		(net "PE_RX1_DR10_P")
	)
	(arc
		(start 45.096684 -413.475932)
		(mid 45.064896 -413.367071)
		(end 45.010324 -413.267652)
		(width 0.1651)
		(layer "In2.Cu")
		(net "PE_RX1_DR10_P")
	)
	(arc
		(start 45.327824 -414.967928)
		(mid 45.335735 -414.877504)
		(end 45.327824 -414.78708)
		(width 0.1651)
		(layer "In2.Cu")
		(net "PE_RX1_DR10_P")
	)
	(arc
		(start 29.416248 -445.718184)
		(mid 29.416783 -445.715268)
		(end 29.417264 -445.712342)
		(width 0.1651)
		(layer "In2.Cu")
		(net "PE_RX1_DR10_P")
	)
	(arc
		(start 28.233624 -447.903346)
		(mid 28.292012 -447.839602)
		(end 28.344622 -447.771012)
		(width 0.1651)
		(layer "In2.Cu")
		(net "PE_RX1_DR10_P")
	)
	(arc
		(start 30.30855 -440.655456)
		(mid 30.323984 -440.602502)
		(end 30.35046 -440.55411)
		(width 0.1651)
		(layer "In2.Cu")
		(net "PE_RX1_DR10_P")
	)
	(arc
		(start 26.929588 -448.744848)
		(mid 27.136404 -448.684558)
		(end 27.32532 -448.581018)
		(width 0.1651)
		(layer "In2.Cu")
		(net "PE_RX1_DR10_P")
	)
	(segment
		(start 23.903178 -448.210178)
		(end 22.800056 -448.210178)
		(width 0.174752)
		(layer "F.Cu")
		(net "PE_RX1_DR10_N")
	)
	(segment
		(start 24.8412 -448.482974)
		(end 24.175974 -448.482974)
		(width 0.174752)
		(layer "F.Cu")
		(net "PE_RX1_DR10_N")
	)
	(segment
		(start 24.175974 -448.482974)
		(end 23.903178 -448.210178)
		(width 0.174752)
		(layer "F.Cu")
		(net "PE_RX1_DR10_N")
	)
	(segment
		(start 25.273 -448.051174)
		(end 24.8412 -448.482974)
		(width 0.174752)
		(layer "F.Cu")
		(net "PE_RX1_DR10_N")
	)
	(via
		(at 5.08 -404.747984)
		(size 0.508)
		(drill 0.254)
		(layers "F.Cu" "B.Cu")
		(net "PE_RX1_DR10_N")
	)
	(via
		(at 25.273 -448.051174)
		(size 0.508)
		(drill 0.254)
		(layers "F.Cu" "B.Cu")
		(net "PE_RX1_DR10_N")
	)
	(segment
		(start 1.868932 -404.741888)
		(end 3.657854 -404.741888)
		(width 0.174752)
		(layer "B.Cu")
		(net "PE_RX1_DR10_N")
	)
	(segment
		(start 3.905504 -404.494238)
		(end 4.826254 -404.494238)
		(width 0.174752)
		(layer "B.Cu")
		(net "PE_RX1_DR10_N")
	)
	(segment
		(start 4.826254 -404.494238)
		(end 5.08 -404.747984)
		(width 0.174752)
		(layer "B.Cu")
		(net "PE_RX1_DR10_N")
	)
	(segment
		(start 3.657854 -404.741888)
		(end 3.905504 -404.494238)
		(width 0.174752)
		(layer "B.Cu")
		(net "PE_RX1_DR10_N")
	)
	(segment
		(start 43.981116 -420.421816)
		(end 33.537652 -435.369716)
		(width 0.1651)
		(layer "In2.Cu")
		(net "PE_RX1_DR10_N")
	)
	(segment
		(start 31.464758 -438.027064)
		(end 31.5087 -438.27446)
		(width 0.1651)
		(layer "In2.Cu")
		(net "PE_RX1_DR10_N")
	)
	(segment
		(start 41.662604 -410.018738)
		(end 42.891964 -410.879544)
		(width 0.1651)
		(layer "In2.Cu")
		(net "PE_RX1_DR10_N")
	)
	(segment
		(start 26.609294 -448.432174)
		(end 25.654 -448.432174)
		(width 0.1651)
		(layer "In2.Cu")
		(net "PE_RX1_DR10_N")
	)
	(segment
		(start 44.977558 -414.906206)
		(end 44.023026 -420.320216)
		(width 0.1651)
		(layer "In2.Cu")
		(net "PE_RX1_DR10_N")
	)
	(segment
		(start 30.062678 -440.34456)
		(end 30.059884 -440.344814)
		(width 0.1651)
		(layer "In2.Cu")
		(net "PE_RX1_DR10_N")
	)
	(segment
		(start 13.181838 -405.590248)
		(end 14.912848 -405.28494)
		(width 0.1651)
		(layer "In2.Cu")
		(net "PE_RX1_DR10_N")
	)
	(segment
		(start 28.899612 -445.516254)
		(end 29.052266 -445.734186)
		(width 0.1651)
		(layer "In2.Cu")
		(net "PE_RX1_DR10_N")
	)
	(segment
		(start 33.537652 -435.369716)
		(end 33.290256 -435.413658)
		(width 0.1651)
		(layer "In2.Cu")
		(net "PE_RX1_DR10_N")
	)
	(segment
		(start 28.985718 -445.028574)
		(end 28.899612 -445.516254)
		(width 0.1651)
		(layer "In2.Cu")
		(net "PE_RX1_DR10_N")
	)
	(segment
		(start 30.977586 -438.724548)
		(end 30.693868 -439.130694)
		(width 0.1651)
		(layer "In2.Cu")
		(net "PE_RX1_DR10_N")
	)
	(segment
		(start 25.654 -448.432174)
		(end 25.273 -448.051174)
		(width 0.1651)
		(layer "In2.Cu")
		(net "PE_RX1_DR10_N")
	)
	(segment
		(start 31.224982 -438.680606)
		(end 30.977586 -438.724548)
		(width 0.1651)
		(layer "In2.Cu")
		(net "PE_RX1_DR10_N")
	)
	(segment
		(start 29.46019 -442.336936)
		(end 29.374084 -442.82487)
		(width 0.1651)
		(layer "In2.Cu")
		(net "PE_RX1_DR10_N")
	)
	(segment
		(start 41.66235 -410.018738)
		(end 41.662604 -410.018738)
		(width 0.1651)
		(layer "In2.Cu")
		(net "PE_RX1_DR10_N")
	)
	(segment
		(start 31.748476 -437.620918)
		(end 31.464758 -438.027064)
		(width 0.1651)
		(layer "In2.Cu")
		(net "PE_RX1_DR10_N")
	)
	(segment
		(start 27.982164 -447.651886)
		(end 27.904948 -447.729102)
		(width 0.1651)
		(layer "In2.Cu")
		(net "PE_RX1_DR10_N")
	)
	(segment
		(start 30.73781 -439.378344)
		(end 30.062678 -440.34456)
		(width 0.1651)
		(layer "In2.Cu")
		(net "PE_RX1_DR10_N")
	)
	(segment
		(start 5.308346 -404.519638)
		(end 7.112 -404.519638)
		(width 0.1651)
		(layer "In2.Cu")
		(net "PE_RX1_DR10_N")
	)
	(segment
		(start 32.519366 -436.517288)
		(end 32.235648 -436.923434)
		(width 0.1651)
		(layer "In2.Cu")
		(net "PE_RX1_DR10_N")
	)
	(segment
		(start 33.290256 -435.413658)
		(end 33.006538 -435.819804)
		(width 0.1651)
		(layer "In2.Cu")
		(net "PE_RX1_DR10_N")
	)
	(segment
		(start 32.235648 -436.923434)
		(end 32.27959 -437.17083)
		(width 0.1651)
		(layer "In2.Cu")
		(net "PE_RX1_DR10_N")
	)
	(segment
		(start 33.006538 -435.819804)
		(end 33.05048 -436.0672)
		(width 0.1651)
		(layer "In2.Cu")
		(net "PE_RX1_DR10_N")
	)
	(segment
		(start 27.820112 -447.800476)
		(end 27.121358 -448.28968)
		(width 0.1651)
		(layer "In2.Cu")
		(net "PE_RX1_DR10_N")
	)
	(segment
		(start 7.112 -404.519638)
		(end 13.181838 -405.590248)
		(width 0.1651)
		(layer "In2.Cu")
		(net "PE_RX1_DR10_N")
	)
	(segment
		(start 5.08 -404.747984)
		(end 5.308346 -404.519638)
		(width 0.1651)
		(layer "In2.Cu")
		(net "PE_RX1_DR10_N")
	)
	(segment
		(start 31.5087 -438.27446)
		(end 31.224982 -438.680606)
		(width 0.1651)
		(layer "In2.Cu")
		(net "PE_RX1_DR10_N")
	)
	(segment
		(start 29.203396 -444.876174)
		(end 28.985718 -445.028574)
		(width 0.1651)
		(layer "In2.Cu")
		(net "PE_RX1_DR10_N")
	)
	(segment
		(start 44.746418 -413.537654)
		(end 44.977558 -414.848802)
		(width 0.1651)
		(layer "In2.Cu")
		(net "PE_RX1_DR10_N")
	)
	(segment
		(start 29.136848 -444.170562)
		(end 29.289502 -444.38824)
		(width 0.1651)
		(layer "In2.Cu")
		(net "PE_RX1_DR10_N")
	)
	(segment
		(start 29.677868 -442.184536)
		(end 29.46019 -442.336936)
		(width 0.1651)
		(layer "In2.Cu")
		(net "PE_RX1_DR10_N")
	)
	(segment
		(start 42.93235 -410.91993)
		(end 44.718986 -413.471614)
		(width 0.1651)
		(layer "In2.Cu")
		(net "PE_RX1_DR10_N")
	)
	(segment
		(start 33.05048 -436.0672)
		(end 32.766762 -436.473346)
		(width 0.1651)
		(layer "In2.Cu")
		(net "PE_RX1_DR10_N")
	)
	(segment
		(start 31.995872 -437.576976)
		(end 31.748476 -437.620918)
		(width 0.1651)
		(layer "In2.Cu")
		(net "PE_RX1_DR10_N")
	)
	(segment
		(start 32.766762 -436.473346)
		(end 32.519366 -436.517288)
		(width 0.1651)
		(layer "In2.Cu")
		(net "PE_RX1_DR10_N")
	)
	(segment
		(start 29.289502 -444.38824)
		(end 29.203396 -444.876174)
		(width 0.1651)
		(layer "In2.Cu")
		(net "PE_RX1_DR10_N")
	)
	(segment
		(start 29.052266 -445.734186)
		(end 28.975812 -446.167764)
		(width 0.1651)
		(layer "In2.Cu")
		(net "PE_RX1_DR10_N")
	)
	(segment
		(start 29.222954 -443.682882)
		(end 29.136848 -444.170562)
		(width 0.1651)
		(layer "In2.Cu")
		(net "PE_RX1_DR10_N")
	)
	(segment
		(start 26.867612 -448.394582)
		(end 26.699972 -448.4243)
		(width 0.1651)
		(layer "In2.Cu")
		(net "PE_RX1_DR10_N")
	)
	(segment
		(start 14.912848 -405.28494)
		(end 41.596564 -409.991306)
		(width 0.1651)
		(layer "In2.Cu")
		(net "PE_RX1_DR10_N")
	)
	(segment
		(start 29.526738 -443.042548)
		(end 29.440632 -443.530228)
		(width 0.1651)
		(layer "In2.Cu")
		(net "PE_RX1_DR10_N")
	)
	(segment
		(start 29.440632 -443.530228)
		(end 29.222954 -443.682882)
		(width 0.1651)
		(layer "In2.Cu")
		(net "PE_RX1_DR10_N")
	)
	(segment
		(start 30.693868 -439.130694)
		(end 30.73781 -439.378344)
		(width 0.1651)
		(layer "In2.Cu")
		(net "PE_RX1_DR10_N")
	)
	(segment
		(start 29.374084 -442.82487)
		(end 29.526738 -443.042548)
		(width 0.1651)
		(layer "In2.Cu")
		(net "PE_RX1_DR10_N")
	)
	(segment
		(start 32.27959 -437.17083)
		(end 31.995872 -437.576976)
		(width 0.1651)
		(layer "In2.Cu")
		(net "PE_RX1_DR10_N")
	)
	(segment
		(start 28.892754 -446.368424)
		(end 28.053284 -447.56705)
		(width 0.1651)
		(layer "In2.Cu")
		(net "PE_RX1_DR10_N")
	)
	(segment
		(start 43.981116 -420.421562)
		(end 43.981116 -420.421816)
		(width 0.1651)
		(layer "In2.Cu")
		(net "PE_RX1_DR10_N")
	)
	(segment
		(start 44.718986 -413.471614)
		(end 44.718986 -413.471868)
		(width 0.1651)
		(layer "In2.Cu")
		(net "PE_RX1_DR10_N")
	)
	(segment
		(start 29.9593 -440.588146)
		(end 29.677868 -442.184536)
		(width 0.1651)
		(layer "In2.Cu")
		(net "PE_RX1_DR10_N")
	)
	(arc
		(start 44.023026 -420.320216)
		(mid 44.007592 -420.37317)
		(end 43.981116 -420.421562)
		(width 0.1651)
		(layer "In2.Cu")
		(net "PE_RX1_DR10_N")
	)
	(arc
		(start 42.891964 -410.879544)
		(mid 42.913917 -410.897977)
		(end 42.93235 -410.91993)
		(width 0.1651)
		(layer "In2.Cu")
		(net "PE_RX1_DR10_N")
	)
	(arc
		(start 26.699972 -448.4243)
		(mid 26.654805 -448.430213)
		(end 26.609294 -448.432174)
		(width 0.1651)
		(layer "In2.Cu")
		(net "PE_RX1_DR10_N")
	)
	(arc
		(start 28.053284 -447.56705)
		(mid 28.019571 -447.611016)
		(end 27.982164 -447.651886)
		(width 0.1651)
		(layer "In2.Cu")
		(net "PE_RX1_DR10_N")
	)
	(arc
		(start 28.975812 -446.167764)
		(mid 28.963409 -446.221039)
		(end 28.945332 -446.272666)
		(width 0.1651)
		(layer "In2.Cu")
		(net "PE_RX1_DR10_N")
	)
	(arc
		(start 27.904948 -447.729102)
		(mid 27.86409 -447.766643)
		(end 27.820112 -447.800476)
		(width 0.1651)
		(layer "In2.Cu")
		(net "PE_RX1_DR10_N")
	)
	(arc
		(start 41.596564 -409.991306)
		(mid 41.630968 -410.001404)
		(end 41.66235 -410.018738)
		(width 0.1651)
		(layer "In2.Cu")
		(net "PE_RX1_DR10_N")
	)
	(arc
		(start 44.977558 -414.848802)
		(mid 44.980072 -414.877504)
		(end 44.977558 -414.906206)
		(width 0.1651)
		(layer "In2.Cu")
		(net "PE_RX1_DR10_N")
	)
	(arc
		(start 44.718986 -413.471868)
		(mid 44.736325 -413.503253)
		(end 44.746418 -413.537654)
		(width 0.1651)
		(layer "In2.Cu")
		(net "PE_RX1_DR10_N")
	)
	(arc
		(start 28.945332 -446.272666)
		(mid 28.921648 -446.321975)
		(end 28.892754 -446.368424)
		(width 0.1651)
		(layer "In2.Cu")
		(net "PE_RX1_DR10_N")
	)
	(arc
		(start 30.059884 -440.344814)
		(mid 29.996316 -440.46099)
		(end 29.9593 -440.588146)
		(width 0.1651)
		(layer "In2.Cu")
		(net "PE_RX1_DR10_N")
	)
	(arc
		(start 27.121358 -448.28968)
		(mid 27.000224 -448.356014)
		(end 26.867612 -448.394582)
		(width 0.1651)
		(layer "In2.Cu")
		(net "PE_RX1_DR10_N")
	)
	(segment
		(start 223.132396 -366.78997)
		(end 222.885 -366.542574)
		(width 0.174752)
		(layer "F.Cu")
		(net "PE_RX1_DR1_P")
	)
	(segment
		(start 222.885 -366.542574)
		(end 222.133414 -366.542574)
		(width 0.174752)
		(layer "F.Cu")
		(net "PE_RX1_DR1_P")
	)
	(segment
		(start 222.133414 -366.542574)
		(end 221.727014 -366.948974)
		(width 0.174752)
		(layer "F.Cu")
		(net "PE_RX1_DR1_P")
	)
	(segment
		(start 224.199958 -366.78997)
		(end 223.132396 -366.78997)
		(width 0.174752)
		(layer "F.Cu")
		(net "PE_RX1_DR1_P")
	)
	(via
		(at 221.727014 -366.948974)
		(size 0.508)
		(drill 0.254)
		(layers "F.Cu" "B.Cu")
		(net "PE_RX1_DR1_P")
	)
	(via
		(at 5.08 -389.548116)
		(size 0.508)
		(drill 0.254)
		(layers "F.Cu" "B.Cu")
		(net "PE_RX1_DR1_P")
	)
	(segment
		(start 3.657854 -389.54202)
		(end 3.905504 -389.29437)
		(width 0.174752)
		(layer "B.Cu")
		(net "PE_RX1_DR1_P")
	)
	(segment
		(start 4.826254 -389.29437)
		(end 5.08 -389.548116)
		(width 0.174752)
		(layer "B.Cu")
		(net "PE_RX1_DR1_P")
	)
	(segment
		(start 1.868932 -389.54202)
		(end 3.657854 -389.54202)
		(width 0.174752)
		(layer "B.Cu")
		(net "PE_RX1_DR1_P")
	)
	(segment
		(start 3.905504 -389.29437)
		(end 4.826254 -389.29437)
		(width 0.174752)
		(layer "B.Cu")
		(net "PE_RX1_DR1_P")
	)
	(segment
		(start 9.673844 -391.107168)
		(end 7.434834 -389.538972)
		(width 0.1651)
		(layer "In2.Cu")
		(net "PE_RX1_DR1_P")
	)
	(segment
		(start 5.308346 -389.31977)
		(end 5.08 -389.548116)
		(width 0.1651)
		(layer "In2.Cu")
		(net "PE_RX1_DR1_P")
	)
	(segment
		(start 220.345 -366.567974)
		(end 203.71435 -378.212858)
		(width 0.1651)
		(layer "In2.Cu")
		(net "PE_RX1_DR1_P")
	)
	(segment
		(start 221.727014 -366.948974)
		(end 221.346014 -366.567974)
		(width 0.1651)
		(layer "In2.Cu")
		(net "PE_RX1_DR1_P")
	)
	(segment
		(start 221.346014 -366.567974)
		(end 220.345 -366.567974)
		(width 0.1651)
		(layer "In2.Cu")
		(net "PE_RX1_DR1_P")
	)
	(segment
		(start 203.318364 -378.376942)
		(end 45.285406 -406.242266)
		(width 0.1651)
		(layer "In2.Cu")
		(net "PE_RX1_DR1_P")
	)
	(segment
		(start 11.947144 -394.35405)
		(end 9.673844 -391.107168)
		(width 0.1651)
		(layer "In2.Cu")
		(net "PE_RX1_DR1_P")
	)
	(segment
		(start 7.434834 -389.538972)
		(end 6.190742 -389.31977)
		(width 0.1651)
		(layer "In2.Cu")
		(net "PE_RX1_DR1_P")
	)
	(segment
		(start 23.537672 -402.468334)
		(end 11.947144 -394.35405)
		(width 0.1651)
		(layer "In2.Cu")
		(net "PE_RX1_DR1_P")
	)
	(segment
		(start 6.190742 -389.31977)
		(end 5.308346 -389.31977)
		(width 0.1651)
		(layer "In2.Cu")
		(net "PE_RX1_DR1_P")
	)
	(segment
		(start 44.94149 -406.242266)
		(end 23.537672 -402.468334)
		(width 0.1651)
		(layer "In2.Cu")
		(net "PE_RX1_DR1_P")
	)
	(arc
		(start 203.71435 -378.212858)
		(mid 203.525342 -378.316586)
		(end 203.318364 -378.376942)
		(width 0.1651)
		(layer "In2.Cu")
		(net "PE_RX1_DR1_P")
	)
	(arc
		(start 45.285406 -406.242266)
		(mid 45.113448 -406.257304)
		(end 44.94149 -406.242266)
		(width 0.1651)
		(layer "In2.Cu")
		(net "PE_RX1_DR1_P")
	)
	(segment
		(start 224.199958 -365.990124)
		(end 223.139 -365.990124)
		(width 0.174752)
		(layer "F.Cu")
		(net "PE_RX1_DR1_N")
	)
	(segment
		(start 222.13316 -366.23752)
		(end 221.727014 -365.831374)
		(width 0.174752)
		(layer "F.Cu")
		(net "PE_RX1_DR1_N")
	)
	(segment
		(start 222.891604 -366.23752)
		(end 222.13316 -366.23752)
		(width 0.174752)
		(layer "F.Cu")
		(net "PE_RX1_DR1_N")
	)
	(segment
		(start 223.139 -365.990124)
		(end 222.891604 -366.23752)
		(width 0.174752)
		(layer "F.Cu")
		(net "PE_RX1_DR1_N")
	)
	(via
		(at 5.08 -388.735316)
		(size 0.508)
		(drill 0.254)
		(layers "F.Cu" "B.Cu")
		(net "PE_RX1_DR1_N")
	)
	(via
		(at 221.727014 -365.831374)
		(size 0.508)
		(drill 0.254)
		(layers "F.Cu" "B.Cu")
		(net "PE_RX1_DR1_N")
	)
	(segment
		(start 4.826 -388.989316)
		(end 5.08 -388.735316)
		(width 0.174752)
		(layer "B.Cu")
		(net "PE_RX1_DR1_N")
	)
	(segment
		(start 1.868932 -388.74192)
		(end 3.658108 -388.74192)
		(width 0.174752)
		(layer "B.Cu")
		(net "PE_RX1_DR1_N")
	)
	(segment
		(start 3.658108 -388.74192)
		(end 3.905504 -388.989316)
		(width 0.174752)
		(layer "B.Cu")
		(net "PE_RX1_DR1_N")
	)
	(segment
		(start 3.905504 -388.989316)
		(end 4.826 -388.989316)
		(width 0.174752)
		(layer "B.Cu")
		(net "PE_RX1_DR1_N")
	)
	(segment
		(start 6.221984 -388.96417)
		(end 5.308854 -388.96417)
		(width 0.1651)
		(layer "In2.Cu")
		(net "PE_RX1_DR1_N")
	)
	(segment
		(start 7.57428 -389.202422)
		(end 6.221984 -388.96417)
		(width 0.1651)
		(layer "In2.Cu")
		(net "PE_RX1_DR1_N")
	)
	(segment
		(start 5.308854 -388.96417)
		(end 5.08 -388.735316)
		(width 0.1651)
		(layer "In2.Cu")
		(net "PE_RX1_DR1_N")
	)
	(segment
		(start 9.929368 -390.851644)
		(end 7.57428 -389.202422)
		(width 0.1651)
		(layer "In2.Cu")
		(net "PE_RX1_DR1_N")
	)
	(segment
		(start 12.202668 -394.098526)
		(end 9.929368 -390.851644)
		(width 0.1651)
		(layer "In2.Cu")
		(net "PE_RX1_DR1_N")
	)
	(segment
		(start 45.003212 -405.891746)
		(end 23.677118 -402.131784)
		(width 0.1651)
		(layer "In2.Cu")
		(net "PE_RX1_DR1_N")
	)
	(segment
		(start 221.727014 -365.831374)
		(end 221.346014 -366.212374)
		(width 0.1651)
		(layer "In2.Cu")
		(net "PE_RX1_DR1_N")
	)
	(segment
		(start 221.346014 -366.212374)
		(end 220.232732 -366.212374)
		(width 0.1651)
		(layer "In2.Cu")
		(net "PE_RX1_DR1_N")
	)
	(segment
		(start 23.677118 -402.131784)
		(end 12.202668 -394.098526)
		(width 0.1651)
		(layer "In2.Cu")
		(net "PE_RX1_DR1_N")
	)
	(segment
		(start 203.256388 -378.026676)
		(end 45.223684 -405.891746)
		(width 0.1651)
		(layer "In2.Cu")
		(net "PE_RX1_DR1_N")
	)
	(segment
		(start 220.232732 -366.212374)
		(end 203.510388 -377.92152)
		(width 0.1651)
		(layer "In2.Cu")
		(net "PE_RX1_DR1_N")
	)
	(arc
		(start 203.510388 -377.92152)
		(mid 203.389153 -377.988029)
		(end 203.256388 -378.026676)
		(width 0.1651)
		(layer "In2.Cu")
		(net "PE_RX1_DR1_N")
	)
	(arc
		(start 45.223684 -405.891746)
		(mid 45.113448 -405.901388)
		(end 45.003212 -405.891746)
		(width 0.1651)
		(layer "In2.Cu")
		(net "PE_RX1_DR1_N")
	)
	(segment
		(start 222.133414 -469.542622)
		(end 221.727014 -469.949022)
		(width 0.174752)
		(layer "F.Cu")
		(net "PE_RX1_DR0_P")
	)
	(segment
		(start 223.156018 -469.790018)
		(end 222.908622 -469.542622)
		(width 0.174752)
		(layer "F.Cu")
		(net "PE_RX1_DR0_P")
	)
	(segment
		(start 224.199958 -469.790018)
		(end 223.156018 -469.790018)
		(width 0.174752)
		(layer "F.Cu")
		(net "PE_RX1_DR0_P")
	)
	(segment
		(start 222.908622 -469.542622)
		(end 222.133414 -469.542622)
		(width 0.174752)
		(layer "F.Cu")
		(net "PE_RX1_DR0_P")
	)
	(via
		(at 221.727014 -469.949022)
		(size 0.508)
		(drill 0.254)
		(layers "F.Cu" "B.Cu")
		(net "PE_RX1_DR0_P")
	)
	(via
		(at 5.08 -417.54806)
		(size 0.508)
		(drill 0.254)
		(layers "F.Cu" "B.Cu")
		(net "PE_RX1_DR0_P")
	)
	(segment
		(start 4.826254 -417.294314)
		(end 5.08 -417.54806)
		(width 0.174752)
		(layer "B.Cu")
		(net "PE_RX1_DR0_P")
	)
	(segment
		(start 3.905504 -417.294314)
		(end 4.826254 -417.294314)
		(width 0.174752)
		(layer "B.Cu")
		(net "PE_RX1_DR0_P")
	)
	(segment
		(start 3.657854 -417.541964)
		(end 3.905504 -417.294314)
		(width 0.174752)
		(layer "B.Cu")
		(net "PE_RX1_DR0_P")
	)
	(segment
		(start 1.868932 -417.541964)
		(end 3.657854 -417.541964)
		(width 0.174752)
		(layer "B.Cu")
		(net "PE_RX1_DR0_P")
	)
	(segment
		(start 26.730706 -454.486772)
		(end 23.278592 -455.095102)
		(width 0.1651)
		(layer "In2.Cu")
		(net "PE_RX1_DR0_P")
	)
	(segment
		(start 6.897116 -417.451032)
		(end 6.152896 -417.319714)
		(width 0.1651)
		(layer "In2.Cu")
		(net "PE_RX1_DR0_P")
	)
	(segment
		(start 16.241522 -449.303648)
		(end 11.706098 -423.579798)
		(width 0.1651)
		(layer "In2.Cu")
		(net "PE_RX1_DR0_P")
	)
	(segment
		(start 29.713682 -452.46798)
		(end 26.974546 -454.38568)
		(width 0.1651)
		(layer "In2.Cu")
		(net "PE_RX1_DR0_P")
	)
	(segment
		(start 220.472 -469.568022)
		(end 210.999832 -471.238326)
		(width 0.1651)
		(layer "In2.Cu")
		(net "PE_RX1_DR0_P")
	)
	(segment
		(start 221.346014 -469.568022)
		(end 220.472 -469.568022)
		(width 0.1651)
		(layer "In2.Cu")
		(net "PE_RX1_DR0_P")
	)
	(segment
		(start 7.913116 -418.162232)
		(end 6.897116 -417.451032)
		(width 0.1651)
		(layer "In2.Cu")
		(net "PE_RX1_DR0_P")
	)
	(segment
		(start 19.943064 -452.964296)
		(end 17.680432 -451.37959)
		(width 0.1651)
		(layer "In2.Cu")
		(net "PE_RX1_DR0_P")
	)
	(segment
		(start 20.900898 -454.332086)
		(end 19.943064 -452.964296)
		(width 0.1651)
		(layer "In2.Cu")
		(net "PE_RX1_DR0_P")
	)
	(segment
		(start 17.530572 -451.229984)
		(end 16.327882 -449.511928)
		(width 0.1651)
		(layer "In2.Cu")
		(net "PE_RX1_DR0_P")
	)
	(segment
		(start 23.278592 -455.095102)
		(end 23.27783 -455.095356)
		(width 0.1651)
		(layer "In2.Cu")
		(net "PE_RX1_DR0_P")
	)
	(segment
		(start 21.461222 -454.762616)
		(end 21.028914 -454.460102)
		(width 0.1651)
		(layer "In2.Cu")
		(net "PE_RX1_DR0_P")
	)
	(segment
		(start 39.620444 -441.684918)
		(end 35.174936 -444.797942)
		(width 0.1651)
		(layer "In2.Cu")
		(net "PE_RX1_DR0_P")
	)
	(segment
		(start 23.065486 -455.095356)
		(end 21.669502 -454.848468)
		(width 0.1651)
		(layer "In2.Cu")
		(net "PE_RX1_DR0_P")
	)
	(segment
		(start 41.684448 -441.320682)
		(end 39.620444 -441.684918)
		(width 0.1651)
		(layer "In2.Cu")
		(net "PE_RX1_DR0_P")
	)
	(segment
		(start 11.706098 -423.579798)
		(end 7.913116 -418.162232)
		(width 0.1651)
		(layer "In2.Cu")
		(net "PE_RX1_DR0_P")
	)
	(segment
		(start 35.019234 -444.953898)
		(end 29.863288 -452.318374)
		(width 0.1651)
		(layer "In2.Cu")
		(net "PE_RX1_DR0_P")
	)
	(segment
		(start 6.152896 -417.319714)
		(end 5.308346 -417.319714)
		(width 0.1651)
		(layer "In2.Cu")
		(net "PE_RX1_DR0_P")
	)
	(segment
		(start 210.999832 -471.238326)
		(end 41.684448 -441.320682)
		(width 0.1651)
		(layer "In2.Cu")
		(net "PE_RX1_DR0_P")
	)
	(segment
		(start 221.727014 -469.949022)
		(end 221.346014 -469.568022)
		(width 0.1651)
		(layer "In2.Cu")
		(net "PE_RX1_DR0_P")
	)
	(segment
		(start 5.308346 -417.319714)
		(end 5.08 -417.54806)
		(width 0.1651)
		(layer "In2.Cu")
		(net "PE_RX1_DR0_P")
	)
	(arc
		(start 21.669502 -454.848468)
		(mid 21.560673 -454.816923)
		(end 21.461222 -454.762616)
		(width 0.1651)
		(layer "In2.Cu")
		(net "PE_RX1_DR0_P")
	)
	(arc
		(start 29.863288 -452.318374)
		(mid 29.795024 -452.399716)
		(end 29.713682 -452.46798)
		(width 0.1651)
		(layer "In2.Cu")
		(net "PE_RX1_DR0_P")
	)
	(arc
		(start 26.974546 -454.38568)
		(mid 26.858162 -454.449578)
		(end 26.730706 -454.486772)
		(width 0.1651)
		(layer "In2.Cu")
		(net "PE_RX1_DR0_P")
	)
	(arc
		(start 23.27783 -455.095356)
		(mid 23.171658 -455.104674)
		(end 23.065486 -455.095356)
		(width 0.1651)
		(layer "In2.Cu")
		(net "PE_RX1_DR0_P")
	)
	(arc
		(start 21.028914 -454.460102)
		(mid 20.959302 -454.401698)
		(end 20.900898 -454.332086)
		(width 0.1651)
		(layer "In2.Cu")
		(net "PE_RX1_DR0_P")
	)
	(arc
		(start 35.174936 -444.797942)
		(mid 35.090261 -444.869108)
		(end 35.019234 -444.953898)
		(width 0.1651)
		(layer "In2.Cu")
		(net "PE_RX1_DR0_P")
	)
	(arc
		(start 17.680432 -451.37959)
		(mid 17.598964 -451.311337)
		(end 17.530572 -451.229984)
		(width 0.1651)
		(layer "In2.Cu")
		(net "PE_RX1_DR0_P")
	)
	(arc
		(start 16.327882 -449.511928)
		(mid 16.273278 -449.412523)
		(end 16.241522 -449.303648)
		(width 0.1651)
		(layer "In2.Cu")
		(net "PE_RX1_DR0_P")
	)
	(segment
		(start 223.132396 -468.990172)
		(end 222.885 -469.237568)
		(width 0.174752)
		(layer "F.Cu")
		(net "PE_RX1_DR0_N")
	)
	(segment
		(start 224.199958 -468.990172)
		(end 223.132396 -468.990172)
		(width 0.174752)
		(layer "F.Cu")
		(net "PE_RX1_DR0_N")
	)
	(segment
		(start 222.885 -469.237568)
		(end 222.13316 -469.237568)
		(width 0.174752)
		(layer "F.Cu")
		(net "PE_RX1_DR0_N")
	)
	(segment
		(start 222.13316 -469.237568)
		(end 221.727014 -468.831422)
		(width 0.174752)
		(layer "F.Cu")
		(net "PE_RX1_DR0_N")
	)
	(via
		(at 5.08 -416.73526)
		(size 0.508)
		(drill 0.254)
		(layers "F.Cu" "B.Cu")
		(net "PE_RX1_DR0_N")
	)
	(via
		(at 221.727014 -468.831422)
		(size 0.508)
		(drill 0.254)
		(layers "F.Cu" "B.Cu")
		(net "PE_RX1_DR0_N")
	)
	(segment
		(start 1.868932 -416.741864)
		(end 3.658108 -416.741864)
		(width 0.174752)
		(layer "B.Cu")
		(net "PE_RX1_DR0_N")
	)
	(segment
		(start 3.905504 -416.98926)
		(end 4.826 -416.98926)
		(width 0.174752)
		(layer "B.Cu")
		(net "PE_RX1_DR0_N")
	)
	(segment
		(start 4.826 -416.98926)
		(end 5.08 -416.73526)
		(width 0.174752)
		(layer "B.Cu")
		(net "PE_RX1_DR0_N")
	)
	(segment
		(start 3.658108 -416.741864)
		(end 3.905504 -416.98926)
		(width 0.174752)
		(layer "B.Cu")
		(net "PE_RX1_DR0_N")
	)
	(segment
		(start 21.192236 -454.128124)
		(end 20.198588 -452.708772)
		(width 0.1651)
		(layer "In2.Cu")
		(net "PE_RX1_DR0_N")
	)
	(segment
		(start 211.000086 -470.877138)
		(end 41.684448 -440.959494)
		(width 0.1651)
		(layer "In2.Cu")
		(net "PE_RX1_DR0_N")
	)
	(segment
		(start 34.727896 -444.749682)
		(end 29.571696 -452.114412)
		(width 0.1651)
		(layer "In2.Cu")
		(net "PE_RX1_DR0_N")
	)
	(segment
		(start 41.684448 -440.959494)
		(end 39.481252 -441.348114)
		(width 0.1651)
		(layer "In2.Cu")
		(net "PE_RX1_DR0_N")
	)
	(segment
		(start 12.042648 -423.440352)
		(end 8.16864 -417.906708)
		(width 0.1651)
		(layer "In2.Cu")
		(net "PE_RX1_DR0_N")
	)
	(segment
		(start 17.82191 -451.025768)
		(end 16.61922 -449.307966)
		(width 0.1651)
		(layer "In2.Cu")
		(net "PE_RX1_DR0_N")
	)
	(segment
		(start 20.198588 -452.708772)
		(end 17.884394 -451.088252)
		(width 0.1651)
		(layer "In2.Cu")
		(net "PE_RX1_DR0_N")
	)
	(segment
		(start 220.440758 -469.212422)
		(end 211.000086 -470.877138)
		(width 0.1651)
		(layer "In2.Cu")
		(net "PE_RX1_DR0_N")
	)
	(segment
		(start 39.481252 -441.348114)
		(end 34.970974 -444.506604)
		(width 0.1651)
		(layer "In2.Cu")
		(net "PE_RX1_DR0_N")
	)
	(segment
		(start 16.591788 -449.241926)
		(end 12.042648 -423.440352)
		(width 0.1651)
		(layer "In2.Cu")
		(net "PE_RX1_DR0_N")
	)
	(segment
		(start 23.128478 -454.744836)
		(end 23.127462 -454.744582)
		(width 0.1651)
		(layer "In2.Cu")
		(net "PE_RX1_DR0_N")
	)
	(segment
		(start 7.036562 -417.114482)
		(end 6.184138 -416.964114)
		(width 0.1651)
		(layer "In2.Cu")
		(net "PE_RX1_DR0_N")
	)
	(segment
		(start 23.127462 -454.744582)
		(end 23.127462 -454.74509)
		(width 0.1651)
		(layer "In2.Cu")
		(net "PE_RX1_DR0_N")
	)
	(segment
		(start 29.509212 -452.176896)
		(end 26.77033 -454.094342)
		(width 0.1651)
		(layer "In2.Cu")
		(net "PE_RX1_DR0_N")
	)
	(segment
		(start 5.308854 -416.964114)
		(end 5.08 -416.73526)
		(width 0.1651)
		(layer "In2.Cu")
		(net "PE_RX1_DR0_N")
	)
	(segment
		(start 8.16864 -417.906708)
		(end 7.036562 -417.114482)
		(width 0.1651)
		(layer "In2.Cu")
		(net "PE_RX1_DR0_N")
	)
	(segment
		(start 221.346014 -469.212422)
		(end 220.440758 -469.212422)
		(width 0.1651)
		(layer "In2.Cu")
		(net "PE_RX1_DR0_N")
	)
	(segment
		(start 23.127462 -454.74509)
		(end 21.73097 -454.498202)
		(width 0.1651)
		(layer "In2.Cu")
		(net "PE_RX1_DR0_N")
	)
	(segment
		(start 26.66873 -454.136506)
		(end 23.21687 -454.744836)
		(width 0.1651)
		(layer "In2.Cu")
		(net "PE_RX1_DR0_N")
	)
	(segment
		(start 21.66493 -454.471024)
		(end 21.232876 -454.168764)
		(width 0.1651)
		(layer "In2.Cu")
		(net "PE_RX1_DR0_N")
	)
	(segment
		(start 6.184138 -416.964114)
		(end 5.308854 -416.964114)
		(width 0.1651)
		(layer "In2.Cu")
		(net "PE_RX1_DR0_N")
	)
	(segment
		(start 221.727014 -468.831422)
		(end 221.346014 -469.212422)
		(width 0.1651)
		(layer "In2.Cu")
		(net "PE_RX1_DR0_N")
	)
	(arc
		(start 29.571696 -452.114412)
		(mid 29.543193 -452.148393)
		(end 29.509212 -452.176896)
		(width 0.1651)
		(layer "In2.Cu")
		(net "PE_RX1_DR0_N")
	)
	(arc
		(start 21.232876 -454.168764)
		(mid 21.210776 -454.150224)
		(end 21.192236 -454.128124)
		(width 0.1651)
		(layer "In2.Cu")
		(net "PE_RX1_DR0_N")
	)
	(arc
		(start 26.77033 -454.094342)
		(mid 26.721835 -454.120973)
		(end 26.66873 -454.136506)
		(width 0.1651)
		(layer "In2.Cu")
		(net "PE_RX1_DR0_N")
	)
	(arc
		(start 21.73097 -454.498202)
		(mid 21.696453 -454.488246)
		(end 21.66493 -454.471024)
		(width 0.1651)
		(layer "In2.Cu")
		(net "PE_RX1_DR0_N")
	)
	(arc
		(start 23.21687 -454.744836)
		(mid 23.172674 -454.748713)
		(end 23.128478 -454.744836)
		(width 0.1651)
		(layer "In2.Cu")
		(net "PE_RX1_DR0_N")
	)
	(arc
		(start 34.970974 -444.506604)
		(mid 34.838809 -444.617517)
		(end 34.727896 -444.749682)
		(width 0.1651)
		(layer "In2.Cu")
		(net "PE_RX1_DR0_N")
	)
	(arc
		(start 17.884394 -451.088252)
		(mid 17.850413 -451.059749)
		(end 17.82191 -451.025768)
		(width 0.1651)
		(layer "In2.Cu")
		(net "PE_RX1_DR0_N")
	)
	(arc
		(start 16.61922 -449.307966)
		(mid 16.601905 -449.276444)
		(end 16.591788 -449.241926)
		(width 0.1651)
		(layer "In2.Cu")
		(net "PE_RX1_DR0_N")
	)
	(segment
		(start 58.537094 -61.138054)
		(end 58.409332 -61.265816)
		(width 0.174752)
		(layer "F.Cu")
		(net "PE_CLK100M_DR9_2_P")
	)
	(segment
		(start 73.838054 -61.138054)
		(end 58.537094 -61.138054)
		(width 0.174752)
		(layer "F.Cu")
		(net "PE_CLK100M_DR9_2_P")
	)
	(segment
		(start 53.26126 -61.265816)
		(end 53.133498 -61.138054)
		(width 0.174752)
		(layer "F.Cu")
		(net "PE_CLK100M_DR9_2_P")
	)
	(segment
		(start 56.453278 -61.138054)
		(end 53.913278 -61.138054)
		(width 0.174752)
		(layer "F.Cu")
		(net "PE_CLK100M_DR9_2_P")
	)
	(segment
		(start 57.885076 -61.265816)
		(end 57.757314 -61.138054)
		(width 0.174752)
		(layer "F.Cu")
		(net "PE_CLK100M_DR9_2_P")
	)
	(segment
		(start 51.829462 -61.138054)
		(end 51.305206 -61.138054)
		(width 0.174752)
		(layer "F.Cu")
		(net "PE_CLK100M_DR9_2_P")
	)
	(segment
		(start 53.785516 -61.265816)
		(end 53.26126 -61.265816)
		(width 0.174752)
		(layer "F.Cu")
		(net "PE_CLK100M_DR9_2_P")
	)
	(segment
		(start 43.434 -60.589922)
		(end 43.68165 -60.837572)
		(width 0.174752)
		(layer "F.Cu")
		(net "PE_CLK100M_DR9_2_P")
	)
	(segment
		(start 51.957224 -61.265816)
		(end 51.829462 -61.138054)
		(width 0.174752)
		(layer "F.Cu")
		(net "PE_CLK100M_DR9_2_P")
	)
	(segment
		(start 86.487 -92.5195)
		(end 86.842346 -92.164154)
		(width 0.174752)
		(layer "F.Cu")
		(net "PE_CLK100M_DR9_2_P")
	)
	(segment
		(start 53.133498 -61.138054)
		(end 52.609242 -61.138054)
		(width 0.174752)
		(layer "F.Cu")
		(net "PE_CLK100M_DR9_2_P")
	)
	(segment
		(start 50.525426 -61.138054)
		(end 48.641 -61.138054)
		(width 0.174752)
		(layer "F.Cu")
		(net "PE_CLK100M_DR9_2_P")
	)
	(segment
		(start 42.39006 -60.589922)
		(end 43.434 -60.589922)
		(width 0.174752)
		(layer "F.Cu")
		(net "PE_CLK100M_DR9_2_P")
	)
	(segment
		(start 57.105296 -61.265816)
		(end 56.58104 -61.265816)
		(width 0.174752)
		(layer "F.Cu")
		(net "PE_CLK100M_DR9_2_P")
	)
	(segment
		(start 57.233058 -61.138054)
		(end 57.105296 -61.265816)
		(width 0.174752)
		(layer "F.Cu")
		(net "PE_CLK100M_DR9_2_P")
	)
	(segment
		(start 51.305206 -61.138054)
		(end 51.177444 -61.265816)
		(width 0.174752)
		(layer "F.Cu")
		(net "PE_CLK100M_DR9_2_P")
	)
	(segment
		(start 53.913278 -61.138054)
		(end 53.785516 -61.265816)
		(width 0.174752)
		(layer "F.Cu")
		(net "PE_CLK100M_DR9_2_P")
	)
	(segment
		(start 45.160946 -60.043822)
		(end 44.9072 -59.790076)
		(width 0.174752)
		(layer "F.Cu")
		(net "PE_CLK100M_DR9_2_P")
	)
	(segment
		(start 86.054946 -90.982292)
		(end 86.054946 -73.354946)
		(width 0.174752)
		(layer "F.Cu")
		(net "PE_CLK100M_DR9_2_P")
	)
	(segment
		(start 86.842346 -92.164154)
		(end 86.842346 -91.769692)
		(width 0.174752)
		(layer "F.Cu")
		(net "PE_CLK100M_DR9_2_P")
	)
	(segment
		(start 48.641 -61.138054)
		(end 48.387 -61.392054)
		(width 0.174752)
		(layer "F.Cu")
		(net "PE_CLK100M_DR9_2_P")
	)
	(segment
		(start 86.054946 -73.354946)
		(end 73.838054 -61.138054)
		(width 0.174752)
		(layer "F.Cu")
		(net "PE_CLK100M_DR9_2_P")
	)
	(segment
		(start 52.48148 -61.265816)
		(end 51.957224 -61.265816)
		(width 0.174752)
		(layer "F.Cu")
		(net "PE_CLK100M_DR9_2_P")
	)
	(segment
		(start 56.58104 -61.265816)
		(end 56.453278 -61.138054)
		(width 0.174752)
		(layer "F.Cu")
		(net "PE_CLK100M_DR9_2_P")
	)
	(segment
		(start 57.757314 -61.138054)
		(end 57.233058 -61.138054)
		(width 0.174752)
		(layer "F.Cu")
		(net "PE_CLK100M_DR9_2_P")
	)
	(segment
		(start 50.653188 -61.265816)
		(end 50.525426 -61.138054)
		(width 0.174752)
		(layer "F.Cu")
		(net "PE_CLK100M_DR9_2_P")
	)
	(segment
		(start 45.160946 -60.579508)
		(end 45.160946 -60.043822)
		(width 0.174752)
		(layer "F.Cu")
		(net "PE_CLK100M_DR9_2_P")
	)
	(segment
		(start 44.902882 -60.837572)
		(end 45.160946 -60.579508)
		(width 0.174752)
		(layer "F.Cu")
		(net "PE_CLK100M_DR9_2_P")
	)
	(segment
		(start 52.609242 -61.138054)
		(end 52.48148 -61.265816)
		(width 0.174752)
		(layer "F.Cu")
		(net "PE_CLK100M_DR9_2_P")
	)
	(segment
		(start 58.409332 -61.265816)
		(end 57.885076 -61.265816)
		(width 0.174752)
		(layer "F.Cu")
		(net "PE_CLK100M_DR9_2_P")
	)
	(segment
		(start 86.842346 -91.769692)
		(end 86.054946 -90.982292)
		(width 0.174752)
		(layer "F.Cu")
		(net "PE_CLK100M_DR9_2_P")
	)
	(segment
		(start 51.177444 -61.265816)
		(end 50.653188 -61.265816)
		(width 0.174752)
		(layer "F.Cu")
		(net "PE_CLK100M_DR9_2_P")
	)
	(segment
		(start 43.68165 -60.837572)
		(end 44.902882 -60.837572)
		(width 0.174752)
		(layer "F.Cu")
		(net "PE_CLK100M_DR9_2_P")
	)
	(via
		(at 48.387 -61.392054)
		(size 0.508)
		(drill 0.254)
		(layers "F.Cu" "B.Cu")
		(net "PE_CLK100M_DR9_2_P")
	)
	(via
		(at 44.9072 -59.790076)
		(size 0.508)
		(drill 0.254)
		(layers "F.Cu" "B.Cu")
		(net "PE_CLK100M_DR9_2_P")
	)
	(segment
		(start 45.593508 -61.138054)
		(end 45.160946 -60.705492)
		(width 0.174752)
		(layer "B.Cu")
		(net "PE_CLK100M_DR9_2_P")
	)
	(segment
		(start 45.160946 -60.043822)
		(end 44.9072 -59.790076)
		(width 0.174752)
		(layer "B.Cu")
		(net "PE_CLK100M_DR9_2_P")
	)
	(segment
		(start 48.387 -61.392054)
		(end 48.133 -61.138054)
		(width 0.174752)
		(layer "B.Cu")
		(net "PE_CLK100M_DR9_2_P")
	)
	(segment
		(start 48.133 -61.138054)
		(end 45.593508 -61.138054)
		(width 0.174752)
		(layer "B.Cu")
		(net "PE_CLK100M_DR9_2_P")
	)
	(segment
		(start 45.160946 -60.705492)
		(end 45.160946 -60.043822)
		(width 0.174752)
		(layer "B.Cu")
		(net "PE_CLK100M_DR9_2_P")
	)
	(segment
		(start 86.36 -90.8558)
		(end 86.36 -73.228454)
		(width 0.174752)
		(layer "F.Cu")
		(net "PE_CLK100M_DR9_2_N")
	)
	(segment
		(start 86.36 -73.228454)
		(end 73.964546 -60.833)
		(width 0.174752)
		(layer "F.Cu")
		(net "PE_CLK100M_DR9_2_N")
	)
	(segment
		(start 45.029374 -61.142626)
		(end 45.466 -60.706)
		(width 0.174752)
		(layer "F.Cu")
		(net "PE_CLK100M_DR9_2_N")
	)
	(segment
		(start 87.1474 -92.1639)
		(end 87.1474 -91.6432)
		(width 0.174752)
		(layer "F.Cu")
		(net "PE_CLK100M_DR9_2_N")
	)
	(segment
		(start 43.688 -61.142626)
		(end 45.029374 -61.142626)
		(width 0.174752)
		(layer "F.Cu")
		(net "PE_CLK100M_DR9_2_N")
	)
	(segment
		(start 73.964546 -60.833)
		(end 48.640746 -60.833)
		(width 0.174752)
		(layer "F.Cu")
		(net "PE_CLK100M_DR9_2_N")
	)
	(segment
		(start 87.503 -92.5195)
		(end 87.1474 -92.1639)
		(width 0.174752)
		(layer "F.Cu")
		(net "PE_CLK100M_DR9_2_N")
	)
	(segment
		(start 45.466 -60.044076)
		(end 45.72 -59.790076)
		(width 0.174752)
		(layer "F.Cu")
		(net "PE_CLK100M_DR9_2_N")
	)
	(segment
		(start 48.640746 -60.833)
		(end 48.387 -60.579254)
		(width 0.174752)
		(layer "F.Cu")
		(net "PE_CLK100M_DR9_2_N")
	)
	(segment
		(start 42.39006 -61.390022)
		(end 43.440604 -61.390022)
		(width 0.174752)
		(layer "F.Cu")
		(net "PE_CLK100M_DR9_2_N")
	)
	(segment
		(start 45.466 -60.706)
		(end 45.466 -60.044076)
		(width 0.174752)
		(layer "F.Cu")
		(net "PE_CLK100M_DR9_2_N")
	)
	(segment
		(start 87.1474 -91.6432)
		(end 86.36 -90.8558)
		(width 0.174752)
		(layer "F.Cu")
		(net "PE_CLK100M_DR9_2_N")
	)
	(segment
		(start 43.440604 -61.390022)
		(end 43.688 -61.142626)
		(width 0.174752)
		(layer "F.Cu")
		(net "PE_CLK100M_DR9_2_N")
	)
	(via
		(at 48.387 -60.579254)
		(size 0.508)
		(drill 0.254)
		(layers "F.Cu" "B.Cu")
		(net "PE_CLK100M_DR9_2_N")
	)
	(via
		(at 45.72 -59.790076)
		(size 0.508)
		(drill 0.254)
		(layers "F.Cu" "B.Cu")
		(net "PE_CLK100M_DR9_2_N")
	)
	(segment
		(start 45.72 -60.833)
		(end 45.466 -60.579)
		(width 0.174752)
		(layer "B.Cu")
		(net "PE_CLK100M_DR9_2_N")
	)
	(segment
		(start 45.466 -60.044076)
		(end 45.72 -59.790076)
		(width 0.174752)
		(layer "B.Cu")
		(net "PE_CLK100M_DR9_2_N")
	)
	(segment
		(start 48.133254 -60.833)
		(end 45.72 -60.833)
		(width 0.174752)
		(layer "B.Cu")
		(net "PE_CLK100M_DR9_2_N")
	)
	(segment
		(start 45.466 -60.579)
		(end 45.466 -60.044076)
		(width 0.174752)
		(layer "B.Cu")
		(net "PE_CLK100M_DR9_2_N")
	)
	(segment
		(start 48.387 -60.579254)
		(end 48.133254 -60.833)
		(width 0.174752)
		(layer "B.Cu")
		(net "PE_CLK100M_DR9_2_N")
	)
	(segment
		(start 53.234082 -57.26557)
		(end 52.709826 -57.26557)
		(width 0.174752)
		(layer "F.Cu")
		(net "PE_CLK100M_DR9_1_P")
	)
	(segment
		(start 64.414908 -57.26557)
		(end 64.287146 -57.137808)
		(width 0.174752)
		(layer "F.Cu")
		(net "PE_CLK100M_DR9_1_P")
	)
	(segment
		(start 61.897768 -57.137808)
		(end 61.770006 -57.26557)
		(width 0.174752)
		(layer "F.Cu")
		(net "PE_CLK100M_DR9_1_P")
	)
	(segment
		(start 50.079402 -55.339996)
		(end 50.079402 -55.159402)
		(width 0.174752)
		(layer "F.Cu")
		(net "PE_CLK100M_DR9_1_P")
	)
	(segment
		(start 46.809914 -52.070508)
		(end 46.809914 -51.889914)
		(width 0.174752)
		(layer "F.Cu")
		(net "PE_CLK100M_DR9_1_P")
	)
	(segment
		(start 50.079402 -55.159402)
		(end 48.283368 -53.363368)
		(width 0.174752)
		(layer "F.Cu")
		(net "PE_CLK100M_DR9_1_P")
	)
	(segment
		(start 50.630836 -55.710836)
		(end 50.449988 -55.710836)
		(width 0.174752)
		(layer "F.Cu")
		(net "PE_CLK100M_DR9_1_P")
	)
	(segment
		(start 66.2432 -57.26557)
		(end 65.718944 -57.26557)
		(width 0.174752)
		(layer "F.Cu")
		(net "PE_CLK100M_DR9_1_P")
	)
	(segment
		(start 59.941714 -57.26557)
		(end 59.813952 -57.137808)
		(width 0.174752)
		(layer "F.Cu")
		(net "PE_CLK100M_DR9_1_P")
	)
	(segment
		(start 37.591492 -50.597054)
		(end 36.957 -51.231546)
		(width 0.174752)
		(layer "F.Cu")
		(net "PE_CLK100M_DR9_1_P")
	)
	(segment
		(start 67.02298 -57.26557)
		(end 66.895218 -57.137808)
		(width 0.174752)
		(layer "F.Cu")
		(net "PE_CLK100M_DR9_1_P")
	)
	(segment
		(start 60.593732 -57.137808)
		(end 60.46597 -57.26557)
		(width 0.174752)
		(layer "F.Cu")
		(net "PE_CLK100M_DR9_1_P")
	)
	(segment
		(start 59.161934 -57.26557)
		(end 58.637678 -57.26557)
		(width 0.174752)
		(layer "F.Cu")
		(net "PE_CLK100M_DR9_1_P")
	)
	(segment
		(start 54.66588 -57.137808)
		(end 54.538118 -57.26557)
		(width 0.174752)
		(layer "F.Cu")
		(net "PE_CLK100M_DR9_1_P")
	)
	(segment
		(start 64.939164 -57.26557)
		(end 64.414908 -57.26557)
		(width 0.174752)
		(layer "F.Cu")
		(net "PE_CLK100M_DR9_1_P")
	)
	(segment
		(start 52.582064 -57.137808)
		(end 52.057808 -57.137808)
		(width 0.174752)
		(layer "F.Cu")
		(net "PE_CLK100M_DR9_1_P")
	)
	(segment
		(start 72.950832 -57.26557)
		(end 72.82307 -57.137808)
		(width 0.174752)
		(layer "F.Cu")
		(net "PE_CLK100M_DR9_1_P")
	)
	(segment
		(start 72.82307 -57.137808)
		(end 67.674998 -57.137808)
		(width 0.174752)
		(layer "F.Cu")
		(net "PE_CLK100M_DR9_1_P")
	)
	(segment
		(start 67.674998 -57.137808)
		(end 67.547236 -57.26557)
		(width 0.174752)
		(layer "F.Cu")
		(net "PE_CLK100M_DR9_1_P")
	)
	(segment
		(start 55.969916 -57.137808)
		(end 55.842154 -57.26557)
		(width 0.174752)
		(layer "F.Cu")
		(net "PE_CLK100M_DR9_1_P")
	)
	(segment
		(start 73.60285 -57.137808)
		(end 73.475088 -57.26557)
		(width 0.174752)
		(layer "F.Cu")
		(net "PE_CLK100M_DR9_1_P")
	)
	(segment
		(start 61.770006 -57.26557)
		(end 61.24575 -57.26557)
		(width 0.174752)
		(layer "F.Cu")
		(net "PE_CLK100M_DR9_1_P")
	)
	(segment
		(start 52.057808 -57.137808)
		(end 50.630836 -55.710836)
		(width 0.174752)
		(layer "F.Cu")
		(net "PE_CLK100M_DR9_1_P")
	)
	(segment
		(start 45.517054 -50.597054)
		(end 37.591492 -50.597054)
		(width 0.174752)
		(layer "F.Cu")
		(net "PE_CLK100M_DR9_1_P")
	)
	(segment
		(start 36.957 -51.943)
		(end 37.451284 -52.437284)
		(width 0.174752)
		(layer "F.Cu")
		(net "PE_CLK100M_DR9_1_P")
	)
	(segment
		(start 48.102774 -53.363368)
		(end 47.731934 -52.992528)
		(width 0.174752)
		(layer "F.Cu")
		(net "PE_CLK100M_DR9_1_P")
	)
	(segment
		(start 53.8861 -57.137808)
		(end 53.361844 -57.137808)
		(width 0.174752)
		(layer "F.Cu")
		(net "PE_CLK100M_DR9_1_P")
	)
	(segment
		(start 38.093396 -52.189888)
		(end 39.200074 -52.189888)
		(width 0.174752)
		(layer "F.Cu")
		(net "PE_CLK100M_DR9_1_P")
	)
	(segment
		(start 91.896946 -90.297508)
		(end 91.896946 -74.907648)
		(width 0.174752)
		(layer "F.Cu")
		(net "PE_CLK100M_DR9_1_P")
	)
	(segment
		(start 47.731934 -52.992528)
		(end 47.731934 -52.811934)
		(width 0.174752)
		(layer "F.Cu")
		(net "PE_CLK100M_DR9_1_P")
	)
	(segment
		(start 90.297 -92.5195)
		(end 90.703146 -92.113354)
		(width 0.174752)
		(layer "F.Cu")
		(net "PE_CLK100M_DR9_1_P")
	)
	(segment
		(start 54.013862 -57.26557)
		(end 53.8861 -57.137808)
		(width 0.174752)
		(layer "F.Cu")
		(net "PE_CLK100M_DR9_1_P")
	)
	(segment
		(start 53.361844 -57.137808)
		(end 53.234082 -57.26557)
		(width 0.174752)
		(layer "F.Cu")
		(net "PE_CLK100M_DR9_1_P")
	)
	(segment
		(start 55.190136 -57.137808)
		(end 54.66588 -57.137808)
		(width 0.174752)
		(layer "F.Cu")
		(net "PE_CLK100M_DR9_1_P")
	)
	(segment
		(start 36.957 -51.231546)
		(end 36.957 -51.943)
		(width 0.174752)
		(layer "F.Cu")
		(net "PE_CLK100M_DR9_1_P")
	)
	(segment
		(start 46.25848 -51.519074)
		(end 45.88764 -51.148488)
		(width 0.174752)
		(layer "F.Cu")
		(net "PE_CLK100M_DR9_1_P")
	)
	(segment
		(start 47.1805 -52.441348)
		(end 46.809914 -52.070508)
		(width 0.174752)
		(layer "F.Cu")
		(net "PE_CLK100M_DR9_1_P")
	)
	(segment
		(start 47.731934 -52.811934)
		(end 47.361348 -52.441348)
		(width 0.174752)
		(layer "F.Cu")
		(net "PE_CLK100M_DR9_1_P")
	)
	(segment
		(start 67.547236 -57.26557)
		(end 67.02298 -57.26557)
		(width 0.174752)
		(layer "F.Cu")
		(net "PE_CLK100M_DR9_1_P")
	)
	(segment
		(start 65.591182 -57.137808)
		(end 65.066926 -57.137808)
		(width 0.174752)
		(layer "F.Cu")
		(net "PE_CLK100M_DR9_1_P")
	)
	(segment
		(start 66.370962 -57.137808)
		(end 66.2432 -57.26557)
		(width 0.174752)
		(layer "F.Cu")
		(net "PE_CLK100M_DR9_1_P")
	)
	(segment
		(start 61.24575 -57.26557)
		(end 61.117988 -57.137808)
		(width 0.174752)
		(layer "F.Cu")
		(net "PE_CLK100M_DR9_1_P")
	)
	(segment
		(start 59.813952 -57.137808)
		(end 59.289696 -57.137808)
		(width 0.174752)
		(layer "F.Cu")
		(net "PE_CLK100M_DR9_1_P")
	)
	(segment
		(start 47.361348 -52.441348)
		(end 47.1805 -52.441348)
		(width 0.174752)
		(layer "F.Cu")
		(net "PE_CLK100M_DR9_1_P")
	)
	(segment
		(start 90.703146 -92.113354)
		(end 90.703146 -91.491308)
		(width 0.174752)
		(layer "F.Cu")
		(net "PE_CLK100M_DR9_1_P")
	)
	(segment
		(start 52.709826 -57.26557)
		(end 52.582064 -57.137808)
		(width 0.174752)
		(layer "F.Cu")
		(net "PE_CLK100M_DR9_1_P")
	)
	(segment
		(start 64.287146 -57.137808)
		(end 61.897768 -57.137808)
		(width 0.174752)
		(layer "F.Cu")
		(net "PE_CLK100M_DR9_1_P")
	)
	(segment
		(start 45.88764 -51.148488)
		(end 45.88764 -50.96764)
		(width 0.174752)
		(layer "F.Cu")
		(net "PE_CLK100M_DR9_1_P")
	)
	(segment
		(start 65.718944 -57.26557)
		(end 65.591182 -57.137808)
		(width 0.174752)
		(layer "F.Cu")
		(net "PE_CLK100M_DR9_1_P")
	)
	(segment
		(start 65.066926 -57.137808)
		(end 64.939164 -57.26557)
		(width 0.174752)
		(layer "F.Cu")
		(net "PE_CLK100M_DR9_1_P")
	)
	(segment
		(start 55.842154 -57.26557)
		(end 55.317898 -57.26557)
		(width 0.174752)
		(layer "F.Cu")
		(net "PE_CLK100M_DR9_1_P")
	)
	(segment
		(start 73.475088 -57.26557)
		(end 72.950832 -57.26557)
		(width 0.174752)
		(layer "F.Cu")
		(net "PE_CLK100M_DR9_1_P")
	)
	(segment
		(start 46.439074 -51.519074)
		(end 46.25848 -51.519074)
		(width 0.174752)
		(layer "F.Cu")
		(net "PE_CLK100M_DR9_1_P")
	)
	(segment
		(start 54.538118 -57.26557)
		(end 54.013862 -57.26557)
		(width 0.174752)
		(layer "F.Cu")
		(net "PE_CLK100M_DR9_1_P")
	)
	(segment
		(start 66.895218 -57.137808)
		(end 66.370962 -57.137808)
		(width 0.174752)
		(layer "F.Cu")
		(net "PE_CLK100M_DR9_1_P")
	)
	(segment
		(start 45.88764 -50.96764)
		(end 45.517054 -50.597054)
		(width 0.174752)
		(layer "F.Cu")
		(net "PE_CLK100M_DR9_1_P")
	)
	(segment
		(start 50.449988 -55.710836)
		(end 50.079402 -55.339996)
		(width 0.174752)
		(layer "F.Cu")
		(net "PE_CLK100M_DR9_1_P")
	)
	(segment
		(start 74.127106 -57.137808)
		(end 73.60285 -57.137808)
		(width 0.174752)
		(layer "F.Cu")
		(net "PE_CLK100M_DR9_1_P")
	)
	(segment
		(start 48.283368 -53.363368)
		(end 48.102774 -53.363368)
		(width 0.174752)
		(layer "F.Cu")
		(net "PE_CLK100M_DR9_1_P")
	)
	(segment
		(start 60.46597 -57.26557)
		(end 59.941714 -57.26557)
		(width 0.174752)
		(layer "F.Cu")
		(net "PE_CLK100M_DR9_1_P")
	)
	(segment
		(start 59.289696 -57.137808)
		(end 59.161934 -57.26557)
		(width 0.174752)
		(layer "F.Cu")
		(net "PE_CLK100M_DR9_1_P")
	)
	(segment
		(start 61.117988 -57.137808)
		(end 60.593732 -57.137808)
		(width 0.174752)
		(layer "F.Cu")
		(net "PE_CLK100M_DR9_1_P")
	)
	(segment
		(start 46.809914 -51.889914)
		(end 46.439074 -51.519074)
		(width 0.174752)
		(layer "F.Cu")
		(net "PE_CLK100M_DR9_1_P")
	)
	(segment
		(start 37.846 -52.437284)
		(end 38.093396 -52.189888)
		(width 0.174752)
		(layer "F.Cu")
		(net "PE_CLK100M_DR9_1_P")
	)
	(segment
		(start 37.451284 -52.437284)
		(end 37.846 -52.437284)
		(width 0.174752)
		(layer "F.Cu")
		(net "PE_CLK100M_DR9_1_P")
	)
	(segment
		(start 91.896946 -74.907648)
		(end 74.127106 -57.137808)
		(width 0.174752)
		(layer "F.Cu")
		(net "PE_CLK100M_DR9_1_P")
	)
	(segment
		(start 58.509916 -57.137808)
		(end 55.969916 -57.137808)
		(width 0.174752)
		(layer "F.Cu")
		(net "PE_CLK100M_DR9_1_P")
	)
	(segment
		(start 90.703146 -91.491308)
		(end 91.896946 -90.297508)
		(width 0.174752)
		(layer "F.Cu")
		(net "PE_CLK100M_DR9_1_P")
	)
	(segment
		(start 58.637678 -57.26557)
		(end 58.509916 -57.137808)
		(width 0.174752)
		(layer "F.Cu")
		(net "PE_CLK100M_DR9_1_P")
	)
	(segment
		(start 55.317898 -57.26557)
		(end 55.190136 -57.137808)
		(width 0.174752)
		(layer "F.Cu")
		(net "PE_CLK100M_DR9_1_P")
	)
	(segment
		(start 74.253598 -56.832754)
		(end 52.1843 -56.832754)
		(width 0.174752)
		(layer "F.Cu")
		(net "PE_CLK100M_DR9_1_N")
	)
	(segment
		(start 38.09365 -52.989988)
		(end 39.200074 -52.989988)
		(width 0.174752)
		(layer "F.Cu")
		(net "PE_CLK100M_DR9_1_N")
	)
	(segment
		(start 37.465 -50.292)
		(end 36.651946 -51.105054)
		(width 0.174752)
		(layer "F.Cu")
		(net "PE_CLK100M_DR9_1_N")
	)
	(segment
		(start 45.643546 -50.292)
		(end 37.465 -50.292)
		(width 0.174752)
		(layer "F.Cu")
		(net "PE_CLK100M_DR9_1_N")
	)
	(segment
		(start 37.846 -52.742338)
		(end 38.09365 -52.989988)
		(width 0.174752)
		(layer "F.Cu")
		(net "PE_CLK100M_DR9_1_N")
	)
	(segment
		(start 37.324792 -52.742338)
		(end 37.846 -52.742338)
		(width 0.174752)
		(layer "F.Cu")
		(net "PE_CLK100M_DR9_1_N")
	)
	(segment
		(start 92.202 -74.781156)
		(end 74.253598 -56.832754)
		(width 0.174752)
		(layer "F.Cu")
		(net "PE_CLK100M_DR9_1_N")
	)
	(segment
		(start 91.0082 -92.2147)
		(end 91.0082 -91.6178)
		(width 0.174752)
		(layer "F.Cu")
		(net "PE_CLK100M_DR9_1_N")
	)
	(segment
		(start 92.202 -90.424)
		(end 92.202 -74.781156)
		(width 0.174752)
		(layer "F.Cu")
		(net "PE_CLK100M_DR9_1_N")
	)
	(segment
		(start 36.651946 -51.105054)
		(end 36.651946 -52.069492)
		(width 0.174752)
		(layer "F.Cu")
		(net "PE_CLK100M_DR9_1_N")
	)
	(segment
		(start 52.1843 -56.832754)
		(end 45.643546 -50.292)
		(width 0.174752)
		(layer "F.Cu")
		(net "PE_CLK100M_DR9_1_N")
	)
	(segment
		(start 36.651946 -52.069492)
		(end 37.324792 -52.742338)
		(width 0.174752)
		(layer "F.Cu")
		(net "PE_CLK100M_DR9_1_N")
	)
	(segment
		(start 91.0082 -91.6178)
		(end 92.202 -90.424)
		(width 0.174752)
		(layer "F.Cu")
		(net "PE_CLK100M_DR9_1_N")
	)
	(segment
		(start 91.313 -92.5195)
		(end 91.0082 -92.2147)
		(width 0.174752)
		(layer "F.Cu")
		(net "PE_CLK100M_DR9_1_N")
	)
	(segment
		(start 45.160946 -163.04387)
		(end 44.9072 -162.790124)
		(width 0.174752)
		(layer "F.Cu")
		(net "PE_CLK100M_DR8_2_P")
	)
	(segment
		(start 99.949254 -111.061246)
		(end 99.949254 -111.379508)
		(width 0.174752)
		(layer "F.Cu")
		(net "PE_CLK100M_DR8_2_P")
	)
	(segment
		(start 44.902882 -163.83762)
		(end 45.160946 -163.579556)
		(width 0.174752)
		(layer "F.Cu")
		(net "PE_CLK100M_DR8_2_P")
	)
	(segment
		(start 43.434 -163.58997)
		(end 43.68165 -163.83762)
		(width 0.174752)
		(layer "F.Cu")
		(net "PE_CLK100M_DR8_2_P")
	)
	(segment
		(start 48.641 -164.138102)
		(end 48.387 -164.392102)
		(width 0.174752)
		(layer "F.Cu")
		(net "PE_CLK100M_DR8_2_P")
	)
	(segment
		(start 50.978054 -156.036772)
		(end 50.978054 -162.813492)
		(width 0.174752)
		(layer "F.Cu")
		(net "PE_CLK100M_DR8_2_P")
	)
	(segment
		(start 86.298786 -132.69976)
		(end 74.314812 -132.69976)
		(width 0.174752)
		(layer "F.Cu")
		(net "PE_CLK100M_DR8_2_P")
	)
	(segment
		(start 99.949254 -111.379508)
		(end 100.762054 -112.192308)
		(width 0.174752)
		(layer "F.Cu")
		(net "PE_CLK100M_DR8_2_P")
	)
	(segment
		(start 45.160946 -163.579556)
		(end 45.160946 -163.04387)
		(width 0.174752)
		(layer "F.Cu")
		(net "PE_CLK100M_DR8_2_P")
	)
	(segment
		(start 100.33 -110.6805)
		(end 99.949254 -111.061246)
		(width 0.174752)
		(layer "F.Cu")
		(net "PE_CLK100M_DR8_2_P")
	)
	(segment
		(start 42.39006 -163.58997)
		(end 43.434 -163.58997)
		(width 0.174752)
		(layer "F.Cu")
		(net "PE_CLK100M_DR8_2_P")
	)
	(segment
		(start 49.653444 -164.138102)
		(end 48.641 -164.138102)
		(width 0.174752)
		(layer "F.Cu")
		(net "PE_CLK100M_DR8_2_P")
	)
	(segment
		(start 50.978054 -162.813492)
		(end 49.653444 -164.138102)
		(width 0.174752)
		(layer "F.Cu")
		(net "PE_CLK100M_DR8_2_P")
	)
	(segment
		(start 100.762054 -118.236492)
		(end 86.298786 -132.69976)
		(width 0.174752)
		(layer "F.Cu")
		(net "PE_CLK100M_DR8_2_P")
	)
	(segment
		(start 43.68165 -163.83762)
		(end 44.902882 -163.83762)
		(width 0.174752)
		(layer "F.Cu")
		(net "PE_CLK100M_DR8_2_P")
	)
	(segment
		(start 74.314812 -132.69976)
		(end 50.978054 -156.036772)
		(width 0.174752)
		(layer "F.Cu")
		(net "PE_CLK100M_DR8_2_P")
	)
	(segment
		(start 100.762054 -112.192308)
		(end 100.762054 -118.236492)
		(width 0.174752)
		(layer "F.Cu")
		(net "PE_CLK100M_DR8_2_P")
	)
	(via
		(at 48.387 -164.392102)
		(size 0.508)
		(drill 0.254)
		(layers "F.Cu" "B.Cu")
		(net "PE_CLK100M_DR8_2_P")
	)
	(via
		(at 44.9072 -162.790124)
		(size 0.508)
		(drill 0.254)
		(layers "F.Cu" "B.Cu")
		(net "PE_CLK100M_DR8_2_P")
	)
	(segment
		(start 45.160946 -163.70554)
		(end 45.160946 -163.04387)
		(width 0.174752)
		(layer "B.Cu")
		(net "PE_CLK100M_DR8_2_P")
	)
	(segment
		(start 48.133 -164.138102)
		(end 45.593508 -164.138102)
		(width 0.174752)
		(layer "B.Cu")
		(net "PE_CLK100M_DR8_2_P")
	)
	(segment
		(start 45.593508 -164.138102)
		(end 45.160946 -163.70554)
		(width 0.174752)
		(layer "B.Cu")
		(net "PE_CLK100M_DR8_2_P")
	)
	(segment
		(start 48.387 -164.392102)
		(end 48.133 -164.138102)
		(width 0.174752)
		(layer "B.Cu")
		(net "PE_CLK100M_DR8_2_P")
	)
	(segment
		(start 45.160946 -163.04387)
		(end 44.9072 -162.790124)
		(width 0.174752)
		(layer "B.Cu")
		(net "PE_CLK100M_DR8_2_P")
	)
	(segment
		(start 42.39006 -164.39007)
		(end 43.440604 -164.39007)
		(width 0.174752)
		(layer "F.Cu")
		(net "PE_CLK100M_DR8_2_N")
	)
	(segment
		(start 50.673 -162.162744)
		(end 50.673 -162.687)
		(width 0.174752)
		(layer "F.Cu")
		(net "PE_CLK100M_DR8_2_N")
	)
	(segment
		(start 99.314 -110.6805)
		(end 99.6442 -111.0107)
		(width 0.174752)
		(layer "F.Cu")
		(net "PE_CLK100M_DR8_2_N")
	)
	(segment
		(start 50.545238 -162.034982)
		(end 50.673 -162.162744)
		(width 0.174752)
		(layer "F.Cu")
		(net "PE_CLK100M_DR8_2_N")
	)
	(segment
		(start 51.59502 -154.98826)
		(end 51.414426 -154.98826)
		(width 0.174752)
		(layer "F.Cu")
		(net "PE_CLK100M_DR8_2_N")
	)
	(segment
		(start 50.545238 -160.20669)
		(end 50.545238 -160.730946)
		(width 0.174752)
		(layer "F.Cu")
		(net "PE_CLK100M_DR8_2_N")
	)
	(segment
		(start 45.466 -163.044124)
		(end 45.72 -162.790124)
		(width 0.174752)
		(layer "F.Cu")
		(net "PE_CLK100M_DR8_2_N")
	)
	(segment
		(start 99.6442 -111.0107)
		(end 99.6442 -111.506)
		(width 0.174752)
		(layer "F.Cu")
		(net "PE_CLK100M_DR8_2_N")
	)
	(segment
		(start 86.172294 -132.394706)
		(end 74.18832 -132.394706)
		(width 0.174752)
		(layer "F.Cu")
		(net "PE_CLK100M_DR8_2_N")
	)
	(segment
		(start 45.029374 -164.142674)
		(end 45.466 -163.706048)
		(width 0.174752)
		(layer "F.Cu")
		(net "PE_CLK100M_DR8_2_N")
	)
	(segment
		(start 50.545238 -160.730946)
		(end 50.673 -160.858708)
		(width 0.174752)
		(layer "F.Cu")
		(net "PE_CLK100M_DR8_2_N")
	)
	(segment
		(start 49.526952 -163.833048)
		(end 48.640746 -163.833048)
		(width 0.174752)
		(layer "F.Cu")
		(net "PE_CLK100M_DR8_2_N")
	)
	(segment
		(start 52.517294 -154.065986)
		(end 52.336446 -154.065986)
		(width 0.174752)
		(layer "F.Cu")
		(net "PE_CLK100M_DR8_2_N")
	)
	(segment
		(start 45.466 -163.706048)
		(end 45.466 -163.044124)
		(width 0.174752)
		(layer "F.Cu")
		(net "PE_CLK100M_DR8_2_N")
	)
	(segment
		(start 51.043586 -155.539694)
		(end 50.673 -155.91028)
		(width 0.174752)
		(layer "F.Cu")
		(net "PE_CLK100M_DR8_2_N")
	)
	(segment
		(start 50.545238 -158.902654)
		(end 50.545238 -159.42691)
		(width 0.174752)
		(layer "F.Cu")
		(net "PE_CLK100M_DR8_2_N")
	)
	(segment
		(start 50.673 -158.774892)
		(end 50.545238 -158.902654)
		(width 0.174752)
		(layer "F.Cu")
		(net "PE_CLK100M_DR8_2_N")
	)
	(segment
		(start 43.440604 -164.39007)
		(end 43.688 -164.142674)
		(width 0.174752)
		(layer "F.Cu")
		(net "PE_CLK100M_DR8_2_N")
	)
	(segment
		(start 50.673 -161.382964)
		(end 50.545238 -161.510726)
		(width 0.174752)
		(layer "F.Cu")
		(net "PE_CLK100M_DR8_2_N")
	)
	(segment
		(start 51.96586 -154.61742)
		(end 51.59502 -154.98826)
		(width 0.174752)
		(layer "F.Cu")
		(net "PE_CLK100M_DR8_2_N")
	)
	(segment
		(start 50.673 -160.858708)
		(end 50.673 -161.382964)
		(width 0.174752)
		(layer "F.Cu")
		(net "PE_CLK100M_DR8_2_N")
	)
	(segment
		(start 100.457 -112.3188)
		(end 100.457 -118.11)
		(width 0.174752)
		(layer "F.Cu")
		(net "PE_CLK100M_DR8_2_N")
	)
	(segment
		(start 50.545238 -161.510726)
		(end 50.545238 -162.034982)
		(width 0.174752)
		(layer "F.Cu")
		(net "PE_CLK100M_DR8_2_N")
	)
	(segment
		(start 51.414426 -154.98826)
		(end 51.043586 -155.358846)
		(width 0.174752)
		(layer "F.Cu")
		(net "PE_CLK100M_DR8_2_N")
	)
	(segment
		(start 52.336446 -154.065986)
		(end 51.96586 -154.436826)
		(width 0.174752)
		(layer "F.Cu")
		(net "PE_CLK100M_DR8_2_N")
	)
	(segment
		(start 48.640746 -163.833048)
		(end 48.387 -163.579302)
		(width 0.174752)
		(layer "F.Cu")
		(net "PE_CLK100M_DR8_2_N")
	)
	(segment
		(start 50.673 -160.078928)
		(end 50.545238 -160.20669)
		(width 0.174752)
		(layer "F.Cu")
		(net "PE_CLK100M_DR8_2_N")
	)
	(segment
		(start 50.673 -159.554672)
		(end 50.673 -160.078928)
		(width 0.174752)
		(layer "F.Cu")
		(net "PE_CLK100M_DR8_2_N")
	)
	(segment
		(start 50.673 -155.91028)
		(end 50.673 -158.774892)
		(width 0.174752)
		(layer "F.Cu")
		(net "PE_CLK100M_DR8_2_N")
	)
	(segment
		(start 100.457 -118.11)
		(end 86.172294 -132.394706)
		(width 0.174752)
		(layer "F.Cu")
		(net "PE_CLK100M_DR8_2_N")
	)
	(segment
		(start 50.545238 -159.42691)
		(end 50.673 -159.554672)
		(width 0.174752)
		(layer "F.Cu")
		(net "PE_CLK100M_DR8_2_N")
	)
	(segment
		(start 50.673 -162.687)
		(end 49.526952 -163.833048)
		(width 0.174752)
		(layer "F.Cu")
		(net "PE_CLK100M_DR8_2_N")
	)
	(segment
		(start 74.18832 -132.394706)
		(end 52.517294 -154.065986)
		(width 0.174752)
		(layer "F.Cu")
		(net "PE_CLK100M_DR8_2_N")
	)
	(segment
		(start 43.688 -164.142674)
		(end 45.029374 -164.142674)
		(width 0.174752)
		(layer "F.Cu")
		(net "PE_CLK100M_DR8_2_N")
	)
	(segment
		(start 51.96586 -154.436826)
		(end 51.96586 -154.61742)
		(width 0.174752)
		(layer "F.Cu")
		(net "PE_CLK100M_DR8_2_N")
	)
	(segment
		(start 51.043586 -155.358846)
		(end 51.043586 -155.539694)
		(width 0.174752)
		(layer "F.Cu")
		(net "PE_CLK100M_DR8_2_N")
	)
	(segment
		(start 99.6442 -111.506)
		(end 100.457 -112.3188)
		(width 0.174752)
		(layer "F.Cu")
		(net "PE_CLK100M_DR8_2_N")
	)
	(via
		(at 48.387 -163.579302)
		(size 0.508)
		(drill 0.254)
		(layers "F.Cu" "B.Cu")
		(net "PE_CLK100M_DR8_2_N")
	)
	(via
		(at 45.72 -162.790124)
		(size 0.508)
		(drill 0.254)
		(layers "F.Cu" "B.Cu")
		(net "PE_CLK100M_DR8_2_N")
	)
	(segment
		(start 45.72 -163.833048)
		(end 45.466 -163.579048)
		(width 0.174752)
		(layer "B.Cu")
		(net "PE_CLK100M_DR8_2_N")
	)
	(segment
		(start 45.466 -163.579048)
		(end 45.466 -163.044124)
		(width 0.174752)
		(layer "B.Cu")
		(net "PE_CLK100M_DR8_2_N")
	)
	(segment
		(start 48.387 -163.579302)
		(end 48.133254 -163.833048)
		(width 0.174752)
		(layer "B.Cu")
		(net "PE_CLK100M_DR8_2_N")
	)
	(segment
		(start 45.466 -163.044124)
		(end 45.72 -162.790124)
		(width 0.174752)
		(layer "B.Cu")
		(net "PE_CLK100M_DR8_2_N")
	)
	(segment
		(start 48.133254 -163.833048)
		(end 45.72 -163.833048)
		(width 0.174752)
		(layer "B.Cu")
		(net "PE_CLK100M_DR8_2_N")
	)
	(segment
		(start 72.517 -129.667)
		(end 54.549802 -147.634198)
		(width 0.174752)
		(layer "F.Cu")
		(net "PE_CLK100M_DR8_1_P")
	)
	(segment
		(start 49.065434 -153.299414)
		(end 48.884586 -153.299414)
		(width 0.174752)
		(layer "F.Cu")
		(net "PE_CLK100M_DR8_1_P")
	)
	(segment
		(start 49.80686 -152.37714)
		(end 49.43602 -152.74798)
		(width 0.174752)
		(layer "F.Cu")
		(net "PE_CLK100M_DR8_1_P")
	)
	(segment
		(start 50.358294 -151.825706)
		(end 50.358294 -152.006554)
		(width 0.174752)
		(layer "F.Cu")
		(net "PE_CLK100M_DR8_1_P")
	)
	(segment
		(start 35.56 -154.94)
		(end 36.057332 -155.437332)
		(width 0.174752)
		(layer "F.Cu")
		(net "PE_CLK100M_DR8_1_P")
	)
	(segment
		(start 94.996 -112.776)
		(end 94.996 -117.348)
		(width 0.174752)
		(layer "F.Cu")
		(net "PE_CLK100M_DR8_1_P")
	)
	(segment
		(start 36.068 -153.67)
		(end 35.56 -154.178)
		(width 0.174752)
		(layer "F.Cu")
		(net "PE_CLK100M_DR8_1_P")
	)
	(segment
		(start 54.179216 -148.185632)
		(end 53.998368 -148.185632)
		(width 0.174752)
		(layer "F.Cu")
		(net "PE_CLK100M_DR8_1_P")
	)
	(segment
		(start 36.057332 -155.437332)
		(end 37.856668 -155.437332)
		(width 0.174752)
		(layer "F.Cu")
		(net "PE_CLK100M_DR8_1_P")
	)
	(segment
		(start 54.549802 -147.634198)
		(end 54.549802 -147.814792)
		(width 0.174752)
		(layer "F.Cu")
		(net "PE_CLK100M_DR8_1_P")
	)
	(segment
		(start 35.56 -154.178)
		(end 35.56 -154.94)
		(width 0.174752)
		(layer "F.Cu")
		(net "PE_CLK100M_DR8_1_P")
	)
	(segment
		(start 96.190054 -111.010446)
		(end 96.190054 -111.581946)
		(width 0.174752)
		(layer "F.Cu")
		(net "PE_CLK100M_DR8_1_P")
	)
	(segment
		(start 94.996 -117.348)
		(end 82.677 -129.667)
		(width 0.174752)
		(layer "F.Cu")
		(net "PE_CLK100M_DR8_1_P")
	)
	(segment
		(start 50.72888 -151.45512)
		(end 50.358294 -151.825706)
		(width 0.174752)
		(layer "F.Cu")
		(net "PE_CLK100M_DR8_1_P")
	)
	(segment
		(start 96.190054 -111.581946)
		(end 94.996 -112.776)
		(width 0.174752)
		(layer "F.Cu")
		(net "PE_CLK100M_DR8_1_P")
	)
	(segment
		(start 48.884586 -153.299414)
		(end 48.514 -153.67)
		(width 0.174752)
		(layer "F.Cu")
		(net "PE_CLK100M_DR8_1_P")
	)
	(segment
		(start 38.104064 -155.189936)
		(end 39.200074 -155.189936)
		(width 0.174752)
		(layer "F.Cu")
		(net "PE_CLK100M_DR8_1_P")
	)
	(segment
		(start 54.549802 -147.814792)
		(end 54.179216 -148.185632)
		(width 0.174752)
		(layer "F.Cu")
		(net "PE_CLK100M_DR8_1_P")
	)
	(segment
		(start 49.43602 -152.928574)
		(end 49.065434 -153.299414)
		(width 0.174752)
		(layer "F.Cu")
		(net "PE_CLK100M_DR8_1_P")
	)
	(segment
		(start 96.52 -110.6805)
		(end 96.190054 -111.010446)
		(width 0.174752)
		(layer "F.Cu")
		(net "PE_CLK100M_DR8_1_P")
	)
	(segment
		(start 50.909474 -151.45512)
		(end 50.72888 -151.45512)
		(width 0.174752)
		(layer "F.Cu")
		(net "PE_CLK100M_DR8_1_P")
	)
	(segment
		(start 51.280314 -151.08428)
		(end 50.909474 -151.45512)
		(width 0.174752)
		(layer "F.Cu")
		(net "PE_CLK100M_DR8_1_P")
	)
	(segment
		(start 48.514 -153.67)
		(end 36.068 -153.67)
		(width 0.174752)
		(layer "F.Cu")
		(net "PE_CLK100M_DR8_1_P")
	)
	(segment
		(start 53.998368 -148.185632)
		(end 53.627782 -148.556218)
		(width 0.174752)
		(layer "F.Cu")
		(net "PE_CLK100M_DR8_1_P")
	)
	(segment
		(start 49.987454 -152.37714)
		(end 49.80686 -152.37714)
		(width 0.174752)
		(layer "F.Cu")
		(net "PE_CLK100M_DR8_1_P")
	)
	(segment
		(start 37.856668 -155.437332)
		(end 38.104064 -155.189936)
		(width 0.174752)
		(layer "F.Cu")
		(net "PE_CLK100M_DR8_1_P")
	)
	(segment
		(start 51.280314 -150.903686)
		(end 51.280314 -151.08428)
		(width 0.174752)
		(layer "F.Cu")
		(net "PE_CLK100M_DR8_1_P")
	)
	(segment
		(start 49.43602 -152.74798)
		(end 49.43602 -152.928574)
		(width 0.174752)
		(layer "F.Cu")
		(net "PE_CLK100M_DR8_1_P")
	)
	(segment
		(start 53.076348 -149.107652)
		(end 51.280314 -150.903686)
		(width 0.174752)
		(layer "F.Cu")
		(net "PE_CLK100M_DR8_1_P")
	)
	(segment
		(start 82.677 -129.667)
		(end 72.517 -129.667)
		(width 0.174752)
		(layer "F.Cu")
		(net "PE_CLK100M_DR8_1_P")
	)
	(segment
		(start 53.627782 -148.556218)
		(end 53.627782 -148.737066)
		(width 0.174752)
		(layer "F.Cu")
		(net "PE_CLK100M_DR8_1_P")
	)
	(segment
		(start 53.256942 -149.107652)
		(end 53.076348 -149.107652)
		(width 0.174752)
		(layer "F.Cu")
		(net "PE_CLK100M_DR8_1_P")
	)
	(segment
		(start 50.358294 -152.006554)
		(end 49.987454 -152.37714)
		(width 0.174752)
		(layer "F.Cu")
		(net "PE_CLK100M_DR8_1_P")
	)
	(segment
		(start 53.627782 -148.737066)
		(end 53.256942 -149.107652)
		(width 0.174752)
		(layer "F.Cu")
		(net "PE_CLK100M_DR8_1_P")
	)
	(segment
		(start 82.550508 -129.361946)
		(end 72.390508 -129.361946)
		(width 0.174752)
		(layer "F.Cu")
		(net "PE_CLK100M_DR8_1_N")
	)
	(segment
		(start 72.390508 -129.361946)
		(end 48.387508 -153.364946)
		(width 0.174752)
		(layer "F.Cu")
		(net "PE_CLK100M_DR8_1_N")
	)
	(segment
		(start 95.885 -111.0615)
		(end 95.885 -111.455454)
		(width 0.174752)
		(layer "F.Cu")
		(net "PE_CLK100M_DR8_1_N")
	)
	(segment
		(start 37.846 -155.742386)
		(end 38.09365 -155.990036)
		(width 0.174752)
		(layer "F.Cu")
		(net "PE_CLK100M_DR8_1_N")
	)
	(segment
		(start 35.254946 -155.066492)
		(end 35.93084 -155.742386)
		(width 0.174752)
		(layer "F.Cu")
		(net "PE_CLK100M_DR8_1_N")
	)
	(segment
		(start 95.885 -111.455454)
		(end 94.690946 -112.649508)
		(width 0.174752)
		(layer "F.Cu")
		(net "PE_CLK100M_DR8_1_N")
	)
	(segment
		(start 94.690946 -117.221508)
		(end 82.550508 -129.361946)
		(width 0.174752)
		(layer "F.Cu")
		(net "PE_CLK100M_DR8_1_N")
	)
	(segment
		(start 95.504 -110.6805)
		(end 95.885 -111.0615)
		(width 0.174752)
		(layer "F.Cu")
		(net "PE_CLK100M_DR8_1_N")
	)
	(segment
		(start 35.254946 -154.051508)
		(end 35.254946 -155.066492)
		(width 0.174752)
		(layer "F.Cu")
		(net "PE_CLK100M_DR8_1_N")
	)
	(segment
		(start 35.93084 -155.742386)
		(end 37.846 -155.742386)
		(width 0.174752)
		(layer "F.Cu")
		(net "PE_CLK100M_DR8_1_N")
	)
	(segment
		(start 94.690946 -112.649508)
		(end 94.690946 -117.221508)
		(width 0.174752)
		(layer "F.Cu")
		(net "PE_CLK100M_DR8_1_N")
	)
	(segment
		(start 38.09365 -155.990036)
		(end 39.200074 -155.990036)
		(width 0.174752)
		(layer "F.Cu")
		(net "PE_CLK100M_DR8_1_N")
	)
	(segment
		(start 48.387508 -153.364946)
		(end 35.941508 -153.364946)
		(width 0.174752)
		(layer "F.Cu")
		(net "PE_CLK100M_DR8_1_N")
	)
	(segment
		(start 35.941508 -153.364946)
		(end 35.254946 -154.051508)
		(width 0.174752)
		(layer "F.Cu")
		(net "PE_CLK100M_DR8_1_N")
	)
	(segment
		(start 42.39006 -266.590018)
		(end 43.434 -266.590018)
		(width 0.174752)
		(layer "F.Cu")
		(net "PE_CLK100M_DR7_2_P")
	)
	(segment
		(start 50.8 -265.991594)
		(end 49.653444 -267.13815)
		(width 0.174752)
		(layer "F.Cu")
		(net "PE_CLK100M_DR7_2_P")
	)
	(segment
		(start 100.33 -219.9005)
		(end 99.949 -220.2815)
		(width 0.174752)
		(layer "F.Cu")
		(net "PE_CLK100M_DR7_2_P")
	)
	(segment
		(start 43.434 -266.590018)
		(end 43.68165 -266.837668)
		(width 0.174752)
		(layer "F.Cu")
		(net "PE_CLK100M_DR7_2_P")
	)
	(segment
		(start 45.160946 -266.579604)
		(end 45.160946 -266.043918)
		(width 0.174752)
		(layer "F.Cu")
		(net "PE_CLK100M_DR7_2_P")
	)
	(segment
		(start 49.653444 -267.13815)
		(end 48.641 -267.13815)
		(width 0.174752)
		(layer "F.Cu")
		(net "PE_CLK100M_DR7_2_P")
	)
	(segment
		(start 44.902882 -266.837668)
		(end 45.160946 -266.579604)
		(width 0.174752)
		(layer "F.Cu")
		(net "PE_CLK100M_DR7_2_P")
	)
	(segment
		(start 100.762054 -227.532946)
		(end 84.831936 -243.463064)
		(width 0.174752)
		(layer "F.Cu")
		(net "PE_CLK100M_DR7_2_P")
	)
	(segment
		(start 100.762054 -221.361508)
		(end 100.762054 -227.532946)
		(width 0.174752)
		(layer "F.Cu")
		(net "PE_CLK100M_DR7_2_P")
	)
	(segment
		(start 84.831936 -243.463064)
		(end 66.391536 -243.463064)
		(width 0.174752)
		(layer "F.Cu")
		(net "PE_CLK100M_DR7_2_P")
	)
	(segment
		(start 66.391536 -243.463064)
		(end 50.8 -259.0546)
		(width 0.174752)
		(layer "F.Cu")
		(net "PE_CLK100M_DR7_2_P")
	)
	(segment
		(start 99.949 -220.2815)
		(end 99.949 -220.548454)
		(width 0.174752)
		(layer "F.Cu")
		(net "PE_CLK100M_DR7_2_P")
	)
	(segment
		(start 43.68165 -266.837668)
		(end 44.902882 -266.837668)
		(width 0.174752)
		(layer "F.Cu")
		(net "PE_CLK100M_DR7_2_P")
	)
	(segment
		(start 48.641 -267.13815)
		(end 48.387 -267.39215)
		(width 0.174752)
		(layer "F.Cu")
		(net "PE_CLK100M_DR7_2_P")
	)
	(segment
		(start 99.949 -220.548454)
		(end 100.762054 -221.361508)
		(width 0.174752)
		(layer "F.Cu")
		(net "PE_CLK100M_DR7_2_P")
	)
	(segment
		(start 45.160946 -266.043918)
		(end 44.9072 -265.790172)
		(width 0.174752)
		(layer "F.Cu")
		(net "PE_CLK100M_DR7_2_P")
	)
	(segment
		(start 50.8 -259.0546)
		(end 50.8 -265.991594)
		(width 0.174752)
		(layer "F.Cu")
		(net "PE_CLK100M_DR7_2_P")
	)
	(via
		(at 48.387 -267.39215)
		(size 0.508)
		(drill 0.254)
		(layers "F.Cu" "B.Cu")
		(net "PE_CLK100M_DR7_2_P")
	)
	(via
		(at 44.9072 -265.790172)
		(size 0.508)
		(drill 0.254)
		(layers "F.Cu" "B.Cu")
		(net "PE_CLK100M_DR7_2_P")
	)
	(segment
		(start 45.160946 -266.043918)
		(end 45.160946 -266.705588)
		(width 0.174752)
		(layer "B.Cu")
		(net "PE_CLK100M_DR7_2_P")
	)
	(segment
		(start 48.133 -267.13815)
		(end 48.387 -267.39215)
		(width 0.174752)
		(layer "B.Cu")
		(net "PE_CLK100M_DR7_2_P")
	)
	(segment
		(start 44.9072 -265.790172)
		(end 45.160946 -266.043918)
		(width 0.174752)
		(layer "B.Cu")
		(net "PE_CLK100M_DR7_2_P")
	)
	(segment
		(start 45.160946 -266.705588)
		(end 45.593508 -267.13815)
		(width 0.174752)
		(layer "B.Cu")
		(net "PE_CLK100M_DR7_2_P")
	)
	(segment
		(start 45.593508 -267.13815)
		(end 48.133 -267.13815)
		(width 0.174752)
		(layer "B.Cu")
		(net "PE_CLK100M_DR7_2_P")
	)
	(segment
		(start 56.206136 -253.216918)
		(end 55.835296 -253.587758)
		(width 0.174752)
		(layer "F.Cu")
		(net "PE_CLK100M_DR7_2_N")
	)
	(segment
		(start 100.457 -227.406454)
		(end 84.705444 -243.15801)
		(width 0.174752)
		(layer "F.Cu")
		(net "PE_CLK100M_DR7_2_N")
	)
	(segment
		(start 84.705444 -243.15801)
		(end 66.265044 -243.15801)
		(width 0.174752)
		(layer "F.Cu")
		(net "PE_CLK100M_DR7_2_N")
	)
	(segment
		(start 56.757316 -252.665738)
		(end 56.576722 -252.665738)
		(width 0.174752)
		(layer "F.Cu")
		(net "PE_CLK100M_DR7_2_N")
	)
	(segment
		(start 99.643946 -220.230446)
		(end 99.643946 -220.674946)
		(width 0.174752)
		(layer "F.Cu")
		(net "PE_CLK100M_DR7_2_N")
	)
	(segment
		(start 42.39006 -267.390118)
		(end 43.434 -267.390118)
		(width 0.174752)
		(layer "F.Cu")
		(net "PE_CLK100M_DR7_2_N")
	)
	(segment
		(start 55.283862 -254.139192)
		(end 53.487828 -255.935226)
		(width 0.174752)
		(layer "F.Cu")
		(net "PE_CLK100M_DR7_2_N")
	)
	(segment
		(start 99.314 -219.9005)
		(end 99.643946 -220.230446)
		(width 0.174752)
		(layer "F.Cu")
		(net "PE_CLK100M_DR7_2_N")
	)
	(segment
		(start 51.092354 -258.3307)
		(end 50.494946 -258.928108)
		(width 0.174752)
		(layer "F.Cu")
		(net "PE_CLK100M_DR7_2_N")
	)
	(segment
		(start 52.565808 -256.857246)
		(end 52.385214 -256.857246)
		(width 0.174752)
		(layer "F.Cu")
		(net "PE_CLK100M_DR7_2_N")
	)
	(segment
		(start 99.643946 -220.674946)
		(end 100.457 -221.488)
		(width 0.174752)
		(layer "F.Cu")
		(net "PE_CLK100M_DR7_2_N")
	)
	(segment
		(start 100.457 -221.488)
		(end 100.457 -227.406454)
		(width 0.174752)
		(layer "F.Cu")
		(net "PE_CLK100M_DR7_2_N")
	)
	(segment
		(start 45.029374 -267.142722)
		(end 45.466 -266.706096)
		(width 0.174752)
		(layer "F.Cu")
		(net "PE_CLK100M_DR7_2_N")
	)
	(segment
		(start 52.014374 -257.40868)
		(end 51.643788 -257.779266)
		(width 0.174752)
		(layer "F.Cu")
		(net "PE_CLK100M_DR7_2_N")
	)
	(segment
		(start 45.466 -266.706096)
		(end 45.466 -266.044172)
		(width 0.174752)
		(layer "F.Cu")
		(net "PE_CLK100M_DR7_2_N")
	)
	(segment
		(start 43.434 -267.390118)
		(end 43.681396 -267.142722)
		(width 0.174752)
		(layer "F.Cu")
		(net "PE_CLK100M_DR7_2_N")
	)
	(segment
		(start 52.936394 -256.48666)
		(end 52.565808 -256.857246)
		(width 0.174752)
		(layer "F.Cu")
		(net "PE_CLK100M_DR7_2_N")
	)
	(segment
		(start 48.640746 -266.833096)
		(end 48.387 -266.57935)
		(width 0.174752)
		(layer "F.Cu")
		(net "PE_CLK100M_DR7_2_N")
	)
	(segment
		(start 55.283862 -253.958344)
		(end 55.283862 -254.139192)
		(width 0.174752)
		(layer "F.Cu")
		(net "PE_CLK100M_DR7_2_N")
	)
	(segment
		(start 66.265044 -243.15801)
		(end 56.757316 -252.665738)
		(width 0.174752)
		(layer "F.Cu")
		(net "PE_CLK100M_DR7_2_N")
	)
	(segment
		(start 45.466 -266.044172)
		(end 45.72 -265.790172)
		(width 0.174752)
		(layer "F.Cu")
		(net "PE_CLK100M_DR7_2_N")
	)
	(segment
		(start 52.385214 -256.857246)
		(end 52.014374 -257.228086)
		(width 0.174752)
		(layer "F.Cu")
		(net "PE_CLK100M_DR7_2_N")
	)
	(segment
		(start 52.936394 -256.305812)
		(end 52.936394 -256.48666)
		(width 0.174752)
		(layer "F.Cu")
		(net "PE_CLK100M_DR7_2_N")
	)
	(segment
		(start 51.46294 -257.779266)
		(end 51.092354 -258.150106)
		(width 0.174752)
		(layer "F.Cu")
		(net "PE_CLK100M_DR7_2_N")
	)
	(segment
		(start 49.526952 -266.833096)
		(end 48.640746 -266.833096)
		(width 0.174752)
		(layer "F.Cu")
		(net "PE_CLK100M_DR7_2_N")
	)
	(segment
		(start 43.681396 -267.142722)
		(end 45.029374 -267.142722)
		(width 0.174752)
		(layer "F.Cu")
		(net "PE_CLK100M_DR7_2_N")
	)
	(segment
		(start 55.835296 -253.587758)
		(end 55.654702 -253.587758)
		(width 0.174752)
		(layer "F.Cu")
		(net "PE_CLK100M_DR7_2_N")
	)
	(segment
		(start 50.494946 -258.928108)
		(end 50.494946 -265.865102)
		(width 0.174752)
		(layer "F.Cu")
		(net "PE_CLK100M_DR7_2_N")
	)
	(segment
		(start 55.654702 -253.587758)
		(end 55.283862 -253.958344)
		(width 0.174752)
		(layer "F.Cu")
		(net "PE_CLK100M_DR7_2_N")
	)
	(segment
		(start 53.487828 -255.935226)
		(end 53.307234 -255.935226)
		(width 0.174752)
		(layer "F.Cu")
		(net "PE_CLK100M_DR7_2_N")
	)
	(segment
		(start 50.494946 -265.865102)
		(end 49.526952 -266.833096)
		(width 0.174752)
		(layer "F.Cu")
		(net "PE_CLK100M_DR7_2_N")
	)
	(segment
		(start 56.576722 -252.665738)
		(end 56.206136 -253.036324)
		(width 0.174752)
		(layer "F.Cu")
		(net "PE_CLK100M_DR7_2_N")
	)
	(segment
		(start 56.206136 -253.036324)
		(end 56.206136 -253.216918)
		(width 0.174752)
		(layer "F.Cu")
		(net "PE_CLK100M_DR7_2_N")
	)
	(segment
		(start 53.307234 -255.935226)
		(end 52.936394 -256.305812)
		(width 0.174752)
		(layer "F.Cu")
		(net "PE_CLK100M_DR7_2_N")
	)
	(segment
		(start 51.643788 -257.779266)
		(end 51.46294 -257.779266)
		(width 0.174752)
		(layer "F.Cu")
		(net "PE_CLK100M_DR7_2_N")
	)
	(segment
		(start 52.014374 -257.228086)
		(end 52.014374 -257.40868)
		(width 0.174752)
		(layer "F.Cu")
		(net "PE_CLK100M_DR7_2_N")
	)
	(segment
		(start 51.092354 -258.150106)
		(end 51.092354 -258.3307)
		(width 0.174752)
		(layer "F.Cu")
		(net "PE_CLK100M_DR7_2_N")
	)
	(via
		(at 45.72 -265.790172)
		(size 0.508)
		(drill 0.254)
		(layers "F.Cu" "B.Cu")
		(net "PE_CLK100M_DR7_2_N")
	)
	(via
		(at 48.387 -266.57935)
		(size 0.508)
		(drill 0.254)
		(layers "F.Cu" "B.Cu")
		(net "PE_CLK100M_DR7_2_N")
	)
	(segment
		(start 45.466 -266.579096)
		(end 45.72 -266.833096)
		(width 0.174752)
		(layer "B.Cu")
		(net "PE_CLK100M_DR7_2_N")
	)
	(segment
		(start 48.133254 -266.833096)
		(end 48.387 -266.57935)
		(width 0.174752)
		(layer "B.Cu")
		(net "PE_CLK100M_DR7_2_N")
	)
	(segment
		(start 45.72 -266.833096)
		(end 48.133254 -266.833096)
		(width 0.174752)
		(layer "B.Cu")
		(net "PE_CLK100M_DR7_2_N")
	)
	(segment
		(start 45.72 -265.790172)
		(end 45.466 -266.044172)
		(width 0.174752)
		(layer "B.Cu")
		(net "PE_CLK100M_DR7_2_N")
	)
	(segment
		(start 45.466 -266.044172)
		(end 45.466 -266.579096)
		(width 0.174752)
		(layer "B.Cu")
		(net "PE_CLK100M_DR7_2_N")
	)
	(segment
		(start 47.871634 -256.169414)
		(end 47.690786 -256.169414)
		(width 0.174752)
		(layer "F.Cu")
		(net "PE_CLK100M_DR7_1_P")
	)
	(segment
		(start 94.996 -226.568)
		(end 81.28 -240.284)
		(width 0.174752)
		(layer "F.Cu")
		(net "PE_CLK100M_DR7_1_P")
	)
	(segment
		(start 53.356002 -250.684792)
		(end 52.985416 -251.055632)
		(width 0.174752)
		(layer "F.Cu")
		(net "PE_CLK100M_DR7_1_P")
	)
	(segment
		(start 96.52 -219.9005)
		(end 96.1898 -220.2307)
		(width 0.174752)
		(layer "F.Cu")
		(net "PE_CLK100M_DR7_1_P")
	)
	(segment
		(start 53.356002 -250.504198)
		(end 53.356002 -250.684792)
		(width 0.174752)
		(layer "F.Cu")
		(net "PE_CLK100M_DR7_1_P")
	)
	(segment
		(start 37.07638 -258.43738)
		(end 37.846 -258.43738)
		(width 0.174752)
		(layer "F.Cu")
		(net "PE_CLK100M_DR7_1_P")
	)
	(segment
		(start 96.1898 -220.8022)
		(end 94.996 -221.996)
		(width 0.174752)
		(layer "F.Cu")
		(net "PE_CLK100M_DR7_1_P")
	)
	(segment
		(start 47.3202 -256.54)
		(end 37.084 -256.54)
		(width 0.174752)
		(layer "F.Cu")
		(net "PE_CLK100M_DR7_1_P")
	)
	(segment
		(start 48.61306 -255.24714)
		(end 48.24222 -255.61798)
		(width 0.174752)
		(layer "F.Cu")
		(net "PE_CLK100M_DR7_1_P")
	)
	(segment
		(start 36.576 -257.048)
		(end 36.576 -257.937)
		(width 0.174752)
		(layer "F.Cu")
		(net "PE_CLK100M_DR7_1_P")
	)
	(segment
		(start 96.1898 -220.2307)
		(end 96.1898 -220.8022)
		(width 0.174752)
		(layer "F.Cu")
		(net "PE_CLK100M_DR7_1_P")
	)
	(segment
		(start 48.793654 -255.24714)
		(end 48.61306 -255.24714)
		(width 0.174752)
		(layer "F.Cu")
		(net "PE_CLK100M_DR7_1_P")
	)
	(segment
		(start 52.433982 -251.607066)
		(end 52.063142 -251.977652)
		(width 0.174752)
		(layer "F.Cu")
		(net "PE_CLK100M_DR7_1_P")
	)
	(segment
		(start 49.53508 -254.32512)
		(end 49.164494 -254.695706)
		(width 0.174752)
		(layer "F.Cu")
		(net "PE_CLK100M_DR7_1_P")
	)
	(segment
		(start 49.164494 -254.876554)
		(end 48.793654 -255.24714)
		(width 0.174752)
		(layer "F.Cu")
		(net "PE_CLK100M_DR7_1_P")
	)
	(segment
		(start 38.093396 -258.189984)
		(end 39.200074 -258.189984)
		(width 0.174752)
		(layer "F.Cu")
		(net "PE_CLK100M_DR7_1_P")
	)
	(segment
		(start 36.576 -257.937)
		(end 37.07638 -258.43738)
		(width 0.174752)
		(layer "F.Cu")
		(net "PE_CLK100M_DR7_1_P")
	)
	(segment
		(start 49.715674 -254.32512)
		(end 49.53508 -254.32512)
		(width 0.174752)
		(layer "F.Cu")
		(net "PE_CLK100M_DR7_1_P")
	)
	(segment
		(start 49.164494 -254.695706)
		(end 49.164494 -254.876554)
		(width 0.174752)
		(layer "F.Cu")
		(net "PE_CLK100M_DR7_1_P")
	)
	(segment
		(start 51.882548 -251.977652)
		(end 50.086514 -253.773686)
		(width 0.174752)
		(layer "F.Cu")
		(net "PE_CLK100M_DR7_1_P")
	)
	(segment
		(start 37.846 -258.43738)
		(end 38.093396 -258.189984)
		(width 0.174752)
		(layer "F.Cu")
		(net "PE_CLK100M_DR7_1_P")
	)
	(segment
		(start 37.084 -256.54)
		(end 36.576 -257.048)
		(width 0.174752)
		(layer "F.Cu")
		(net "PE_CLK100M_DR7_1_P")
	)
	(segment
		(start 94.996 -221.996)
		(end 94.996 -226.568)
		(width 0.174752)
		(layer "F.Cu")
		(net "PE_CLK100M_DR7_1_P")
	)
	(segment
		(start 52.985416 -251.055632)
		(end 52.804568 -251.055632)
		(width 0.174752)
		(layer "F.Cu")
		(net "PE_CLK100M_DR7_1_P")
	)
	(segment
		(start 52.804568 -251.055632)
		(end 52.433982 -251.426218)
		(width 0.174752)
		(layer "F.Cu")
		(net "PE_CLK100M_DR7_1_P")
	)
	(segment
		(start 48.24222 -255.798574)
		(end 47.871634 -256.169414)
		(width 0.174752)
		(layer "F.Cu")
		(net "PE_CLK100M_DR7_1_P")
	)
	(segment
		(start 50.086514 -253.95428)
		(end 49.715674 -254.32512)
		(width 0.174752)
		(layer "F.Cu")
		(net "PE_CLK100M_DR7_1_P")
	)
	(segment
		(start 50.086514 -253.773686)
		(end 50.086514 -253.95428)
		(width 0.174752)
		(layer "F.Cu")
		(net "PE_CLK100M_DR7_1_P")
	)
	(segment
		(start 63.5762 -240.284)
		(end 53.356002 -250.504198)
		(width 0.174752)
		(layer "F.Cu")
		(net "PE_CLK100M_DR7_1_P")
	)
	(segment
		(start 52.433982 -251.426218)
		(end 52.433982 -251.607066)
		(width 0.174752)
		(layer "F.Cu")
		(net "PE_CLK100M_DR7_1_P")
	)
	(segment
		(start 81.28 -240.284)
		(end 63.5762 -240.284)
		(width 0.174752)
		(layer "F.Cu")
		(net "PE_CLK100M_DR7_1_P")
	)
	(segment
		(start 47.690786 -256.169414)
		(end 47.3202 -256.54)
		(width 0.174752)
		(layer "F.Cu")
		(net "PE_CLK100M_DR7_1_P")
	)
	(segment
		(start 48.24222 -255.61798)
		(end 48.24222 -255.798574)
		(width 0.174752)
		(layer "F.Cu")
		(net "PE_CLK100M_DR7_1_P")
	)
	(segment
		(start 52.063142 -251.977652)
		(end 51.882548 -251.977652)
		(width 0.174752)
		(layer "F.Cu")
		(net "PE_CLK100M_DR7_1_P")
	)
	(segment
		(start 95.504 -219.9005)
		(end 95.884746 -220.281246)
		(width 0.174752)
		(layer "F.Cu")
		(net "PE_CLK100M_DR7_1_N")
	)
	(segment
		(start 47.193708 -256.234946)
		(end 36.957508 -256.234946)
		(width 0.174752)
		(layer "F.Cu")
		(net "PE_CLK100M_DR7_1_N")
	)
	(segment
		(start 38.09365 -258.990084)
		(end 39.200074 -258.990084)
		(width 0.174752)
		(layer "F.Cu")
		(net "PE_CLK100M_DR7_1_N")
	)
	(segment
		(start 95.884746 -220.281246)
		(end 95.884746 -220.675708)
		(width 0.174752)
		(layer "F.Cu")
		(net "PE_CLK100M_DR7_1_N")
	)
	(segment
		(start 36.949888 -258.742434)
		(end 37.846 -258.742434)
		(width 0.174752)
		(layer "F.Cu")
		(net "PE_CLK100M_DR7_1_N")
	)
	(segment
		(start 36.957508 -256.234946)
		(end 36.270946 -256.921508)
		(width 0.174752)
		(layer "F.Cu")
		(net "PE_CLK100M_DR7_1_N")
	)
	(segment
		(start 36.270946 -258.063492)
		(end 36.949888 -258.742434)
		(width 0.174752)
		(layer "F.Cu")
		(net "PE_CLK100M_DR7_1_N")
	)
	(segment
		(start 37.846 -258.742434)
		(end 38.09365 -258.990084)
		(width 0.174752)
		(layer "F.Cu")
		(net "PE_CLK100M_DR7_1_N")
	)
	(segment
		(start 95.884746 -220.675708)
		(end 94.690946 -221.869508)
		(width 0.174752)
		(layer "F.Cu")
		(net "PE_CLK100M_DR7_1_N")
	)
	(segment
		(start 81.153508 -239.978946)
		(end 63.449708 -239.978946)
		(width 0.174752)
		(layer "F.Cu")
		(net "PE_CLK100M_DR7_1_N")
	)
	(segment
		(start 94.690946 -221.869508)
		(end 94.690946 -226.441508)
		(width 0.174752)
		(layer "F.Cu")
		(net "PE_CLK100M_DR7_1_N")
	)
	(segment
		(start 94.690946 -226.441508)
		(end 81.153508 -239.978946)
		(width 0.174752)
		(layer "F.Cu")
		(net "PE_CLK100M_DR7_1_N")
	)
	(segment
		(start 36.270946 -256.921508)
		(end 36.270946 -258.063492)
		(width 0.174752)
		(layer "F.Cu")
		(net "PE_CLK100M_DR7_1_N")
	)
	(segment
		(start 63.449708 -239.978946)
		(end 47.193708 -256.234946)
		(width 0.174752)
		(layer "F.Cu")
		(net "PE_CLK100M_DR7_1_N")
	)
	(segment
		(start 43.68165 -369.837716)
		(end 44.902882 -369.837716)
		(width 0.174752)
		(layer "F.Cu")
		(net "PE_CLK100M_DR6_2_P")
	)
	(segment
		(start 45.160946 -369.579652)
		(end 45.160946 -369.043966)
		(width 0.174752)
		(layer "F.Cu")
		(net "PE_CLK100M_DR6_2_P")
	)
	(segment
		(start 99.949 -314.909454)
		(end 99.949 -314.6425)
		(width 0.174752)
		(layer "F.Cu")
		(net "PE_CLK100M_DR6_2_P")
	)
	(segment
		(start 49.602136 -370.138198)
		(end 50.233326 -369.507008)
		(width 0.174752)
		(layer "F.Cu")
		(net "PE_CLK100M_DR6_2_P")
	)
	(segment
		(start 48.641 -370.138198)
		(end 49.602136 -370.138198)
		(width 0.174752)
		(layer "F.Cu")
		(net "PE_CLK100M_DR6_2_P")
	)
	(segment
		(start 67.030092 -346.126054)
		(end 76.580492 -346.126054)
		(width 0.174752)
		(layer "F.Cu")
		(net "PE_CLK100M_DR6_2_P")
	)
	(segment
		(start 45.160946 -369.043966)
		(end 44.9072 -368.79022)
		(width 0.174752)
		(layer "F.Cu")
		(net "PE_CLK100M_DR6_2_P")
	)
	(segment
		(start 100.762054 -321.944492)
		(end 100.762054 -315.722508)
		(width 0.174752)
		(layer "F.Cu")
		(net "PE_CLK100M_DR6_2_P")
	)
	(segment
		(start 50.233326 -369.507008)
		(end 50.233326 -362.923582)
		(width 0.174752)
		(layer "F.Cu")
		(net "PE_CLK100M_DR6_2_P")
	)
	(segment
		(start 99.949 -314.6425)
		(end 100.33 -314.2615)
		(width 0.174752)
		(layer "F.Cu")
		(net "PE_CLK100M_DR6_2_P")
	)
	(segment
		(start 50.233326 -362.923582)
		(end 52.13604 -361.020868)
		(width 0.174752)
		(layer "F.Cu")
		(net "PE_CLK100M_DR6_2_P")
	)
	(segment
		(start 52.13604 -361.020868)
		(end 67.030092 -346.126054)
		(width 0.174752)
		(layer "F.Cu")
		(net "PE_CLK100M_DR6_2_P")
	)
	(segment
		(start 44.902882 -369.837716)
		(end 45.160946 -369.579652)
		(width 0.174752)
		(layer "F.Cu")
		(net "PE_CLK100M_DR6_2_P")
	)
	(segment
		(start 43.434 -369.590066)
		(end 43.68165 -369.837716)
		(width 0.174752)
		(layer "F.Cu")
		(net "PE_CLK100M_DR6_2_P")
	)
	(segment
		(start 42.39006 -369.590066)
		(end 43.434 -369.590066)
		(width 0.174752)
		(layer "F.Cu")
		(net "PE_CLK100M_DR6_2_P")
	)
	(segment
		(start 76.580492 -346.126054)
		(end 100.762054 -321.944492)
		(width 0.174752)
		(layer "F.Cu")
		(net "PE_CLK100M_DR6_2_P")
	)
	(segment
		(start 100.762054 -315.722508)
		(end 99.949 -314.909454)
		(width 0.174752)
		(layer "F.Cu")
		(net "PE_CLK100M_DR6_2_P")
	)
	(segment
		(start 48.387 -370.392198)
		(end 48.641 -370.138198)
		(width 0.174752)
		(layer "F.Cu")
		(net "PE_CLK100M_DR6_2_P")
	)
	(via
		(at 48.387 -370.392198)
		(size 0.508)
		(drill 0.254)
		(layers "F.Cu" "B.Cu")
		(net "PE_CLK100M_DR6_2_P")
	)
	(via
		(at 44.9072 -368.79022)
		(size 0.508)
		(drill 0.254)
		(layers "F.Cu" "B.Cu")
		(net "PE_CLK100M_DR6_2_P")
	)
	(segment
		(start 48.387 -370.392198)
		(end 48.133 -370.138198)
		(width 0.174752)
		(layer "B.Cu")
		(net "PE_CLK100M_DR6_2_P")
	)
	(segment
		(start 45.160946 -369.043966)
		(end 44.9072 -368.79022)
		(width 0.174752)
		(layer "B.Cu")
		(net "PE_CLK100M_DR6_2_P")
	)
	(segment
		(start 48.133 -370.138198)
		(end 45.593508 -370.138198)
		(width 0.174752)
		(layer "B.Cu")
		(net "PE_CLK100M_DR6_2_P")
	)
	(segment
		(start 45.593508 -370.138198)
		(end 45.160946 -369.705636)
		(width 0.174752)
		(layer "B.Cu")
		(net "PE_CLK100M_DR6_2_P")
	)
	(segment
		(start 45.160946 -369.705636)
		(end 45.160946 -369.043966)
		(width 0.174752)
		(layer "B.Cu")
		(net "PE_CLK100M_DR6_2_P")
	)
	(segment
		(start 52.753006 -359.791508)
		(end 52.753006 -359.972102)
		(width 0.174752)
		(layer "F.Cu")
		(net "PE_CLK100M_DR6_2_N")
	)
	(segment
		(start 45.466 -369.04422)
		(end 45.72 -368.79022)
		(width 0.174752)
		(layer "F.Cu")
		(net "PE_CLK100M_DR6_2_N")
	)
	(segment
		(start 76.454 -345.821)
		(end 66.9036 -345.821)
		(width 0.174752)
		(layer "F.Cu")
		(net "PE_CLK100M_DR6_2_N")
	)
	(segment
		(start 45.029374 -370.14277)
		(end 45.466 -369.706144)
		(width 0.174752)
		(layer "F.Cu")
		(net "PE_CLK100M_DR6_2_N")
	)
	(segment
		(start 43.688 -370.14277)
		(end 45.029374 -370.14277)
		(width 0.174752)
		(layer "F.Cu")
		(net "PE_CLK100M_DR6_2_N")
	)
	(segment
		(start 49.928272 -369.380516)
		(end 49.475644 -369.833144)
		(width 0.174752)
		(layer "F.Cu")
		(net "PE_CLK100M_DR6_2_N")
	)
	(segment
		(start 60.904628 -351.639632)
		(end 60.533788 -352.010218)
		(width 0.174752)
		(layer "F.Cu")
		(net "PE_CLK100M_DR6_2_N")
	)
	(segment
		(start 59.611768 -352.932492)
		(end 59.611768 -353.113086)
		(width 0.174752)
		(layer "F.Cu")
		(net "PE_CLK100M_DR6_2_N")
	)
	(segment
		(start 99.643946 -315.035946)
		(end 100.457 -315.849)
		(width 0.174752)
		(layer "F.Cu")
		(net "PE_CLK100M_DR6_2_N")
	)
	(segment
		(start 52.201826 -360.342942)
		(end 51.830986 -360.713528)
		(width 0.174752)
		(layer "F.Cu")
		(net "PE_CLK100M_DR6_2_N")
	)
	(segment
		(start 53.123846 -359.420922)
		(end 52.753006 -359.791508)
		(width 0.174752)
		(layer "F.Cu")
		(net "PE_CLK100M_DR6_2_N")
	)
	(segment
		(start 100.457 -321.818)
		(end 76.454 -345.821)
		(width 0.174752)
		(layer "F.Cu")
		(net "PE_CLK100M_DR6_2_N")
	)
	(segment
		(start 60.533788 -352.010218)
		(end 60.533788 -352.191066)
		(width 0.174752)
		(layer "F.Cu")
		(net "PE_CLK100M_DR6_2_N")
	)
	(segment
		(start 51.830986 -360.894376)
		(end 49.928272 -362.79709)
		(width 0.174752)
		(layer "F.Cu")
		(net "PE_CLK100M_DR6_2_N")
	)
	(segment
		(start 42.39006 -370.390166)
		(end 43.440604 -370.390166)
		(width 0.174752)
		(layer "F.Cu")
		(net "PE_CLK100M_DR6_2_N")
	)
	(segment
		(start 59.611768 -353.113086)
		(end 54.22646 -358.498902)
		(width 0.174752)
		(layer "F.Cu")
		(net "PE_CLK100M_DR6_2_N")
	)
	(segment
		(start 100.457 -315.849)
		(end 100.457 -321.818)
		(width 0.174752)
		(layer "F.Cu")
		(net "PE_CLK100M_DR6_2_N")
	)
	(segment
		(start 53.30444 -359.420922)
		(end 53.123846 -359.420922)
		(width 0.174752)
		(layer "F.Cu")
		(net "PE_CLK100M_DR6_2_N")
	)
	(segment
		(start 60.163202 -352.561652)
		(end 59.982608 -352.561652)
		(width 0.174752)
		(layer "F.Cu")
		(net "PE_CLK100M_DR6_2_N")
	)
	(segment
		(start 52.38242 -360.342942)
		(end 52.201826 -360.342942)
		(width 0.174752)
		(layer "F.Cu")
		(net "PE_CLK100M_DR6_2_N")
	)
	(segment
		(start 51.830986 -360.713528)
		(end 51.830986 -360.894376)
		(width 0.174752)
		(layer "F.Cu")
		(net "PE_CLK100M_DR6_2_N")
	)
	(segment
		(start 43.440604 -370.390166)
		(end 43.688 -370.14277)
		(width 0.174752)
		(layer "F.Cu")
		(net "PE_CLK100M_DR6_2_N")
	)
	(segment
		(start 52.753006 -359.972102)
		(end 52.38242 -360.342942)
		(width 0.174752)
		(layer "F.Cu")
		(net "PE_CLK100M_DR6_2_N")
	)
	(segment
		(start 66.9036 -345.821)
		(end 61.085222 -351.639632)
		(width 0.174752)
		(layer "F.Cu")
		(net "PE_CLK100M_DR6_2_N")
	)
	(segment
		(start 61.085222 -351.639632)
		(end 60.904628 -351.639632)
		(width 0.174752)
		(layer "F.Cu")
		(net "PE_CLK100M_DR6_2_N")
	)
	(segment
		(start 99.314 -314.2615)
		(end 99.643946 -314.591446)
		(width 0.174752)
		(layer "F.Cu")
		(net "PE_CLK100M_DR6_2_N")
	)
	(segment
		(start 49.928272 -362.79709)
		(end 49.928272 -369.380516)
		(width 0.174752)
		(layer "F.Cu")
		(net "PE_CLK100M_DR6_2_N")
	)
	(segment
		(start 99.643946 -314.591446)
		(end 99.643946 -315.035946)
		(width 0.174752)
		(layer "F.Cu")
		(net "PE_CLK100M_DR6_2_N")
	)
	(segment
		(start 54.045866 -358.498902)
		(end 53.675026 -358.869488)
		(width 0.174752)
		(layer "F.Cu")
		(net "PE_CLK100M_DR6_2_N")
	)
	(segment
		(start 48.640746 -369.833144)
		(end 48.387 -369.579398)
		(width 0.174752)
		(layer "F.Cu")
		(net "PE_CLK100M_DR6_2_N")
	)
	(segment
		(start 49.475644 -369.833144)
		(end 48.640746 -369.833144)
		(width 0.174752)
		(layer "F.Cu")
		(net "PE_CLK100M_DR6_2_N")
	)
	(segment
		(start 53.675026 -359.050082)
		(end 53.30444 -359.420922)
		(width 0.174752)
		(layer "F.Cu")
		(net "PE_CLK100M_DR6_2_N")
	)
	(segment
		(start 60.533788 -352.191066)
		(end 60.163202 -352.561652)
		(width 0.174752)
		(layer "F.Cu")
		(net "PE_CLK100M_DR6_2_N")
	)
	(segment
		(start 59.982608 -352.561652)
		(end 59.611768 -352.932492)
		(width 0.174752)
		(layer "F.Cu")
		(net "PE_CLK100M_DR6_2_N")
	)
	(segment
		(start 54.22646 -358.498902)
		(end 54.045866 -358.498902)
		(width 0.174752)
		(layer "F.Cu")
		(net "PE_CLK100M_DR6_2_N")
	)
	(segment
		(start 45.466 -369.706144)
		(end 45.466 -369.04422)
		(width 0.174752)
		(layer "F.Cu")
		(net "PE_CLK100M_DR6_2_N")
	)
	(segment
		(start 53.675026 -358.869488)
		(end 53.675026 -359.050082)
		(width 0.174752)
		(layer "F.Cu")
		(net "PE_CLK100M_DR6_2_N")
	)
	(via
		(at 48.387 -369.579398)
		(size 0.508)
		(drill 0.254)
		(layers "F.Cu" "B.Cu")
		(net "PE_CLK100M_DR6_2_N")
	)
	(via
		(at 45.72 -368.79022)
		(size 0.508)
		(drill 0.254)
		(layers "F.Cu" "B.Cu")
		(net "PE_CLK100M_DR6_2_N")
	)
	(segment
		(start 45.72 -369.833144)
		(end 45.466 -369.579144)
		(width 0.174752)
		(layer "B.Cu")
		(net "PE_CLK100M_DR6_2_N")
	)
	(segment
		(start 48.133254 -369.833144)
		(end 45.72 -369.833144)
		(width 0.174752)
		(layer "B.Cu")
		(net "PE_CLK100M_DR6_2_N")
	)
	(segment
		(start 45.466 -369.579144)
		(end 45.466 -369.04422)
		(width 0.174752)
		(layer "B.Cu")
		(net "PE_CLK100M_DR6_2_N")
	)
	(segment
		(start 45.466 -369.04422)
		(end 45.72 -368.79022)
		(width 0.174752)
		(layer "B.Cu")
		(net "PE_CLK100M_DR6_2_N")
	)
	(segment
		(start 48.387 -369.579398)
		(end 48.133254 -369.833144)
		(width 0.174752)
		(layer "B.Cu")
		(net "PE_CLK100M_DR6_2_N")
	)
	(segment
		(start 50.816002 -356.85603)
		(end 50.445416 -357.22687)
		(width 0.174752)
		(layer "F.Cu")
		(net "PE_CLK100M_DR6_1_P")
	)
	(segment
		(start 36.952428 -361.437428)
		(end 37.852604 -361.437428)
		(width 0.174752)
		(layer "F.Cu")
		(net "PE_CLK100M_DR6_1_P")
	)
	(segment
		(start 54.697884 -352.974402)
		(end 54.517036 -352.974402)
		(width 0.174752)
		(layer "F.Cu")
		(net "PE_CLK100M_DR6_1_P")
	)
	(segment
		(start 94.996 -316.357)
		(end 94.996 -320.979546)
		(width 0.174752)
		(layer "F.Cu")
		(net "PE_CLK100M_DR6_1_P")
	)
	(segment
		(start 64.464438 -343.027)
		(end 55.06847 -352.422968)
		(width 0.174752)
		(layer "F.Cu")
		(net "PE_CLK100M_DR6_1_P")
	)
	(segment
		(start 53.77561 -353.896422)
		(end 53.595016 -353.896422)
		(width 0.174752)
		(layer "F.Cu")
		(net "PE_CLK100M_DR6_1_P")
	)
	(segment
		(start 38.1 -361.190032)
		(end 39.200074 -361.190032)
		(width 0.174752)
		(layer "F.Cu")
		(net "PE_CLK100M_DR6_1_P")
	)
	(segment
		(start 48.420528 -359.07091)
		(end 47.954438 -359.537)
		(width 0.174752)
		(layer "F.Cu")
		(net "PE_CLK100M_DR6_1_P")
	)
	(segment
		(start 54.14645 -353.344988)
		(end 54.14645 -353.525836)
		(width 0.174752)
		(layer "F.Cu")
		(net "PE_CLK100M_DR6_1_P")
	)
	(segment
		(start 49.523396 -358.14889)
		(end 49.342548 -358.14889)
		(width 0.174752)
		(layer "F.Cu")
		(net "PE_CLK100M_DR6_1_P")
	)
	(segment
		(start 72.948546 -343.027)
		(end 64.464438 -343.027)
		(width 0.174752)
		(layer "F.Cu")
		(net "PE_CLK100M_DR6_1_P")
	)
	(segment
		(start 54.517036 -352.974402)
		(end 54.14645 -353.344988)
		(width 0.174752)
		(layer "F.Cu")
		(net "PE_CLK100M_DR6_1_P")
	)
	(segment
		(start 50.445416 -357.22687)
		(end 50.264568 -357.22687)
		(width 0.174752)
		(layer "F.Cu")
		(net "PE_CLK100M_DR6_1_P")
	)
	(segment
		(start 36.957 -359.537)
		(end 36.576 -359.918)
		(width 0.174752)
		(layer "F.Cu")
		(net "PE_CLK100M_DR6_1_P")
	)
	(segment
		(start 55.06847 -352.603562)
		(end 54.697884 -352.974402)
		(width 0.174752)
		(layer "F.Cu")
		(net "PE_CLK100M_DR6_1_P")
	)
	(segment
		(start 94.996 -320.979546)
		(end 72.948546 -343.027)
		(width 0.174752)
		(layer "F.Cu")
		(net "PE_CLK100M_DR6_1_P")
	)
	(segment
		(start 96.52 -314.2615)
		(end 96.1898 -314.5917)
		(width 0.174752)
		(layer "F.Cu")
		(net "PE_CLK100M_DR6_1_P")
	)
	(segment
		(start 50.264568 -357.22687)
		(end 49.893982 -357.597456)
		(width 0.174752)
		(layer "F.Cu")
		(net "PE_CLK100M_DR6_1_P")
	)
	(segment
		(start 48.971962 -358.519476)
		(end 48.971962 -358.700324)
		(width 0.174752)
		(layer "F.Cu")
		(net "PE_CLK100M_DR6_1_P")
	)
	(segment
		(start 96.1898 -315.1632)
		(end 94.996 -316.357)
		(width 0.174752)
		(layer "F.Cu")
		(net "PE_CLK100M_DR6_1_P")
	)
	(segment
		(start 36.576 -359.918)
		(end 36.576 -361.061)
		(width 0.174752)
		(layer "F.Cu")
		(net "PE_CLK100M_DR6_1_P")
	)
	(segment
		(start 53.595016 -353.896422)
		(end 50.816002 -356.675436)
		(width 0.174752)
		(layer "F.Cu")
		(net "PE_CLK100M_DR6_1_P")
	)
	(segment
		(start 48.601122 -359.07091)
		(end 48.420528 -359.07091)
		(width 0.174752)
		(layer "F.Cu")
		(net "PE_CLK100M_DR6_1_P")
	)
	(segment
		(start 50.816002 -356.675436)
		(end 50.816002 -356.85603)
		(width 0.174752)
		(layer "F.Cu")
		(net "PE_CLK100M_DR6_1_P")
	)
	(segment
		(start 36.576 -361.061)
		(end 36.952428 -361.437428)
		(width 0.174752)
		(layer "F.Cu")
		(net "PE_CLK100M_DR6_1_P")
	)
	(segment
		(start 49.342548 -358.14889)
		(end 48.971962 -358.519476)
		(width 0.174752)
		(layer "F.Cu")
		(net "PE_CLK100M_DR6_1_P")
	)
	(segment
		(start 47.954438 -359.537)
		(end 36.957 -359.537)
		(width 0.174752)
		(layer "F.Cu")
		(net "PE_CLK100M_DR6_1_P")
	)
	(segment
		(start 49.893982 -357.77805)
		(end 49.523396 -358.14889)
		(width 0.174752)
		(layer "F.Cu")
		(net "PE_CLK100M_DR6_1_P")
	)
	(segment
		(start 96.1898 -314.5917)
		(end 96.1898 -315.1632)
		(width 0.174752)
		(layer "F.Cu")
		(net "PE_CLK100M_DR6_1_P")
	)
	(segment
		(start 37.852604 -361.437428)
		(end 38.1 -361.190032)
		(width 0.174752)
		(layer "F.Cu")
		(net "PE_CLK100M_DR6_1_P")
	)
	(segment
		(start 48.971962 -358.700324)
		(end 48.601122 -359.07091)
		(width 0.174752)
		(layer "F.Cu")
		(net "PE_CLK100M_DR6_1_P")
	)
	(segment
		(start 49.893982 -357.597456)
		(end 49.893982 -357.77805)
		(width 0.174752)
		(layer "F.Cu")
		(net "PE_CLK100M_DR6_1_P")
	)
	(segment
		(start 54.14645 -353.525836)
		(end 53.77561 -353.896422)
		(width 0.174752)
		(layer "F.Cu")
		(net "PE_CLK100M_DR6_1_P")
	)
	(segment
		(start 55.06847 -352.422968)
		(end 55.06847 -352.603562)
		(width 0.174752)
		(layer "F.Cu")
		(net "PE_CLK100M_DR6_1_P")
	)
	(segment
		(start 95.884746 -314.642246)
		(end 95.884746 -315.036708)
		(width 0.174752)
		(layer "F.Cu")
		(net "PE_CLK100M_DR6_1_N")
	)
	(segment
		(start 94.690946 -320.853054)
		(end 72.822054 -342.721946)
		(width 0.174752)
		(layer "F.Cu")
		(net "PE_CLK100M_DR6_1_N")
	)
	(segment
		(start 36.830508 -359.231946)
		(end 36.270946 -359.791508)
		(width 0.174752)
		(layer "F.Cu")
		(net "PE_CLK100M_DR6_1_N")
	)
	(segment
		(start 95.504 -314.2615)
		(end 95.884746 -314.642246)
		(width 0.174752)
		(layer "F.Cu")
		(net "PE_CLK100M_DR6_1_N")
	)
	(segment
		(start 47.827946 -359.231946)
		(end 36.830508 -359.231946)
		(width 0.174752)
		(layer "F.Cu")
		(net "PE_CLK100M_DR6_1_N")
	)
	(segment
		(start 95.884746 -315.036708)
		(end 94.690946 -316.230508)
		(width 0.174752)
		(layer "F.Cu")
		(net "PE_CLK100M_DR6_1_N")
	)
	(segment
		(start 36.825936 -361.742482)
		(end 37.846 -361.742482)
		(width 0.174752)
		(layer "F.Cu")
		(net "PE_CLK100M_DR6_1_N")
	)
	(segment
		(start 36.270946 -361.187492)
		(end 36.825936 -361.742482)
		(width 0.174752)
		(layer "F.Cu")
		(net "PE_CLK100M_DR6_1_N")
	)
	(segment
		(start 38.09365 -361.990132)
		(end 39.200074 -361.990132)
		(width 0.174752)
		(layer "F.Cu")
		(net "PE_CLK100M_DR6_1_N")
	)
	(segment
		(start 37.846 -361.742482)
		(end 38.09365 -361.990132)
		(width 0.174752)
		(layer "F.Cu")
		(net "PE_CLK100M_DR6_1_N")
	)
	(segment
		(start 36.270946 -359.791508)
		(end 36.270946 -361.187492)
		(width 0.174752)
		(layer "F.Cu")
		(net "PE_CLK100M_DR6_1_N")
	)
	(segment
		(start 94.690946 -316.230508)
		(end 94.690946 -320.853054)
		(width 0.174752)
		(layer "F.Cu")
		(net "PE_CLK100M_DR6_1_N")
	)
	(segment
		(start 64.337946 -342.721946)
		(end 47.827946 -359.231946)
		(width 0.174752)
		(layer "F.Cu")
		(net "PE_CLK100M_DR6_1_N")
	)
	(segment
		(start 72.822054 -342.721946)
		(end 64.337946 -342.721946)
		(width 0.174752)
		(layer "F.Cu")
		(net "PE_CLK100M_DR6_1_N")
	)
	(segment
		(start 45.160946 -472.044014)
		(end 44.9072 -471.790268)
		(width 0.174752)
		(layer "F.Cu")
		(net "PE_CLK100M_DR5_2_P")
	)
	(segment
		(start 45.160946 -472.5797)
		(end 45.160946 -472.044014)
		(width 0.174752)
		(layer "F.Cu")
		(net "PE_CLK100M_DR5_2_P")
	)
	(segment
		(start 42.39006 -472.590114)
		(end 43.561 -472.590114)
		(width 0.174752)
		(layer "F.Cu")
		(net "PE_CLK100M_DR5_2_P")
	)
	(segment
		(start 48.641 -473.138246)
		(end 48.387 -473.392246)
		(width 0.174752)
		(layer "F.Cu")
		(net "PE_CLK100M_DR5_2_P")
	)
	(segment
		(start 43.80865 -472.837764)
		(end 44.902882 -472.837764)
		(width 0.174752)
		(layer "F.Cu")
		(net "PE_CLK100M_DR5_2_P")
	)
	(segment
		(start 91.745054 -453.897492)
		(end 72.5043 -473.138246)
		(width 0.174752)
		(layer "F.Cu")
		(net "PE_CLK100M_DR5_2_P")
	)
	(segment
		(start 91.745054 -442.341508)
		(end 91.745054 -453.897492)
		(width 0.174752)
		(layer "F.Cu")
		(net "PE_CLK100M_DR5_2_P")
	)
	(segment
		(start 44.902882 -472.837764)
		(end 45.160946 -472.5797)
		(width 0.174752)
		(layer "F.Cu")
		(net "PE_CLK100M_DR5_2_P")
	)
	(segment
		(start 90.957654 -441.235846)
		(end 90.957654 -441.554108)
		(width 0.174752)
		(layer "F.Cu")
		(net "PE_CLK100M_DR5_2_P")
	)
	(segment
		(start 43.561 -472.590114)
		(end 43.80865 -472.837764)
		(width 0.174752)
		(layer "F.Cu")
		(net "PE_CLK100M_DR5_2_P")
	)
	(segment
		(start 72.5043 -473.138246)
		(end 48.641 -473.138246)
		(width 0.174752)
		(layer "F.Cu")
		(net "PE_CLK100M_DR5_2_P")
	)
	(segment
		(start 90.957654 -441.554108)
		(end 91.745054 -442.341508)
		(width 0.174752)
		(layer "F.Cu")
		(net "PE_CLK100M_DR5_2_P")
	)
	(segment
		(start 91.313 -440.8805)
		(end 90.957654 -441.235846)
		(width 0.174752)
		(layer "F.Cu")
		(net "PE_CLK100M_DR5_2_P")
	)
	(via
		(at 48.387 -473.392246)
		(size 0.508)
		(drill 0.254)
		(layers "F.Cu" "B.Cu")
		(net "PE_CLK100M_DR5_2_P")
	)
	(via
		(at 44.9072 -471.790268)
		(size 0.508)
		(drill 0.254)
		(layers "F.Cu" "B.Cu")
		(net "PE_CLK100M_DR5_2_P")
	)
	(segment
		(start 45.160946 -472.705684)
		(end 45.593508 -473.138246)
		(width 0.174752)
		(layer "B.Cu")
		(net "PE_CLK100M_DR5_2_P")
	)
	(segment
		(start 48.133 -473.138246)
		(end 48.387 -473.392246)
		(width 0.174752)
		(layer "B.Cu")
		(net "PE_CLK100M_DR5_2_P")
	)
	(segment
		(start 44.9072 -471.790268)
		(end 45.160946 -472.044014)
		(width 0.174752)
		(layer "B.Cu")
		(net "PE_CLK100M_DR5_2_P")
	)
	(segment
		(start 45.160946 -472.044014)
		(end 45.160946 -472.705684)
		(width 0.174752)
		(layer "B.Cu")
		(net "PE_CLK100M_DR5_2_P")
	)
	(segment
		(start 45.593508 -473.138246)
		(end 48.133 -473.138246)
		(width 0.174752)
		(layer "B.Cu")
		(net "PE_CLK100M_DR5_2_P")
	)
	(segment
		(start 59.954668 -472.70543)
		(end 59.826906 -472.833192)
		(width 0.174752)
		(layer "F.Cu")
		(net "PE_CLK100M_DR5_2_N")
	)
	(segment
		(start 50.878994 -472.70543)
		(end 50.354738 -472.70543)
		(width 0.174752)
		(layer "F.Cu")
		(net "PE_CLK100M_DR5_2_N")
	)
	(segment
		(start 61.258704 -472.70543)
		(end 61.130942 -472.833192)
		(width 0.174752)
		(layer "F.Cu")
		(net "PE_CLK100M_DR5_2_N")
	)
	(segment
		(start 50.354738 -472.70543)
		(end 50.226976 -472.833192)
		(width 0.174752)
		(layer "F.Cu")
		(net "PE_CLK100M_DR5_2_N")
	)
	(segment
		(start 59.826906 -472.833192)
		(end 53.614828 -472.833192)
		(width 0.174752)
		(layer "F.Cu")
		(net "PE_CLK100M_DR5_2_N")
	)
	(segment
		(start 91.44 -442.468)
		(end 91.44 -453.771)
		(width 0.174752)
		(layer "F.Cu")
		(net "PE_CLK100M_DR5_2_N")
	)
	(segment
		(start 90.6526 -441.2361)
		(end 90.6526 -441.6806)
		(width 0.174752)
		(layer "F.Cu")
		(net "PE_CLK100M_DR5_2_N")
	)
	(segment
		(start 52.18303 -472.70543)
		(end 51.658774 -472.70543)
		(width 0.174752)
		(layer "F.Cu")
		(net "PE_CLK100M_DR5_2_N")
	)
	(segment
		(start 48.640746 -472.833192)
		(end 48.387 -472.579446)
		(width 0.174752)
		(layer "F.Cu")
		(net "PE_CLK100M_DR5_2_N")
	)
	(segment
		(start 60.478924 -472.70543)
		(end 59.954668 -472.70543)
		(width 0.174752)
		(layer "F.Cu")
		(net "PE_CLK100M_DR5_2_N")
	)
	(segment
		(start 50.226976 -472.833192)
		(end 48.640746 -472.833192)
		(width 0.174752)
		(layer "F.Cu")
		(net "PE_CLK100M_DR5_2_N")
	)
	(segment
		(start 51.531012 -472.833192)
		(end 51.006756 -472.833192)
		(width 0.174752)
		(layer "F.Cu")
		(net "PE_CLK100M_DR5_2_N")
	)
	(segment
		(start 43.567604 -473.390214)
		(end 43.815 -473.142818)
		(width 0.174752)
		(layer "F.Cu")
		(net "PE_CLK100M_DR5_2_N")
	)
	(segment
		(start 91.44 -453.771)
		(end 72.377808 -472.833192)
		(width 0.174752)
		(layer "F.Cu")
		(net "PE_CLK100M_DR5_2_N")
	)
	(segment
		(start 43.815 -473.142818)
		(end 45.029374 -473.142818)
		(width 0.174752)
		(layer "F.Cu")
		(net "PE_CLK100M_DR5_2_N")
	)
	(segment
		(start 60.606686 -472.833192)
		(end 60.478924 -472.70543)
		(width 0.174752)
		(layer "F.Cu")
		(net "PE_CLK100M_DR5_2_N")
	)
	(segment
		(start 45.029374 -473.142818)
		(end 45.466 -472.706192)
		(width 0.174752)
		(layer "F.Cu")
		(net "PE_CLK100M_DR5_2_N")
	)
	(segment
		(start 72.377808 -472.833192)
		(end 61.910722 -472.833192)
		(width 0.174752)
		(layer "F.Cu")
		(net "PE_CLK100M_DR5_2_N")
	)
	(segment
		(start 53.614828 -472.833192)
		(end 53.487066 -472.70543)
		(width 0.174752)
		(layer "F.Cu")
		(net "PE_CLK100M_DR5_2_N")
	)
	(segment
		(start 90.6526 -441.6806)
		(end 91.44 -442.468)
		(width 0.174752)
		(layer "F.Cu")
		(net "PE_CLK100M_DR5_2_N")
	)
	(segment
		(start 52.96281 -472.70543)
		(end 52.835048 -472.833192)
		(width 0.174752)
		(layer "F.Cu")
		(net "PE_CLK100M_DR5_2_N")
	)
	(segment
		(start 45.466 -472.044268)
		(end 45.72 -471.790268)
		(width 0.174752)
		(layer "F.Cu")
		(net "PE_CLK100M_DR5_2_N")
	)
	(segment
		(start 42.39006 -473.390214)
		(end 43.567604 -473.390214)
		(width 0.174752)
		(layer "F.Cu")
		(net "PE_CLK100M_DR5_2_N")
	)
	(segment
		(start 61.910722 -472.833192)
		(end 61.78296 -472.70543)
		(width 0.174752)
		(layer "F.Cu")
		(net "PE_CLK100M_DR5_2_N")
	)
	(segment
		(start 61.130942 -472.833192)
		(end 60.606686 -472.833192)
		(width 0.174752)
		(layer "F.Cu")
		(net "PE_CLK100M_DR5_2_N")
	)
	(segment
		(start 53.487066 -472.70543)
		(end 52.96281 -472.70543)
		(width 0.174752)
		(layer "F.Cu")
		(net "PE_CLK100M_DR5_2_N")
	)
	(segment
		(start 51.006756 -472.833192)
		(end 50.878994 -472.70543)
		(width 0.174752)
		(layer "F.Cu")
		(net "PE_CLK100M_DR5_2_N")
	)
	(segment
		(start 45.466 -472.706192)
		(end 45.466 -472.044268)
		(width 0.174752)
		(layer "F.Cu")
		(net "PE_CLK100M_DR5_2_N")
	)
	(segment
		(start 52.310792 -472.833192)
		(end 52.18303 -472.70543)
		(width 0.174752)
		(layer "F.Cu")
		(net "PE_CLK100M_DR5_2_N")
	)
	(segment
		(start 90.297 -440.8805)
		(end 90.6526 -441.2361)
		(width 0.174752)
		(layer "F.Cu")
		(net "PE_CLK100M_DR5_2_N")
	)
	(segment
		(start 51.658774 -472.70543)
		(end 51.531012 -472.833192)
		(width 0.174752)
		(layer "F.Cu")
		(net "PE_CLK100M_DR5_2_N")
	)
	(segment
		(start 61.78296 -472.70543)
		(end 61.258704 -472.70543)
		(width 0.174752)
		(layer "F.Cu")
		(net "PE_CLK100M_DR5_2_N")
	)
	(segment
		(start 52.835048 -472.833192)
		(end 52.310792 -472.833192)
		(width 0.174752)
		(layer "F.Cu")
		(net "PE_CLK100M_DR5_2_N")
	)
	(via
		(at 45.72 -471.790268)
		(size 0.508)
		(drill 0.254)
		(layers "F.Cu" "B.Cu")
		(net "PE_CLK100M_DR5_2_N")
	)
	(via
		(at 48.387 -472.579446)
		(size 0.508)
		(drill 0.254)
		(layers "F.Cu" "B.Cu")
		(net "PE_CLK100M_DR5_2_N")
	)
	(segment
		(start 45.72 -472.833192)
		(end 48.133254 -472.833192)
		(width 0.174752)
		(layer "B.Cu")
		(net "PE_CLK100M_DR5_2_N")
	)
	(segment
		(start 45.466 -472.044268)
		(end 45.466 -472.579192)
		(width 0.174752)
		(layer "B.Cu")
		(net "PE_CLK100M_DR5_2_N")
	)
	(segment
		(start 48.133254 -472.833192)
		(end 48.387 -472.579446)
		(width 0.174752)
		(layer "B.Cu")
		(net "PE_CLK100M_DR5_2_N")
	)
	(segment
		(start 45.466 -472.579192)
		(end 45.72 -472.833192)
		(width 0.174752)
		(layer "B.Cu")
		(net "PE_CLK100M_DR5_2_N")
	)
	(segment
		(start 45.72 -471.790268)
		(end 45.466 -472.044268)
		(width 0.174752)
		(layer "B.Cu")
		(net "PE_CLK100M_DR5_2_N")
	)
	(segment
		(start 37.96792 -464.19008)
		(end 39.200074 -464.19008)
		(width 0.174752)
		(layer "F.Cu")
		(net "PE_CLK100M_DR5_1_P")
	)
	(segment
		(start 47.171102 -462.661762)
		(end 46.646846 -462.661762)
		(width 0.174752)
		(layer "F.Cu")
		(net "PE_CLK100M_DR5_1_P")
	)
	(segment
		(start 37.209476 -464.437476)
		(end 37.720524 -464.437476)
		(width 0.174752)
		(layer "F.Cu")
		(net "PE_CLK100M_DR5_1_P")
	)
	(segment
		(start 36.83 -464.058)
		(end 37.209476 -464.437476)
		(width 0.174752)
		(layer "F.Cu")
		(net "PE_CLK100M_DR5_1_P")
	)
	(segment
		(start 53.999384 -462.534)
		(end 53.475128 -462.534)
		(width 0.174752)
		(layer "F.Cu")
		(net "PE_CLK100M_DR5_1_P")
	)
	(segment
		(start 52.695348 -462.534)
		(end 47.298864 -462.534)
		(width 0.174752)
		(layer "F.Cu")
		(net "PE_CLK100M_DR5_1_P")
	)
	(segment
		(start 85.979 -442.976)
		(end 85.979 -453.644)
		(width 0.174752)
		(layer "F.Cu")
		(net "PE_CLK100M_DR5_1_P")
	)
	(segment
		(start 46.646846 -462.661762)
		(end 46.519084 -462.534)
		(width 0.174752)
		(layer "F.Cu")
		(net "PE_CLK100M_DR5_1_P")
	)
	(segment
		(start 87.503 -440.8805)
		(end 87.147654 -441.235846)
		(width 0.174752)
		(layer "F.Cu")
		(net "PE_CLK100M_DR5_1_P")
	)
	(segment
		(start 46.519084 -462.534)
		(end 45.994828 -462.534)
		(width 0.174752)
		(layer "F.Cu")
		(net "PE_CLK100M_DR5_1_P")
	)
	(segment
		(start 45.994828 -462.534)
		(end 45.867066 -462.661762)
		(width 0.174752)
		(layer "F.Cu")
		(net "PE_CLK100M_DR5_1_P")
	)
	(segment
		(start 43.911012 -462.534)
		(end 37.465 -462.534)
		(width 0.174752)
		(layer "F.Cu")
		(net "PE_CLK100M_DR5_1_P")
	)
	(segment
		(start 87.147654 -441.235846)
		(end 87.147654 -441.807346)
		(width 0.174752)
		(layer "F.Cu")
		(net "PE_CLK100M_DR5_1_P")
	)
	(segment
		(start 54.779164 -462.534)
		(end 54.651402 -462.661762)
		(width 0.174752)
		(layer "F.Cu")
		(net "PE_CLK100M_DR5_1_P")
	)
	(segment
		(start 52.82311 -462.661762)
		(end 52.695348 -462.534)
		(width 0.174752)
		(layer "F.Cu")
		(net "PE_CLK100M_DR5_1_P")
	)
	(segment
		(start 54.651402 -462.661762)
		(end 54.127146 -462.661762)
		(width 0.174752)
		(layer "F.Cu")
		(net "PE_CLK100M_DR5_1_P")
	)
	(segment
		(start 45.34281 -462.661762)
		(end 45.215048 -462.534)
		(width 0.174752)
		(layer "F.Cu")
		(net "PE_CLK100M_DR5_1_P")
	)
	(segment
		(start 44.038774 -462.661762)
		(end 43.911012 -462.534)
		(width 0.174752)
		(layer "F.Cu")
		(net "PE_CLK100M_DR5_1_P")
	)
	(segment
		(start 87.147654 -441.807346)
		(end 85.979 -442.976)
		(width 0.174752)
		(layer "F.Cu")
		(net "PE_CLK100M_DR5_1_P")
	)
	(segment
		(start 45.215048 -462.534)
		(end 44.690792 -462.534)
		(width 0.174752)
		(layer "F.Cu")
		(net "PE_CLK100M_DR5_1_P")
	)
	(segment
		(start 53.347366 -462.661762)
		(end 52.82311 -462.661762)
		(width 0.174752)
		(layer "F.Cu")
		(net "PE_CLK100M_DR5_1_P")
	)
	(segment
		(start 45.867066 -462.661762)
		(end 45.34281 -462.661762)
		(width 0.174752)
		(layer "F.Cu")
		(net "PE_CLK100M_DR5_1_P")
	)
	(segment
		(start 54.127146 -462.661762)
		(end 53.999384 -462.534)
		(width 0.174752)
		(layer "F.Cu")
		(net "PE_CLK100M_DR5_1_P")
	)
	(segment
		(start 53.475128 -462.534)
		(end 53.347366 -462.661762)
		(width 0.174752)
		(layer "F.Cu")
		(net "PE_CLK100M_DR5_1_P")
	)
	(segment
		(start 37.465 -462.534)
		(end 36.83 -463.169)
		(width 0.174752)
		(layer "F.Cu")
		(net "PE_CLK100M_DR5_1_P")
	)
	(segment
		(start 36.83 -463.169)
		(end 36.83 -464.058)
		(width 0.174752)
		(layer "F.Cu")
		(net "PE_CLK100M_DR5_1_P")
	)
	(segment
		(start 85.979 -453.644)
		(end 77.089 -462.534)
		(width 0.174752)
		(layer "F.Cu")
		(net "PE_CLK100M_DR5_1_P")
	)
	(segment
		(start 44.690792 -462.534)
		(end 44.56303 -462.661762)
		(width 0.174752)
		(layer "F.Cu")
		(net "PE_CLK100M_DR5_1_P")
	)
	(segment
		(start 77.089 -462.534)
		(end 54.779164 -462.534)
		(width 0.174752)
		(layer "F.Cu")
		(net "PE_CLK100M_DR5_1_P")
	)
	(segment
		(start 37.720524 -464.437476)
		(end 37.96792 -464.19008)
		(width 0.174752)
		(layer "F.Cu")
		(net "PE_CLK100M_DR5_1_P")
	)
	(segment
		(start 44.56303 -462.661762)
		(end 44.038774 -462.661762)
		(width 0.174752)
		(layer "F.Cu")
		(net "PE_CLK100M_DR5_1_P")
	)
	(segment
		(start 47.298864 -462.534)
		(end 47.171102 -462.661762)
		(width 0.174752)
		(layer "F.Cu")
		(net "PE_CLK100M_DR5_1_P")
	)
	(segment
		(start 76.962508 -462.228946)
		(end 85.673946 -453.517508)
		(width 0.174752)
		(layer "F.Cu")
		(net "PE_CLK100M_DR5_1_N")
	)
	(segment
		(start 86.8426 -441.680854)
		(end 86.8426 -441.2361)
		(width 0.174752)
		(layer "F.Cu")
		(net "PE_CLK100M_DR5_1_N")
	)
	(segment
		(start 85.673946 -442.849508)
		(end 86.8426 -441.680854)
		(width 0.174752)
		(layer "F.Cu")
		(net "PE_CLK100M_DR5_1_N")
	)
	(segment
		(start 36.524946 -464.184492)
		(end 36.524946 -463.042508)
		(width 0.174752)
		(layer "F.Cu")
		(net "PE_CLK100M_DR5_1_N")
	)
	(segment
		(start 37.72535 -464.74253)
		(end 37.082984 -464.74253)
		(width 0.174752)
		(layer "F.Cu")
		(net "PE_CLK100M_DR5_1_N")
	)
	(segment
		(start 86.8426 -441.2361)
		(end 86.487 -440.8805)
		(width 0.174752)
		(layer "F.Cu")
		(net "PE_CLK100M_DR5_1_N")
	)
	(segment
		(start 37.973 -464.99018)
		(end 37.72535 -464.74253)
		(width 0.174752)
		(layer "F.Cu")
		(net "PE_CLK100M_DR5_1_N")
	)
	(segment
		(start 85.673946 -453.517508)
		(end 85.673946 -442.849508)
		(width 0.174752)
		(layer "F.Cu")
		(net "PE_CLK100M_DR5_1_N")
	)
	(segment
		(start 36.524946 -463.042508)
		(end 37.338508 -462.228946)
		(width 0.174752)
		(layer "F.Cu")
		(net "PE_CLK100M_DR5_1_N")
	)
	(segment
		(start 39.200074 -464.99018)
		(end 37.973 -464.99018)
		(width 0.174752)
		(layer "F.Cu")
		(net "PE_CLK100M_DR5_1_N")
	)
	(segment
		(start 37.338508 -462.228946)
		(end 76.962508 -462.228946)
		(width 0.174752)
		(layer "F.Cu")
		(net "PE_CLK100M_DR5_1_N")
	)
	(segment
		(start 37.082984 -464.74253)
		(end 36.524946 -464.184492)
		(width 0.174752)
		(layer "F.Cu")
		(net "PE_CLK100M_DR5_1_N")
	)
	(segment
		(start 94.208346 -201.065892)
		(end 93.420946 -200.278492)
		(width 0.174752)
		(layer "F.Cu")
		(net "PE_CLK100M_DR4_2_P")
	)
	(segment
		(start 230.16083 -60.043822)
		(end 230.16083 -60.579508)
		(width 0.174752)
		(layer "F.Cu")
		(net "PE_CLK100M_DR4_2_P")
	)
	(segment
		(start 235.763054 -60.3123)
		(end 234.9373 -61.138054)
		(width 0.174752)
		(layer "F.Cu")
		(net "PE_CLK100M_DR4_2_P")
	)
	(segment
		(start 234.9373 -61.138054)
		(end 233.640884 -61.138054)
		(width 0.174752)
		(layer "F.Cu")
		(net "PE_CLK100M_DR4_2_P")
	)
	(segment
		(start 93.853 -201.7395)
		(end 94.208346 -201.384154)
		(width 0.174752)
		(layer "F.Cu")
		(net "PE_CLK100M_DR4_2_P")
	)
	(segment
		(start 94.208346 -201.384154)
		(end 94.208346 -201.065892)
		(width 0.174752)
		(layer "F.Cu")
		(net "PE_CLK100M_DR4_2_P")
	)
	(segment
		(start 229.932992 -60.807346)
		(end 228.690424 -60.807346)
		(width 0.174752)
		(layer "F.Cu")
		(net "PE_CLK100M_DR4_2_P")
	)
	(segment
		(start 229.488746 -46.938946)
		(end 235.763054 -53.213254)
		(width 0.174752)
		(layer "F.Cu")
		(net "PE_CLK100M_DR4_2_P")
	)
	(segment
		(start 228.473 -60.589922)
		(end 227.389944 -60.589922)
		(width 0.174752)
		(layer "F.Cu")
		(net "PE_CLK100M_DR4_2_P")
	)
	(segment
		(start 93.420946 -200.278492)
		(end 93.420946 -172.822108)
		(width 0.174752)
		(layer "F.Cu")
		(net "PE_CLK100M_DR4_2_P")
	)
	(segment
		(start 219.304108 -46.938946)
		(end 229.488746 -46.938946)
		(width 0.174752)
		(layer "F.Cu")
		(net "PE_CLK100M_DR4_2_P")
	)
	(segment
		(start 230.16083 -60.579508)
		(end 229.932992 -60.807346)
		(width 0.174752)
		(layer "F.Cu")
		(net "PE_CLK100M_DR4_2_P")
	)
	(segment
		(start 93.420946 -172.822108)
		(end 219.304108 -46.938946)
		(width 0.174752)
		(layer "F.Cu")
		(net "PE_CLK100M_DR4_2_P")
	)
	(segment
		(start 229.907084 -59.790076)
		(end 230.16083 -60.043822)
		(width 0.174752)
		(layer "F.Cu")
		(net "PE_CLK100M_DR4_2_P")
	)
	(segment
		(start 235.763054 -53.213254)
		(end 235.763054 -60.3123)
		(width 0.174752)
		(layer "F.Cu")
		(net "PE_CLK100M_DR4_2_P")
	)
	(segment
		(start 233.640884 -61.138054)
		(end 233.386884 -61.392054)
		(width 0.174752)
		(layer "F.Cu")
		(net "PE_CLK100M_DR4_2_P")
	)
	(segment
		(start 228.690424 -60.807346)
		(end 228.473 -60.589922)
		(width 0.174752)
		(layer "F.Cu")
		(net "PE_CLK100M_DR4_2_P")
	)
	(via
		(at 229.907084 -59.790076)
		(size 0.508)
		(drill 0.254)
		(layers "F.Cu" "B.Cu")
		(net "PE_CLK100M_DR4_2_P")
	)
	(via
		(at 233.386884 -61.392054)
		(size 0.508)
		(drill 0.254)
		(layers "F.Cu" "B.Cu")
		(net "PE_CLK100M_DR4_2_P")
	)
	(segment
		(start 233.132884 -61.138054)
		(end 233.386884 -61.392054)
		(width 0.174752)
		(layer "B.Cu")
		(net "PE_CLK100M_DR4_2_P")
	)
	(segment
		(start 229.907084 -59.790076)
		(end 230.16083 -60.043822)
		(width 0.174752)
		(layer "B.Cu")
		(net "PE_CLK100M_DR4_2_P")
	)
	(segment
		(start 230.593392 -61.138054)
		(end 233.132884 -61.138054)
		(width 0.174752)
		(layer "B.Cu")
		(net "PE_CLK100M_DR4_2_P")
	)
	(segment
		(start 230.16083 -60.705492)
		(end 230.593392 -61.138054)
		(width 0.174752)
		(layer "B.Cu")
		(net "PE_CLK100M_DR4_2_P")
	)
	(segment
		(start 230.16083 -60.043822)
		(end 230.16083 -60.705492)
		(width 0.174752)
		(layer "B.Cu")
		(net "PE_CLK100M_DR4_2_P")
	)
	(segment
		(start 235.330238 -59.009534)
		(end 235.330238 -59.53379)
		(width 0.174752)
		(layer "F.Cu")
		(net "PE_CLK100M_DR4_2_N")
	)
	(segment
		(start 223.86671 -47.371762)
		(end 224.390966 -47.371762)
		(width 0.174752)
		(layer "F.Cu")
		(net "PE_CLK100M_DR4_2_N")
	)
	(segment
		(start 235.458 -60.185808)
		(end 234.810808 -60.833)
		(width 0.174752)
		(layer "F.Cu")
		(net "PE_CLK100M_DR4_2_N")
	)
	(segment
		(start 232.691686 -50.754026)
		(end 233.062526 -51.124866)
		(width 0.174752)
		(layer "F.Cu")
		(net "PE_CLK100M_DR4_2_N")
	)
	(segment
		(start 214.316818 -52.357782)
		(end 214.497666 -52.357782)
		(width 0.174752)
		(layer "F.Cu")
		(net "PE_CLK100M_DR4_2_N")
	)
	(segment
		(start 235.330238 -57.705498)
		(end 235.330238 -58.229754)
		(width 0.174752)
		(layer "F.Cu")
		(net "PE_CLK100M_DR4_2_N")
	)
	(segment
		(start 216.664286 -50.010314)
		(end 216.84488 -50.010314)
		(width 0.174752)
		(layer "F.Cu")
		(net "PE_CLK100M_DR4_2_N")
	)
	(segment
		(start 229.362254 -47.244)
		(end 230.344218 -48.225964)
		(width 0.174752)
		(layer "F.Cu")
		(net "PE_CLK100M_DR4_2_N")
	)
	(segment
		(start 230.344218 -48.225964)
		(end 230.344218 -48.406812)
		(width 0.174752)
		(layer "F.Cu")
		(net "PE_CLK100M_DR4_2_N")
	)
	(segment
		(start 218.13774 -48.53686)
		(end 218.50858 -48.16602)
		(width 0.174752)
		(layer "F.Cu")
		(net "PE_CLK100M_DR4_2_N")
	)
	(segment
		(start 217.21572 -49.639474)
		(end 217.21572 -49.45888)
		(width 0.174752)
		(layer "F.Cu")
		(net "PE_CLK100M_DR4_2_N")
	)
	(segment
		(start 235.330238 -58.229754)
		(end 235.458 -58.357516)
		(width 0.174752)
		(layer "F.Cu")
		(net "PE_CLK100M_DR4_2_N")
	)
	(segment
		(start 214.868252 -51.806348)
		(end 216.664286 -50.010314)
		(width 0.174752)
		(layer "F.Cu")
		(net "PE_CLK100M_DR4_2_N")
	)
	(segment
		(start 230.465884 -60.706)
		(end 230.059484 -61.1124)
		(width 0.174752)
		(layer "F.Cu")
		(net "PE_CLK100M_DR4_2_N")
	)
	(segment
		(start 228.479604 -61.390022)
		(end 227.389944 -61.390022)
		(width 0.174752)
		(layer "F.Cu")
		(net "PE_CLK100M_DR4_2_N")
	)
	(segment
		(start 230.719884 -59.790076)
		(end 230.465884 -60.044076)
		(width 0.174752)
		(layer "F.Cu")
		(net "PE_CLK100M_DR4_2_N")
	)
	(segment
		(start 94.869 -201.7395)
		(end 94.5134 -201.3839)
		(width 0.174752)
		(layer "F.Cu")
		(net "PE_CLK100M_DR4_2_N")
	)
	(segment
		(start 213.394798 -53.279802)
		(end 213.575392 -53.279802)
		(width 0.174752)
		(layer "F.Cu")
		(net "PE_CLK100M_DR4_2_N")
	)
	(segment
		(start 217.586306 -49.088294)
		(end 217.767154 -49.088294)
		(width 0.174752)
		(layer "F.Cu")
		(net "PE_CLK100M_DR4_2_N")
	)
	(segment
		(start 232.691686 -50.573432)
		(end 232.691686 -50.754026)
		(width 0.174752)
		(layer "F.Cu")
		(net "PE_CLK100M_DR4_2_N")
	)
	(segment
		(start 218.13774 -48.717454)
		(end 218.13774 -48.53686)
		(width 0.174752)
		(layer "F.Cu")
		(net "PE_CLK100M_DR4_2_N")
	)
	(segment
		(start 217.21572 -49.45888)
		(end 217.586306 -49.088294)
		(width 0.174752)
		(layer "F.Cu")
		(net "PE_CLK100M_DR4_2_N")
	)
	(segment
		(start 233.24312 -51.124866)
		(end 233.613706 -51.495452)
		(width 0.174752)
		(layer "F.Cu")
		(net "PE_CLK100M_DR4_2_N")
	)
	(segment
		(start 235.458 -57.577736)
		(end 235.330238 -57.705498)
		(width 0.174752)
		(layer "F.Cu")
		(net "PE_CLK100M_DR4_2_N")
	)
	(segment
		(start 213.575392 -53.279802)
		(end 213.946232 -52.909216)
		(width 0.174752)
		(layer "F.Cu")
		(net "PE_CLK100M_DR4_2_N")
	)
	(segment
		(start 230.715058 -48.777398)
		(end 230.895652 -48.777398)
		(width 0.174752)
		(layer "F.Cu")
		(net "PE_CLK100M_DR4_2_N")
	)
	(segment
		(start 222.562674 -47.371762)
		(end 223.08693 -47.371762)
		(width 0.174752)
		(layer "F.Cu")
		(net "PE_CLK100M_DR4_2_N")
	)
	(segment
		(start 235.330238 -59.53379)
		(end 235.458 -59.661552)
		(width 0.174752)
		(layer "F.Cu")
		(net "PE_CLK100M_DR4_2_N")
	)
	(segment
		(start 235.458 -58.881772)
		(end 235.330238 -59.009534)
		(width 0.174752)
		(layer "F.Cu")
		(net "PE_CLK100M_DR4_2_N")
	)
	(segment
		(start 235.458 -57.05348)
		(end 235.458 -57.577736)
		(width 0.174752)
		(layer "F.Cu")
		(net "PE_CLK100M_DR4_2_N")
	)
	(segment
		(start 233.64063 -60.833)
		(end 233.386884 -60.579254)
		(width 0.174752)
		(layer "F.Cu")
		(net "PE_CLK100M_DR4_2_N")
	)
	(segment
		(start 228.757226 -61.1124)
		(end 228.479604 -61.390022)
		(width 0.174752)
		(layer "F.Cu")
		(net "PE_CLK100M_DR4_2_N")
	)
	(segment
		(start 93.726 -172.9486)
		(end 213.394798 -53.279802)
		(width 0.174752)
		(layer "F.Cu")
		(net "PE_CLK100M_DR4_2_N")
	)
	(segment
		(start 218.50858 -48.16602)
		(end 218.689174 -48.16602)
		(width 0.174752)
		(layer "F.Cu")
		(net "PE_CLK100M_DR4_2_N")
	)
	(segment
		(start 234.53598 -52.59832)
		(end 234.906566 -52.96916)
		(width 0.174752)
		(layer "F.Cu")
		(net "PE_CLK100M_DR4_2_N")
	)
	(segment
		(start 233.984546 -52.046886)
		(end 234.16514 -52.046886)
		(width 0.174752)
		(layer "F.Cu")
		(net "PE_CLK100M_DR4_2_N")
	)
	(segment
		(start 219.060014 -47.795434)
		(end 219.060014 -47.614586)
		(width 0.174752)
		(layer "F.Cu")
		(net "PE_CLK100M_DR4_2_N")
	)
	(segment
		(start 235.458 -58.357516)
		(end 235.458 -58.881772)
		(width 0.174752)
		(layer "F.Cu")
		(net "PE_CLK100M_DR4_2_N")
	)
	(segment
		(start 222.434912 -47.244)
		(end 222.562674 -47.371762)
		(width 0.174752)
		(layer "F.Cu")
		(net "PE_CLK100M_DR4_2_N")
	)
	(segment
		(start 218.689174 -48.16602)
		(end 219.060014 -47.795434)
		(width 0.174752)
		(layer "F.Cu")
		(net "PE_CLK100M_DR4_2_N")
	)
	(segment
		(start 223.08693 -47.371762)
		(end 223.214692 -47.244)
		(width 0.174752)
		(layer "F.Cu")
		(net "PE_CLK100M_DR4_2_N")
	)
	(segment
		(start 213.946232 -52.728368)
		(end 214.316818 -52.357782)
		(width 0.174752)
		(layer "F.Cu")
		(net "PE_CLK100M_DR4_2_N")
	)
	(segment
		(start 213.946232 -52.909216)
		(end 213.946232 -52.728368)
		(width 0.174752)
		(layer "F.Cu")
		(net "PE_CLK100M_DR4_2_N")
	)
	(segment
		(start 235.330238 -56.401462)
		(end 235.330238 -56.925718)
		(width 0.174752)
		(layer "F.Cu")
		(net "PE_CLK100M_DR4_2_N")
	)
	(segment
		(start 235.458 -56.2737)
		(end 235.330238 -56.401462)
		(width 0.174752)
		(layer "F.Cu")
		(net "PE_CLK100M_DR4_2_N")
	)
	(segment
		(start 224.518728 -47.244)
		(end 229.362254 -47.244)
		(width 0.174752)
		(layer "F.Cu")
		(net "PE_CLK100M_DR4_2_N")
	)
	(segment
		(start 234.16514 -52.046886)
		(end 234.53598 -52.417726)
		(width 0.174752)
		(layer "F.Cu")
		(net "PE_CLK100M_DR4_2_N")
	)
	(segment
		(start 233.613706 -51.6763)
		(end 233.984546 -52.046886)
		(width 0.174752)
		(layer "F.Cu")
		(net "PE_CLK100M_DR4_2_N")
	)
	(segment
		(start 235.458 -53.339746)
		(end 235.458 -56.2737)
		(width 0.174752)
		(layer "F.Cu")
		(net "PE_CLK100M_DR4_2_N")
	)
	(segment
		(start 230.465884 -60.044076)
		(end 230.465884 -60.706)
		(width 0.174752)
		(layer "F.Cu")
		(net "PE_CLK100M_DR4_2_N")
	)
	(segment
		(start 216.84488 -50.010314)
		(end 217.21572 -49.639474)
		(width 0.174752)
		(layer "F.Cu")
		(net "PE_CLK100M_DR4_2_N")
	)
	(segment
		(start 217.767154 -49.088294)
		(end 218.13774 -48.717454)
		(width 0.174752)
		(layer "F.Cu")
		(net "PE_CLK100M_DR4_2_N")
	)
	(segment
		(start 233.613706 -51.495452)
		(end 233.613706 -51.6763)
		(width 0.174752)
		(layer "F.Cu")
		(net "PE_CLK100M_DR4_2_N")
	)
	(segment
		(start 234.810808 -60.833)
		(end 233.64063 -60.833)
		(width 0.174752)
		(layer "F.Cu")
		(net "PE_CLK100M_DR4_2_N")
	)
	(segment
		(start 223.738948 -47.244)
		(end 223.86671 -47.371762)
		(width 0.174752)
		(layer "F.Cu")
		(net "PE_CLK100M_DR4_2_N")
	)
	(segment
		(start 94.5134 -201.3839)
		(end 94.5134 -200.9394)
		(width 0.174752)
		(layer "F.Cu")
		(net "PE_CLK100M_DR4_2_N")
	)
	(segment
		(start 214.868252 -51.986942)
		(end 214.868252 -51.806348)
		(width 0.174752)
		(layer "F.Cu")
		(net "PE_CLK100M_DR4_2_N")
	)
	(segment
		(start 214.497666 -52.357782)
		(end 214.868252 -51.986942)
		(width 0.174752)
		(layer "F.Cu")
		(net "PE_CLK100M_DR4_2_N")
	)
	(segment
		(start 219.060014 -47.614586)
		(end 219.4306 -47.244)
		(width 0.174752)
		(layer "F.Cu")
		(net "PE_CLK100M_DR4_2_N")
	)
	(segment
		(start 224.390966 -47.371762)
		(end 224.518728 -47.244)
		(width 0.174752)
		(layer "F.Cu")
		(net "PE_CLK100M_DR4_2_N")
	)
	(segment
		(start 230.344218 -48.406812)
		(end 230.715058 -48.777398)
		(width 0.174752)
		(layer "F.Cu")
		(net "PE_CLK100M_DR4_2_N")
	)
	(segment
		(start 94.5134 -200.9394)
		(end 93.726 -200.152)
		(width 0.174752)
		(layer "F.Cu")
		(net "PE_CLK100M_DR4_2_N")
	)
	(segment
		(start 235.330238 -56.925718)
		(end 235.458 -57.05348)
		(width 0.174752)
		(layer "F.Cu")
		(net "PE_CLK100M_DR4_2_N")
	)
	(segment
		(start 234.53598 -52.417726)
		(end 234.53598 -52.59832)
		(width 0.174752)
		(layer "F.Cu")
		(net "PE_CLK100M_DR4_2_N")
	)
	(segment
		(start 234.906566 -52.96916)
		(end 235.087414 -52.96916)
		(width 0.174752)
		(layer "F.Cu")
		(net "PE_CLK100M_DR4_2_N")
	)
	(segment
		(start 230.895652 -48.777398)
		(end 232.691686 -50.573432)
		(width 0.174752)
		(layer "F.Cu")
		(net "PE_CLK100M_DR4_2_N")
	)
	(segment
		(start 235.087414 -52.96916)
		(end 235.458 -53.339746)
		(width 0.174752)
		(layer "F.Cu")
		(net "PE_CLK100M_DR4_2_N")
	)
	(segment
		(start 233.062526 -51.124866)
		(end 233.24312 -51.124866)
		(width 0.174752)
		(layer "F.Cu")
		(net "PE_CLK100M_DR4_2_N")
	)
	(segment
		(start 230.059484 -61.1124)
		(end 228.757226 -61.1124)
		(width 0.174752)
		(layer "F.Cu")
		(net "PE_CLK100M_DR4_2_N")
	)
	(segment
		(start 235.458 -59.661552)
		(end 235.458 -60.185808)
		(width 0.174752)
		(layer "F.Cu")
		(net "PE_CLK100M_DR4_2_N")
	)
	(segment
		(start 223.214692 -47.244)
		(end 223.738948 -47.244)
		(width 0.174752)
		(layer "F.Cu")
		(net "PE_CLK100M_DR4_2_N")
	)
	(segment
		(start 93.726 -200.152)
		(end 93.726 -172.9486)
		(width 0.174752)
		(layer "F.Cu")
		(net "PE_CLK100M_DR4_2_N")
	)
	(segment
		(start 219.4306 -47.244)
		(end 222.434912 -47.244)
		(width 0.174752)
		(layer "F.Cu")
		(net "PE_CLK100M_DR4_2_N")
	)
	(via
		(at 230.719884 -59.790076)
		(size 0.508)
		(drill 0.254)
		(layers "F.Cu" "B.Cu")
		(net "PE_CLK100M_DR4_2_N")
	)
	(via
		(at 233.386884 -60.579254)
		(size 0.508)
		(drill 0.254)
		(layers "F.Cu" "B.Cu")
		(net "PE_CLK100M_DR4_2_N")
	)
	(segment
		(start 230.465884 -60.579)
		(end 230.719884 -60.833)
		(width 0.174752)
		(layer "B.Cu")
		(net "PE_CLK100M_DR4_2_N")
	)
	(segment
		(start 230.719884 -60.833)
		(end 233.133138 -60.833)
		(width 0.174752)
		(layer "B.Cu")
		(net "PE_CLK100M_DR4_2_N")
	)
	(segment
		(start 230.465884 -60.044076)
		(end 230.465884 -60.579)
		(width 0.174752)
		(layer "B.Cu")
		(net "PE_CLK100M_DR4_2_N")
	)
	(segment
		(start 233.133138 -60.833)
		(end 233.386884 -60.579254)
		(width 0.174752)
		(layer "B.Cu")
		(net "PE_CLK100M_DR4_2_N")
	)
	(segment
		(start 230.719884 -59.790076)
		(end 230.465884 -60.044076)
		(width 0.174752)
		(layer "B.Cu")
		(net "PE_CLK100M_DR4_2_N")
	)
	(segment
		(start 99.187 -199.644)
		(end 99.187 -171.958)
		(width 0.174752)
		(layer "F.Cu")
		(net "PE_CLK100M_DR4_1_P")
	)
	(segment
		(start 98.018346 -201.384154)
		(end 98.018346 -200.812654)
		(width 0.174752)
		(layer "F.Cu")
		(net "PE_CLK100M_DR4_1_P")
	)
	(segment
		(start 223.132396 -52.189888)
		(end 224.199958 -52.189888)
		(width 0.174752)
		(layer "F.Cu")
		(net "PE_CLK100M_DR4_1_P")
	)
	(segment
		(start 99.187 -171.958)
		(end 218.694254 -52.450746)
		(width 0.174752)
		(layer "F.Cu")
		(net "PE_CLK100M_DR4_1_P")
	)
	(segment
		(start 218.694254 -52.450746)
		(end 222.871538 -52.450746)
		(width 0.174752)
		(layer "F.Cu")
		(net "PE_CLK100M_DR4_1_P")
	)
	(segment
		(start 98.018346 -200.812654)
		(end 99.187 -199.644)
		(width 0.174752)
		(layer "F.Cu")
		(net "PE_CLK100M_DR4_1_P")
	)
	(segment
		(start 222.871538 -52.450746)
		(end 223.132396 -52.189888)
		(width 0.174752)
		(layer "F.Cu")
		(net "PE_CLK100M_DR4_1_P")
	)
	(segment
		(start 97.663 -201.7395)
		(end 98.018346 -201.384154)
		(width 0.174752)
		(layer "F.Cu")
		(net "PE_CLK100M_DR4_1_P")
	)
	(segment
		(start 98.3234 -200.939146)
		(end 99.492054 -199.770492)
		(width 0.174752)
		(layer "F.Cu")
		(net "PE_CLK100M_DR4_1_N")
	)
	(segment
		(start 211.163916 -60.41263)
		(end 211.534756 -60.04179)
		(width 0.174752)
		(layer "F.Cu")
		(net "PE_CLK100M_DR4_1_N")
	)
	(segment
		(start 216.277698 -55.479442)
		(end 216.277698 -55.298848)
		(width 0.174752)
		(layer "F.Cu")
		(net "PE_CLK100M_DR4_1_N")
	)
	(segment
		(start 98.679 -201.7395)
		(end 98.3234 -201.3839)
		(width 0.174752)
		(layer "F.Cu")
		(net "PE_CLK100M_DR4_1_N")
	)
	(segment
		(start 223.13265 -52.989988)
		(end 224.199958 -52.989988)
		(width 0.174752)
		(layer "F.Cu")
		(net "PE_CLK100M_DR4_1_N")
	)
	(segment
		(start 215.355678 -56.401716)
		(end 215.355678 -56.220868)
		(width 0.174752)
		(layer "F.Cu")
		(net "PE_CLK100M_DR4_1_N")
	)
	(segment
		(start 211.71535 -60.04179)
		(end 212.08619 -59.671204)
		(width 0.174752)
		(layer "F.Cu")
		(net "PE_CLK100M_DR4_1_N")
	)
	(segment
		(start 210.79333 -60.96381)
		(end 211.163916 -60.593224)
		(width 0.174752)
		(layer "F.Cu")
		(net "PE_CLK100M_DR4_1_N")
	)
	(segment
		(start 214.062818 -57.694322)
		(end 214.433658 -57.323736)
		(width 0.174752)
		(layer "F.Cu")
		(net "PE_CLK100M_DR4_1_N")
	)
	(segment
		(start 211.534756 -60.04179)
		(end 211.71535 -60.04179)
		(width 0.174752)
		(layer "F.Cu")
		(net "PE_CLK100M_DR4_1_N")
	)
	(segment
		(start 214.984838 -56.772302)
		(end 215.355678 -56.401716)
		(width 0.174752)
		(layer "F.Cu")
		(net "PE_CLK100M_DR4_1_N")
	)
	(segment
		(start 214.804244 -56.772302)
		(end 214.984838 -56.772302)
		(width 0.174752)
		(layer "F.Cu")
		(net "PE_CLK100M_DR4_1_N")
	)
	(segment
		(start 210.612736 -60.96381)
		(end 210.79333 -60.96381)
		(width 0.174752)
		(layer "F.Cu")
		(net "PE_CLK100M_DR4_1_N")
	)
	(segment
		(start 211.163916 -60.593224)
		(end 211.163916 -60.41263)
		(width 0.174752)
		(layer "F.Cu")
		(net "PE_CLK100M_DR4_1_N")
	)
	(segment
		(start 215.726264 -55.850282)
		(end 215.907112 -55.850282)
		(width 0.174752)
		(layer "F.Cu")
		(net "PE_CLK100M_DR4_1_N")
	)
	(segment
		(start 218.820746 -52.7558)
		(end 222.898462 -52.7558)
		(width 0.174752)
		(layer "F.Cu")
		(net "PE_CLK100M_DR4_1_N")
	)
	(segment
		(start 99.492054 -199.770492)
		(end 99.492054 -172.084492)
		(width 0.174752)
		(layer "F.Cu")
		(net "PE_CLK100M_DR4_1_N")
	)
	(segment
		(start 212.08619 -59.490356)
		(end 213.882224 -57.694322)
		(width 0.174752)
		(layer "F.Cu")
		(net "PE_CLK100M_DR4_1_N")
	)
	(segment
		(start 222.898462 -52.7558)
		(end 223.13265 -52.989988)
		(width 0.174752)
		(layer "F.Cu")
		(net "PE_CLK100M_DR4_1_N")
	)
	(segment
		(start 215.355678 -56.220868)
		(end 215.726264 -55.850282)
		(width 0.174752)
		(layer "F.Cu")
		(net "PE_CLK100M_DR4_1_N")
	)
	(segment
		(start 214.433658 -57.142888)
		(end 214.804244 -56.772302)
		(width 0.174752)
		(layer "F.Cu")
		(net "PE_CLK100M_DR4_1_N")
	)
	(segment
		(start 212.08619 -59.671204)
		(end 212.08619 -59.490356)
		(width 0.174752)
		(layer "F.Cu")
		(net "PE_CLK100M_DR4_1_N")
	)
	(segment
		(start 216.277698 -55.298848)
		(end 218.820746 -52.7558)
		(width 0.174752)
		(layer "F.Cu")
		(net "PE_CLK100M_DR4_1_N")
	)
	(segment
		(start 215.907112 -55.850282)
		(end 216.277698 -55.479442)
		(width 0.174752)
		(layer "F.Cu")
		(net "PE_CLK100M_DR4_1_N")
	)
	(segment
		(start 99.492054 -172.084492)
		(end 210.612736 -60.96381)
		(width 0.174752)
		(layer "F.Cu")
		(net "PE_CLK100M_DR4_1_N")
	)
	(segment
		(start 98.3234 -201.3839)
		(end 98.3234 -200.939146)
		(width 0.174752)
		(layer "F.Cu")
		(net "PE_CLK100M_DR4_1_N")
	)
	(segment
		(start 213.882224 -57.694322)
		(end 214.062818 -57.694322)
		(width 0.174752)
		(layer "F.Cu")
		(net "PE_CLK100M_DR4_1_N")
	)
	(segment
		(start 214.433658 -57.323736)
		(end 214.433658 -57.142888)
		(width 0.174752)
		(layer "F.Cu")
		(net "PE_CLK100M_DR4_1_N")
	)
	(segment
		(start 228.473 -163.58997)
		(end 228.72065 -163.83762)
		(width 0.174752)
		(layer "F.Cu")
		(net "PE_CLK100M_DR3_2_P")
	)
	(segment
		(start 230.16083 -163.04387)
		(end 229.907084 -162.790124)
		(width 0.174752)
		(layer "F.Cu")
		(net "PE_CLK100M_DR3_2_P")
	)
	(segment
		(start 227.080572 -149.808946)
		(end 227.366322 -150.094696)
		(width 0.174752)
		(layer "F.Cu")
		(net "PE_CLK100M_DR3_2_P")
	)
	(segment
		(start 124.11583 -149.808946)
		(end 227.080572 -149.808946)
		(width 0.174752)
		(layer "F.Cu")
		(net "PE_CLK100M_DR3_2_P")
	)
	(segment
		(start 110.744 -163.180776)
		(end 124.11583 -149.808946)
		(width 0.174752)
		(layer "F.Cu")
		(net "PE_CLK100M_DR3_2_P")
	)
	(segment
		(start 110.744 -202.565)
		(end 110.744 -163.180776)
		(width 0.174752)
		(layer "F.Cu")
		(net "PE_CLK100M_DR3_2_P")
	)
	(segment
		(start 104.597708 -204.037946)
		(end 109.271054 -204.037946)
		(width 0.174752)
		(layer "F.Cu")
		(net "PE_CLK100M_DR3_2_P")
	)
	(segment
		(start 230.16083 -163.579556)
		(end 230.16083 -163.04387)
		(width 0.174752)
		(layer "F.Cu")
		(net "PE_CLK100M_DR3_2_P")
	)
	(segment
		(start 227.366322 -150.094696)
		(end 229.139242 -150.094696)
		(width 0.174752)
		(layer "F.Cu")
		(net "PE_CLK100M_DR3_2_P")
	)
	(segment
		(start 228.72065 -163.83762)
		(end 229.902766 -163.83762)
		(width 0.174752)
		(layer "F.Cu")
		(net "PE_CLK100M_DR3_2_P")
	)
	(segment
		(start 103.0605 -204.47)
		(end 103.365046 -204.774546)
		(width 0.174752)
		(layer "F.Cu")
		(net "PE_CLK100M_DR3_2_P")
	)
	(segment
		(start 103.861108 -204.774546)
		(end 104.597708 -204.037946)
		(width 0.174752)
		(layer "F.Cu")
		(net "PE_CLK100M_DR3_2_P")
	)
	(segment
		(start 234.9373 -164.138102)
		(end 233.640884 -164.138102)
		(width 0.174752)
		(layer "F.Cu")
		(net "PE_CLK100M_DR3_2_P")
	)
	(segment
		(start 109.271054 -204.037946)
		(end 110.744 -202.565)
		(width 0.174752)
		(layer "F.Cu")
		(net "PE_CLK100M_DR3_2_P")
	)
	(segment
		(start 233.640884 -164.138102)
		(end 233.386884 -164.392102)
		(width 0.174752)
		(layer "F.Cu")
		(net "PE_CLK100M_DR3_2_P")
	)
	(segment
		(start 229.902766 -163.83762)
		(end 230.16083 -163.579556)
		(width 0.174752)
		(layer "F.Cu")
		(net "PE_CLK100M_DR3_2_P")
	)
	(segment
		(start 103.365046 -204.774546)
		(end 103.861108 -204.774546)
		(width 0.174752)
		(layer "F.Cu")
		(net "PE_CLK100M_DR3_2_P")
	)
	(segment
		(start 235.712 -163.363402)
		(end 234.9373 -164.138102)
		(width 0.174752)
		(layer "F.Cu")
		(net "PE_CLK100M_DR3_2_P")
	)
	(segment
		(start 229.139242 -150.094696)
		(end 235.712 -156.667454)
		(width 0.174752)
		(layer "F.Cu")
		(net "PE_CLK100M_DR3_2_P")
	)
	(segment
		(start 227.389944 -163.58997)
		(end 228.473 -163.58997)
		(width 0.174752)
		(layer "F.Cu")
		(net "PE_CLK100M_DR3_2_P")
	)
	(segment
		(start 235.712 -156.667454)
		(end 235.712 -163.363402)
		(width 0.174752)
		(layer "F.Cu")
		(net "PE_CLK100M_DR3_2_P")
	)
	(via
		(at 229.907084 -162.790124)
		(size 0.508)
		(drill 0.254)
		(layers "F.Cu" "B.Cu")
		(net "PE_CLK100M_DR3_2_P")
	)
	(via
		(at 233.386884 -164.392102)
		(size 0.508)
		(drill 0.254)
		(layers "F.Cu" "B.Cu")
		(net "PE_CLK100M_DR3_2_P")
	)
	(segment
		(start 233.386884 -164.392102)
		(end 233.132884 -164.138102)
		(width 0.174752)
		(layer "B.Cu")
		(net "PE_CLK100M_DR3_2_P")
	)
	(segment
		(start 230.593392 -164.138102)
		(end 230.16083 -163.70554)
		(width 0.174752)
		(layer "B.Cu")
		(net "PE_CLK100M_DR3_2_P")
	)
	(segment
		(start 230.16083 -163.70554)
		(end 230.16083 -163.04387)
		(width 0.174752)
		(layer "B.Cu")
		(net "PE_CLK100M_DR3_2_P")
	)
	(segment
		(start 230.16083 -163.04387)
		(end 229.907084 -162.790124)
		(width 0.174752)
		(layer "B.Cu")
		(net "PE_CLK100M_DR3_2_P")
	)
	(segment
		(start 233.132884 -164.138102)
		(end 230.593392 -164.138102)
		(width 0.174752)
		(layer "B.Cu")
		(net "PE_CLK100M_DR3_2_P")
	)
	(segment
		(start 226.95408 -150.114)
		(end 227.23983 -150.39975)
		(width 0.174752)
		(layer "F.Cu")
		(net "PE_CLK100M_DR3_2_N")
	)
	(segment
		(start 222.991172 -150.114)
		(end 223.118934 -150.241762)
		(width 0.174752)
		(layer "F.Cu")
		(net "PE_CLK100M_DR3_2_N")
	)
	(segment
		(start 233.933492 -155.501086)
		(end 234.114086 -155.501086)
		(width 0.174752)
		(layer "F.Cu")
		(net "PE_CLK100M_DR3_2_N")
	)
	(segment
		(start 229.01275 -150.39975)
		(end 230.293164 -151.680164)
		(width 0.174752)
		(layer "F.Cu")
		(net "PE_CLK100M_DR3_2_N")
	)
	(segment
		(start 227.23983 -150.39975)
		(end 229.01275 -150.39975)
		(width 0.174752)
		(layer "F.Cu")
		(net "PE_CLK100M_DR3_2_N")
	)
	(segment
		(start 230.029258 -164.142674)
		(end 230.465884 -163.706048)
		(width 0.174752)
		(layer "F.Cu")
		(net "PE_CLK100M_DR3_2_N")
	)
	(segment
		(start 234.810808 -163.833048)
		(end 233.64063 -163.833048)
		(width 0.174752)
		(layer "F.Cu")
		(net "PE_CLK100M_DR3_2_N")
	)
	(segment
		(start 234.484926 -155.871926)
		(end 234.484926 -156.05252)
		(width 0.174752)
		(layer "F.Cu")
		(net "PE_CLK100M_DR3_2_N")
	)
	(segment
		(start 225.074988 -150.114)
		(end 226.95408 -150.114)
		(width 0.174752)
		(layer "F.Cu")
		(net "PE_CLK100M_DR3_2_N")
	)
	(segment
		(start 223.118934 -150.241762)
		(end 223.64319 -150.241762)
		(width 0.174752)
		(layer "F.Cu")
		(net "PE_CLK100M_DR3_2_N")
	)
	(segment
		(start 103.9876 -205.0796)
		(end 104.7242 -204.343)
		(width 0.174752)
		(layer "F.Cu")
		(net "PE_CLK100M_DR3_2_N")
	)
	(segment
		(start 224.42297 -150.241762)
		(end 224.947226 -150.241762)
		(width 0.174752)
		(layer "F.Cu")
		(net "PE_CLK100M_DR3_2_N")
	)
	(segment
		(start 232.640632 -154.208226)
		(end 233.011472 -154.579066)
		(width 0.174752)
		(layer "F.Cu")
		(net "PE_CLK100M_DR3_2_N")
	)
	(segment
		(start 235.406946 -161.087562)
		(end 235.406946 -161.611818)
		(width 0.174752)
		(layer "F.Cu")
		(net "PE_CLK100M_DR3_2_N")
	)
	(segment
		(start 230.664004 -152.231598)
		(end 230.844598 -152.231598)
		(width 0.174752)
		(layer "F.Cu")
		(net "PE_CLK100M_DR3_2_N")
	)
	(segment
		(start 230.293164 -151.680164)
		(end 230.293164 -151.861012)
		(width 0.174752)
		(layer "F.Cu")
		(net "PE_CLK100M_DR3_2_N")
	)
	(segment
		(start 227.389944 -164.39007)
		(end 228.479604 -164.39007)
		(width 0.174752)
		(layer "F.Cu")
		(net "PE_CLK100M_DR3_2_N")
	)
	(segment
		(start 234.484926 -156.05252)
		(end 234.855512 -156.42336)
		(width 0.174752)
		(layer "F.Cu")
		(net "PE_CLK100M_DR3_2_N")
	)
	(segment
		(start 233.562652 -154.949652)
		(end 233.562652 -155.1305)
		(width 0.174752)
		(layer "F.Cu")
		(net "PE_CLK100M_DR3_2_N")
	)
	(segment
		(start 235.279184 -159.131508)
		(end 235.279184 -159.655764)
		(width 0.174752)
		(layer "F.Cu")
		(net "PE_CLK100M_DR3_2_N")
	)
	(segment
		(start 235.279184 -160.435544)
		(end 235.279184 -160.9598)
		(width 0.174752)
		(layer "F.Cu")
		(net "PE_CLK100M_DR3_2_N")
	)
	(segment
		(start 223.64319 -150.241762)
		(end 223.770952 -150.114)
		(width 0.174752)
		(layer "F.Cu")
		(net "PE_CLK100M_DR3_2_N")
	)
	(segment
		(start 234.114086 -155.501086)
		(end 234.484926 -155.871926)
		(width 0.174752)
		(layer "F.Cu")
		(net "PE_CLK100M_DR3_2_N")
	)
	(segment
		(start 235.279184 -162.263836)
		(end 235.406946 -162.391598)
		(width 0.174752)
		(layer "F.Cu")
		(net "PE_CLK100M_DR3_2_N")
	)
	(segment
		(start 235.406946 -163.23691)
		(end 234.810808 -163.833048)
		(width 0.174752)
		(layer "F.Cu")
		(net "PE_CLK100M_DR3_2_N")
	)
	(segment
		(start 233.011472 -154.579066)
		(end 233.192066 -154.579066)
		(width 0.174752)
		(layer "F.Cu")
		(net "PE_CLK100M_DR3_2_N")
	)
	(segment
		(start 224.947226 -150.241762)
		(end 225.074988 -150.114)
		(width 0.174752)
		(layer "F.Cu")
		(net "PE_CLK100M_DR3_2_N")
	)
	(segment
		(start 235.406946 -161.611818)
		(end 235.279184 -161.73958)
		(width 0.174752)
		(layer "F.Cu")
		(net "PE_CLK100M_DR3_2_N")
	)
	(segment
		(start 232.640632 -154.027632)
		(end 232.640632 -154.208226)
		(width 0.174752)
		(layer "F.Cu")
		(net "PE_CLK100M_DR3_2_N")
	)
	(segment
		(start 233.562652 -155.1305)
		(end 233.933492 -155.501086)
		(width 0.174752)
		(layer "F.Cu")
		(net "PE_CLK100M_DR3_2_N")
	)
	(segment
		(start 111.049054 -163.307268)
		(end 124.242322 -150.114)
		(width 0.174752)
		(layer "F.Cu")
		(net "PE_CLK100M_DR3_2_N")
	)
	(segment
		(start 230.465884 -163.044124)
		(end 230.719884 -162.790124)
		(width 0.174752)
		(layer "F.Cu")
		(net "PE_CLK100M_DR3_2_N")
	)
	(segment
		(start 124.242322 -150.114)
		(end 222.991172 -150.114)
		(width 0.174752)
		(layer "F.Cu")
		(net "PE_CLK100M_DR3_2_N")
	)
	(segment
		(start 235.279184 -160.9598)
		(end 235.406946 -161.087562)
		(width 0.174752)
		(layer "F.Cu")
		(net "PE_CLK100M_DR3_2_N")
	)
	(segment
		(start 223.770952 -150.114)
		(end 224.295208 -150.114)
		(width 0.174752)
		(layer "F.Cu")
		(net "PE_CLK100M_DR3_2_N")
	)
	(segment
		(start 235.406946 -159.783526)
		(end 235.406946 -160.307782)
		(width 0.174752)
		(layer "F.Cu")
		(net "PE_CLK100M_DR3_2_N")
	)
	(segment
		(start 103.4669 -205.0796)
		(end 103.9876 -205.0796)
		(width 0.174752)
		(layer "F.Cu")
		(net "PE_CLK100M_DR3_2_N")
	)
	(segment
		(start 230.844598 -152.231598)
		(end 232.640632 -154.027632)
		(width 0.174752)
		(layer "F.Cu")
		(net "PE_CLK100M_DR3_2_N")
	)
	(segment
		(start 235.03636 -156.42336)
		(end 235.406946 -156.793946)
		(width 0.174752)
		(layer "F.Cu")
		(net "PE_CLK100M_DR3_2_N")
	)
	(segment
		(start 235.279184 -161.73958)
		(end 235.279184 -162.263836)
		(width 0.174752)
		(layer "F.Cu")
		(net "PE_CLK100M_DR3_2_N")
	)
	(segment
		(start 109.397546 -204.343)
		(end 111.049054 -202.691492)
		(width 0.174752)
		(layer "F.Cu")
		(net "PE_CLK100M_DR3_2_N")
	)
	(segment
		(start 103.0605 -205.486)
		(end 103.4669 -205.0796)
		(width 0.174752)
		(layer "F.Cu")
		(net "PE_CLK100M_DR3_2_N")
	)
	(segment
		(start 235.406946 -159.003746)
		(end 235.279184 -159.131508)
		(width 0.174752)
		(layer "F.Cu")
		(net "PE_CLK100M_DR3_2_N")
	)
	(segment
		(start 235.406946 -160.307782)
		(end 235.279184 -160.435544)
		(width 0.174752)
		(layer "F.Cu")
		(net "PE_CLK100M_DR3_2_N")
	)
	(segment
		(start 228.479604 -164.39007)
		(end 228.727 -164.142674)
		(width 0.174752)
		(layer "F.Cu")
		(net "PE_CLK100M_DR3_2_N")
	)
	(segment
		(start 235.406946 -156.793946)
		(end 235.406946 -159.003746)
		(width 0.174752)
		(layer "F.Cu")
		(net "PE_CLK100M_DR3_2_N")
	)
	(segment
		(start 235.406946 -162.391598)
		(end 235.406946 -163.23691)
		(width 0.174752)
		(layer "F.Cu")
		(net "PE_CLK100M_DR3_2_N")
	)
	(segment
		(start 230.293164 -151.861012)
		(end 230.664004 -152.231598)
		(width 0.174752)
		(layer "F.Cu")
		(net "PE_CLK100M_DR3_2_N")
	)
	(segment
		(start 235.279184 -159.655764)
		(end 235.406946 -159.783526)
		(width 0.174752)
		(layer "F.Cu")
		(net "PE_CLK100M_DR3_2_N")
	)
	(segment
		(start 230.465884 -163.706048)
		(end 230.465884 -163.044124)
		(width 0.174752)
		(layer "F.Cu")
		(net "PE_CLK100M_DR3_2_N")
	)
	(segment
		(start 234.855512 -156.42336)
		(end 235.03636 -156.42336)
		(width 0.174752)
		(layer "F.Cu")
		(net "PE_CLK100M_DR3_2_N")
	)
	(segment
		(start 224.295208 -150.114)
		(end 224.42297 -150.241762)
		(width 0.174752)
		(layer "F.Cu")
		(net "PE_CLK100M_DR3_2_N")
	)
	(segment
		(start 233.64063 -163.833048)
		(end 233.386884 -163.579302)
		(width 0.174752)
		(layer "F.Cu")
		(net "PE_CLK100M_DR3_2_N")
	)
	(segment
		(start 111.049054 -202.691492)
		(end 111.049054 -163.307268)
		(width 0.174752)
		(layer "F.Cu")
		(net "PE_CLK100M_DR3_2_N")
	)
	(segment
		(start 104.7242 -204.343)
		(end 109.397546 -204.343)
		(width 0.174752)
		(layer "F.Cu")
		(net "PE_CLK100M_DR3_2_N")
	)
	(segment
		(start 233.192066 -154.579066)
		(end 233.562652 -154.949652)
		(width 0.174752)
		(layer "F.Cu")
		(net "PE_CLK100M_DR3_2_N")
	)
	(segment
		(start 228.727 -164.142674)
		(end 230.029258 -164.142674)
		(width 0.174752)
		(layer "F.Cu")
		(net "PE_CLK100M_DR3_2_N")
	)
	(via
		(at 230.719884 -162.790124)
		(size 0.508)
		(drill 0.254)
		(layers "F.Cu" "B.Cu")
		(net "PE_CLK100M_DR3_2_N")
	)
	(via
		(at 233.386884 -163.579302)
		(size 0.508)
		(drill 0.254)
		(layers "F.Cu" "B.Cu")
		(net "PE_CLK100M_DR3_2_N")
	)
	(segment
		(start 230.465884 -163.044124)
		(end 230.719884 -162.790124)
		(width 0.174752)
		(layer "B.Cu")
		(net "PE_CLK100M_DR3_2_N")
	)
	(segment
		(start 230.465884 -163.579048)
		(end 230.465884 -163.044124)
		(width 0.174752)
		(layer "B.Cu")
		(net "PE_CLK100M_DR3_2_N")
	)
	(segment
		(start 233.386884 -163.579302)
		(end 233.133138 -163.833048)
		(width 0.174752)
		(layer "B.Cu")
		(net "PE_CLK100M_DR3_2_N")
	)
	(segment
		(start 233.133138 -163.833048)
		(end 230.719884 -163.833048)
		(width 0.174752)
		(layer "B.Cu")
		(net "PE_CLK100M_DR3_2_N")
	)
	(segment
		(start 230.719884 -163.833048)
		(end 230.465884 -163.579048)
		(width 0.174752)
		(layer "B.Cu")
		(net "PE_CLK100M_DR3_2_N")
	)
	(segment
		(start 105.156 -209.804)
		(end 112.903 -209.804)
		(width 0.174752)
		(layer "F.Cu")
		(net "PE_CLK100M_DR3_1_P")
	)
	(segment
		(start 115.189 -165.022276)
		(end 124.773944 -155.437332)
		(width 0.174752)
		(layer "F.Cu")
		(net "PE_CLK100M_DR3_1_P")
	)
	(segment
		(start 223.005396 -155.189936)
		(end 224.199958 -155.189936)
		(width 0.174752)
		(layer "F.Cu")
		(net "PE_CLK100M_DR3_1_P")
	)
	(segment
		(start 103.987346 -208.635346)
		(end 105.156 -209.804)
		(width 0.174752)
		(layer "F.Cu")
		(net "PE_CLK100M_DR3_1_P")
	)
	(segment
		(start 124.773944 -155.437332)
		(end 222.758 -155.437332)
		(width 0.174752)
		(layer "F.Cu")
		(net "PE_CLK100M_DR3_1_P")
	)
	(segment
		(start 222.758 -155.437332)
		(end 223.005396 -155.189936)
		(width 0.174752)
		(layer "F.Cu")
		(net "PE_CLK100M_DR3_1_P")
	)
	(segment
		(start 112.903 -209.804)
		(end 115.189 -207.518)
		(width 0.174752)
		(layer "F.Cu")
		(net "PE_CLK100M_DR3_1_P")
	)
	(segment
		(start 103.0605 -208.28)
		(end 103.415846 -208.635346)
		(width 0.174752)
		(layer "F.Cu")
		(net "PE_CLK100M_DR3_1_P")
	)
	(segment
		(start 103.415846 -208.635346)
		(end 103.987346 -208.635346)
		(width 0.174752)
		(layer "F.Cu")
		(net "PE_CLK100M_DR3_1_P")
	)
	(segment
		(start 115.189 -207.518)
		(end 115.189 -165.022276)
		(width 0.174752)
		(layer "F.Cu")
		(net "PE_CLK100M_DR3_1_P")
	)
	(segment
		(start 103.0605 -209.296)
		(end 103.4161 -208.9404)
		(width 0.174752)
		(layer "F.Cu")
		(net "PE_CLK100M_DR3_1_N")
	)
	(segment
		(start 115.494054 -207.644492)
		(end 115.494054 -165.148768)
		(width 0.174752)
		(layer "F.Cu")
		(net "PE_CLK100M_DR3_1_N")
	)
	(segment
		(start 103.4161 -208.9404)
		(end 103.860854 -208.9404)
		(width 0.174752)
		(layer "F.Cu")
		(net "PE_CLK100M_DR3_1_N")
	)
	(segment
		(start 124.900436 -155.742386)
		(end 222.798386 -155.742386)
		(width 0.174752)
		(layer "F.Cu")
		(net "PE_CLK100M_DR3_1_N")
	)
	(segment
		(start 222.798386 -155.742386)
		(end 223.046036 -155.990036)
		(width 0.174752)
		(layer "F.Cu")
		(net "PE_CLK100M_DR3_1_N")
	)
	(segment
		(start 113.029492 -210.109054)
		(end 115.494054 -207.644492)
		(width 0.174752)
		(layer "F.Cu")
		(net "PE_CLK100M_DR3_1_N")
	)
	(segment
		(start 223.046036 -155.990036)
		(end 224.199958 -155.990036)
		(width 0.174752)
		(layer "F.Cu")
		(net "PE_CLK100M_DR3_1_N")
	)
	(segment
		(start 115.494054 -165.148768)
		(end 124.900436 -155.742386)
		(width 0.174752)
		(layer "F.Cu")
		(net "PE_CLK100M_DR3_1_N")
	)
	(segment
		(start 103.860854 -208.9404)
		(end 105.029508 -210.109054)
		(width 0.174752)
		(layer "F.Cu")
		(net "PE_CLK100M_DR3_1_N")
	)
	(segment
		(start 105.029508 -210.109054)
		(end 113.029492 -210.109054)
		(width 0.174752)
		(layer "F.Cu")
		(net "PE_CLK100M_DR3_1_N")
	)
	(segment
		(start 95.859346 -295.426892)
		(end 95.071946 -294.639492)
		(width 0.174752)
		(layer "F.Cu")
		(net "PE_CLK100M_DR2_2_P")
	)
	(segment
		(start 230.16083 -266.043918)
		(end 230.16083 -266.579604)
		(width 0.174752)
		(layer "F.Cu")
		(net "PE_CLK100M_DR2_2_P")
	)
	(segment
		(start 220.396054 -254.4064)
		(end 221.869508 -252.932946)
		(width 0.174752)
		(layer "F.Cu")
		(net "PE_CLK100M_DR2_2_P")
	)
	(segment
		(start 235.712 -266.36345)
		(end 234.9373 -267.13815)
		(width 0.174752)
		(layer "F.Cu")
		(net "PE_CLK100M_DR2_2_P")
	)
	(segment
		(start 229.768146 -252.932946)
		(end 235.712 -258.8768)
		(width 0.174752)
		(layer "F.Cu")
		(net "PE_CLK100M_DR2_2_P")
	)
	(segment
		(start 124.307854 -254.4064)
		(end 220.396054 -254.4064)
		(width 0.174752)
		(layer "F.Cu")
		(net "PE_CLK100M_DR2_2_P")
	)
	(segment
		(start 230.16083 -266.579604)
		(end 229.939088 -266.801346)
		(width 0.174752)
		(layer "F.Cu")
		(net "PE_CLK100M_DR2_2_P")
	)
	(segment
		(start 95.504 -296.1005)
		(end 95.859346 -295.745154)
		(width 0.174752)
		(layer "F.Cu")
		(net "PE_CLK100M_DR2_2_P")
	)
	(segment
		(start 228.473 -266.590018)
		(end 227.389944 -266.590018)
		(width 0.174752)
		(layer "F.Cu")
		(net "PE_CLK100M_DR2_2_P")
	)
	(segment
		(start 95.071946 -294.639492)
		(end 95.071946 -283.642308)
		(width 0.174752)
		(layer "F.Cu")
		(net "PE_CLK100M_DR2_2_P")
	)
	(segment
		(start 95.071946 -283.642308)
		(end 124.307854 -254.4064)
		(width 0.174752)
		(layer "F.Cu")
		(net "PE_CLK100M_DR2_2_P")
	)
	(segment
		(start 229.907084 -265.790172)
		(end 230.16083 -266.043918)
		(width 0.174752)
		(layer "F.Cu")
		(net "PE_CLK100M_DR2_2_P")
	)
	(segment
		(start 234.9373 -267.13815)
		(end 233.640884 -267.13815)
		(width 0.174752)
		(layer "F.Cu")
		(net "PE_CLK100M_DR2_2_P")
	)
	(segment
		(start 235.712 -258.8768)
		(end 235.712 -266.36345)
		(width 0.174752)
		(layer "F.Cu")
		(net "PE_CLK100M_DR2_2_P")
	)
	(segment
		(start 221.869508 -252.932946)
		(end 229.768146 -252.932946)
		(width 0.174752)
		(layer "F.Cu")
		(net "PE_CLK100M_DR2_2_P")
	)
	(segment
		(start 228.684328 -266.801346)
		(end 228.473 -266.590018)
		(width 0.174752)
		(layer "F.Cu")
		(net "PE_CLK100M_DR2_2_P")
	)
	(segment
		(start 233.640884 -267.13815)
		(end 233.386884 -267.39215)
		(width 0.174752)
		(layer "F.Cu")
		(net "PE_CLK100M_DR2_2_P")
	)
	(segment
		(start 95.859346 -295.745154)
		(end 95.859346 -295.426892)
		(width 0.174752)
		(layer "F.Cu")
		(net "PE_CLK100M_DR2_2_P")
	)
	(segment
		(start 229.939088 -266.801346)
		(end 228.684328 -266.801346)
		(width 0.174752)
		(layer "F.Cu")
		(net "PE_CLK100M_DR2_2_P")
	)
	(via
		(at 229.907084 -265.790172)
		(size 0.508)
		(drill 0.254)
		(layers "F.Cu" "B.Cu")
		(net "PE_CLK100M_DR2_2_P")
	)
	(via
		(at 233.386884 -267.39215)
		(size 0.508)
		(drill 0.254)
		(layers "F.Cu" "B.Cu")
		(net "PE_CLK100M_DR2_2_P")
	)
	(segment
		(start 230.16083 -266.043918)
		(end 229.907084 -265.790172)
		(width 0.174752)
		(layer "B.Cu")
		(net "PE_CLK100M_DR2_2_P")
	)
	(segment
		(start 233.386884 -267.39215)
		(end 233.132884 -267.13815)
		(width 0.174752)
		(layer "B.Cu")
		(net "PE_CLK100M_DR2_2_P")
	)
	(segment
		(start 233.132884 -267.13815)
		(end 230.593392 -267.13815)
		(width 0.174752)
		(layer "B.Cu")
		(net "PE_CLK100M_DR2_2_P")
	)
	(segment
		(start 230.16083 -266.705588)
		(end 230.16083 -266.043918)
		(width 0.174752)
		(layer "B.Cu")
		(net "PE_CLK100M_DR2_2_P")
	)
	(segment
		(start 230.593392 -267.13815)
		(end 230.16083 -266.705588)
		(width 0.174752)
		(layer "B.Cu")
		(net "PE_CLK100M_DR2_2_P")
	)
	(segment
		(start 212.114384 -254.839216)
		(end 212.63864 -254.839216)
		(width 0.174752)
		(layer "F.Cu")
		(net "PE_CLK100M_DR2_2_N")
	)
	(segment
		(start 208.43494 -254.839216)
		(end 208.562702 -254.711454)
		(width 0.174752)
		(layer "F.Cu")
		(net "PE_CLK100M_DR2_2_N")
	)
	(segment
		(start 214.070438 -254.711454)
		(end 216.610438 -254.711454)
		(width 0.174752)
		(layer "F.Cu")
		(net "PE_CLK100M_DR2_2_N")
	)
	(segment
		(start 217.914474 -254.711454)
		(end 218.042236 -254.839216)
		(width 0.174752)
		(layer "F.Cu")
		(net "PE_CLK100M_DR2_2_N")
	)
	(segment
		(start 235.279184 -261.09549)
		(end 235.279184 -261.619746)
		(width 0.174752)
		(layer "F.Cu")
		(net "PE_CLK100M_DR2_2_N")
	)
	(segment
		(start 235.406946 -261.747508)
		(end 235.406946 -262.271764)
		(width 0.174752)
		(layer "F.Cu")
		(net "PE_CLK100M_DR2_2_N")
	)
	(segment
		(start 212.63864 -254.839216)
		(end 212.766402 -254.711454)
		(width 0.174752)
		(layer "F.Cu")
		(net "PE_CLK100M_DR2_2_N")
	)
	(segment
		(start 235.279184 -263.703562)
		(end 235.279184 -264.227818)
		(width 0.174752)
		(layer "F.Cu")
		(net "PE_CLK100M_DR2_2_N")
	)
	(segment
		(start 95.377 -283.7688)
		(end 124.434346 -254.711454)
		(width 0.174752)
		(layer "F.Cu")
		(net "PE_CLK100M_DR2_2_N")
	)
	(segment
		(start 216.610438 -254.711454)
		(end 216.7382 -254.839216)
		(width 0.174752)
		(layer "F.Cu")
		(net "PE_CLK100M_DR2_2_N")
	)
	(segment
		(start 235.279184 -261.619746)
		(end 235.406946 -261.747508)
		(width 0.174752)
		(layer "F.Cu")
		(net "PE_CLK100M_DR2_2_N")
	)
	(segment
		(start 213.942676 -254.839216)
		(end 214.070438 -254.711454)
		(width 0.174752)
		(layer "F.Cu")
		(net "PE_CLK100M_DR2_2_N")
	)
	(segment
		(start 230.465884 -266.706096)
		(end 230.06558 -267.1064)
		(width 0.174752)
		(layer "F.Cu")
		(net "PE_CLK100M_DR2_2_N")
	)
	(segment
		(start 219.99829 -254.711454)
		(end 220.522546 -254.711454)
		(width 0.174752)
		(layer "F.Cu")
		(net "PE_CLK100M_DR2_2_N")
	)
	(segment
		(start 232.373932 -256.150872)
		(end 232.554526 -256.150872)
		(width 0.174752)
		(layer "F.Cu")
		(net "PE_CLK100M_DR2_2_N")
	)
	(segment
		(start 228.479604 -267.390118)
		(end 227.389944 -267.390118)
		(width 0.174752)
		(layer "F.Cu")
		(net "PE_CLK100M_DR2_2_N")
	)
	(segment
		(start 209.866738 -254.711454)
		(end 211.986622 -254.711454)
		(width 0.174752)
		(layer "F.Cu")
		(net "PE_CLK100M_DR2_2_N")
	)
	(segment
		(start 228.763322 -267.1064)
		(end 228.479604 -267.390118)
		(width 0.174752)
		(layer "F.Cu")
		(net "PE_CLK100M_DR2_2_N")
	)
	(segment
		(start 218.566492 -254.839216)
		(end 218.694254 -254.711454)
		(width 0.174752)
		(layer "F.Cu")
		(net "PE_CLK100M_DR2_2_N")
	)
	(segment
		(start 209.738976 -254.839216)
		(end 209.866738 -254.711454)
		(width 0.174752)
		(layer "F.Cu")
		(net "PE_CLK100M_DR2_2_N")
	)
	(segment
		(start 235.406946 -266.236958)
		(end 234.810808 -266.833096)
		(width 0.174752)
		(layer "F.Cu")
		(net "PE_CLK100M_DR2_2_N")
	)
	(segment
		(start 231.081072 -254.858012)
		(end 231.451658 -255.228852)
		(width 0.174752)
		(layer "F.Cu")
		(net "PE_CLK100M_DR2_2_N")
	)
	(segment
		(start 232.925112 -256.702306)
		(end 233.295952 -257.072892)
		(width 0.174752)
		(layer "F.Cu")
		(net "PE_CLK100M_DR2_2_N")
	)
	(segment
		(start 219.870528 -254.839216)
		(end 219.99829 -254.711454)
		(width 0.174752)
		(layer "F.Cu")
		(net "PE_CLK100M_DR2_2_N")
	)
	(segment
		(start 216.7382 -254.839216)
		(end 217.262456 -254.839216)
		(width 0.174752)
		(layer "F.Cu")
		(net "PE_CLK100M_DR2_2_N")
	)
	(segment
		(start 206.478886 -254.711454)
		(end 206.606648 -254.839216)
		(width 0.174752)
		(layer "F.Cu")
		(net "PE_CLK100M_DR2_2_N")
	)
	(segment
		(start 218.042236 -254.839216)
		(end 218.566492 -254.839216)
		(width 0.174752)
		(layer "F.Cu")
		(net "PE_CLK100M_DR2_2_N")
	)
	(segment
		(start 207.258666 -254.711454)
		(end 207.782922 -254.711454)
		(width 0.174752)
		(layer "F.Cu")
		(net "PE_CLK100M_DR2_2_N")
	)
	(segment
		(start 232.003092 -255.780032)
		(end 232.373932 -256.150872)
		(width 0.174752)
		(layer "F.Cu")
		(net "PE_CLK100M_DR2_2_N")
	)
	(segment
		(start 207.130904 -254.839216)
		(end 207.258666 -254.711454)
		(width 0.174752)
		(layer "F.Cu")
		(net "PE_CLK100M_DR2_2_N")
	)
	(segment
		(start 219.21851 -254.711454)
		(end 219.346272 -254.839216)
		(width 0.174752)
		(layer "F.Cu")
		(net "PE_CLK100M_DR2_2_N")
	)
	(segment
		(start 207.782922 -254.711454)
		(end 207.910684 -254.839216)
		(width 0.174752)
		(layer "F.Cu")
		(net "PE_CLK100M_DR2_2_N")
	)
	(segment
		(start 96.1644 -295.3004)
		(end 95.377 -294.513)
		(width 0.174752)
		(layer "F.Cu")
		(net "PE_CLK100M_DR2_2_N")
	)
	(segment
		(start 235.406946 -263.5758)
		(end 235.279184 -263.703562)
		(width 0.174752)
		(layer "F.Cu")
		(net "PE_CLK100M_DR2_2_N")
	)
	(segment
		(start 96.52 -296.1005)
		(end 96.1644 -295.7449)
		(width 0.174752)
		(layer "F.Cu")
		(net "PE_CLK100M_DR2_2_N")
	)
	(segment
		(start 231.632506 -255.228852)
		(end 232.003092 -255.599438)
		(width 0.174752)
		(layer "F.Cu")
		(net "PE_CLK100M_DR2_2_N")
	)
	(segment
		(start 209.21472 -254.839216)
		(end 209.738976 -254.839216)
		(width 0.174752)
		(layer "F.Cu")
		(net "PE_CLK100M_DR2_2_N")
	)
	(segment
		(start 235.279184 -264.227818)
		(end 235.406946 -264.35558)
		(width 0.174752)
		(layer "F.Cu")
		(net "PE_CLK100M_DR2_2_N")
	)
	(segment
		(start 235.406946 -262.271764)
		(end 235.279184 -262.399526)
		(width 0.174752)
		(layer "F.Cu")
		(net "PE_CLK100M_DR2_2_N")
	)
	(segment
		(start 96.1644 -295.7449)
		(end 96.1644 -295.3004)
		(width 0.174752)
		(layer "F.Cu")
		(net "PE_CLK100M_DR2_2_N")
	)
	(segment
		(start 233.476546 -257.072892)
		(end 235.406946 -259.003292)
		(width 0.174752)
		(layer "F.Cu")
		(net "PE_CLK100M_DR2_2_N")
	)
	(segment
		(start 218.694254 -254.711454)
		(end 219.21851 -254.711454)
		(width 0.174752)
		(layer "F.Cu")
		(net "PE_CLK100M_DR2_2_N")
	)
	(segment
		(start 235.406946 -264.35558)
		(end 235.406946 -266.236958)
		(width 0.174752)
		(layer "F.Cu")
		(net "PE_CLK100M_DR2_2_N")
	)
	(segment
		(start 231.451658 -255.228852)
		(end 231.632506 -255.228852)
		(width 0.174752)
		(layer "F.Cu")
		(net "PE_CLK100M_DR2_2_N")
	)
	(segment
		(start 207.910684 -254.839216)
		(end 208.43494 -254.839216)
		(width 0.174752)
		(layer "F.Cu")
		(net "PE_CLK100M_DR2_2_N")
	)
	(segment
		(start 213.41842 -254.839216)
		(end 213.942676 -254.839216)
		(width 0.174752)
		(layer "F.Cu")
		(net "PE_CLK100M_DR2_2_N")
	)
	(segment
		(start 209.086958 -254.711454)
		(end 209.21472 -254.839216)
		(width 0.174752)
		(layer "F.Cu")
		(net "PE_CLK100M_DR2_2_N")
	)
	(segment
		(start 232.925112 -256.521458)
		(end 232.925112 -256.702306)
		(width 0.174752)
		(layer "F.Cu")
		(net "PE_CLK100M_DR2_2_N")
	)
	(segment
		(start 232.003092 -255.599438)
		(end 232.003092 -255.780032)
		(width 0.174752)
		(layer "F.Cu")
		(net "PE_CLK100M_DR2_2_N")
	)
	(segment
		(start 235.279184 -262.399526)
		(end 235.279184 -262.923782)
		(width 0.174752)
		(layer "F.Cu")
		(net "PE_CLK100M_DR2_2_N")
	)
	(segment
		(start 206.606648 -254.839216)
		(end 207.130904 -254.839216)
		(width 0.174752)
		(layer "F.Cu")
		(net "PE_CLK100M_DR2_2_N")
	)
	(segment
		(start 230.06558 -267.1064)
		(end 228.763322 -267.1064)
		(width 0.174752)
		(layer "F.Cu")
		(net "PE_CLK100M_DR2_2_N")
	)
	(segment
		(start 217.390218 -254.711454)
		(end 217.914474 -254.711454)
		(width 0.174752)
		(layer "F.Cu")
		(net "PE_CLK100M_DR2_2_N")
	)
	(segment
		(start 235.279184 -262.923782)
		(end 235.406946 -263.051544)
		(width 0.174752)
		(layer "F.Cu")
		(net "PE_CLK100M_DR2_2_N")
	)
	(segment
		(start 233.295952 -257.072892)
		(end 233.476546 -257.072892)
		(width 0.174752)
		(layer "F.Cu")
		(net "PE_CLK100M_DR2_2_N")
	)
	(segment
		(start 124.434346 -254.711454)
		(end 206.478886 -254.711454)
		(width 0.174752)
		(layer "F.Cu")
		(net "PE_CLK100M_DR2_2_N")
	)
	(segment
		(start 232.554526 -256.150872)
		(end 232.925112 -256.521458)
		(width 0.174752)
		(layer "F.Cu")
		(net "PE_CLK100M_DR2_2_N")
	)
	(segment
		(start 230.719884 -265.790172)
		(end 230.465884 -266.044172)
		(width 0.174752)
		(layer "F.Cu")
		(net "PE_CLK100M_DR2_2_N")
	)
	(segment
		(start 235.406946 -260.967728)
		(end 235.279184 -261.09549)
		(width 0.174752)
		(layer "F.Cu")
		(net "PE_CLK100M_DR2_2_N")
	)
	(segment
		(start 213.290658 -254.711454)
		(end 213.41842 -254.839216)
		(width 0.174752)
		(layer "F.Cu")
		(net "PE_CLK100M_DR2_2_N")
	)
	(segment
		(start 211.986622 -254.711454)
		(end 212.114384 -254.839216)
		(width 0.174752)
		(layer "F.Cu")
		(net "PE_CLK100M_DR2_2_N")
	)
	(segment
		(start 220.522546 -254.711454)
		(end 221.996 -253.238)
		(width 0.174752)
		(layer "F.Cu")
		(net "PE_CLK100M_DR2_2_N")
	)
	(segment
		(start 233.64063 -266.833096)
		(end 233.386884 -266.57935)
		(width 0.174752)
		(layer "F.Cu")
		(net "PE_CLK100M_DR2_2_N")
	)
	(segment
		(start 212.766402 -254.711454)
		(end 213.290658 -254.711454)
		(width 0.174752)
		(layer "F.Cu")
		(net "PE_CLK100M_DR2_2_N")
	)
	(segment
		(start 235.406946 -259.003292)
		(end 235.406946 -260.967728)
		(width 0.174752)
		(layer "F.Cu")
		(net "PE_CLK100M_DR2_2_N")
	)
	(segment
		(start 234.810808 -266.833096)
		(end 233.64063 -266.833096)
		(width 0.174752)
		(layer "F.Cu")
		(net "PE_CLK100M_DR2_2_N")
	)
	(segment
		(start 219.346272 -254.839216)
		(end 219.870528 -254.839216)
		(width 0.174752)
		(layer "F.Cu")
		(net "PE_CLK100M_DR2_2_N")
	)
	(segment
		(start 217.262456 -254.839216)
		(end 217.390218 -254.711454)
		(width 0.174752)
		(layer "F.Cu")
		(net "PE_CLK100M_DR2_2_N")
	)
	(segment
		(start 235.406946 -263.051544)
		(end 235.406946 -263.5758)
		(width 0.174752)
		(layer "F.Cu")
		(net "PE_CLK100M_DR2_2_N")
	)
	(segment
		(start 208.562702 -254.711454)
		(end 209.086958 -254.711454)
		(width 0.174752)
		(layer "F.Cu")
		(net "PE_CLK100M_DR2_2_N")
	)
	(segment
		(start 231.081072 -254.677418)
		(end 231.081072 -254.858012)
		(width 0.174752)
		(layer "F.Cu")
		(net "PE_CLK100M_DR2_2_N")
	)
	(segment
		(start 95.377 -294.513)
		(end 95.377 -283.7688)
		(width 0.174752)
		(layer "F.Cu")
		(net "PE_CLK100M_DR2_2_N")
	)
	(segment
		(start 229.641654 -253.238)
		(end 231.081072 -254.677418)
		(width 0.174752)
		(layer "F.Cu")
		(net "PE_CLK100M_DR2_2_N")
	)
	(segment
		(start 221.996 -253.238)
		(end 229.641654 -253.238)
		(width 0.174752)
		(layer "F.Cu")
		(net "PE_CLK100M_DR2_2_N")
	)
	(segment
		(start 230.465884 -266.044172)
		(end 230.465884 -266.706096)
		(width 0.174752)
		(layer "F.Cu")
		(net "PE_CLK100M_DR2_2_N")
	)
	(via
		(at 230.719884 -265.790172)
		(size 0.508)
		(drill 0.254)
		(layers "F.Cu" "B.Cu")
		(net "PE_CLK100M_DR2_2_N")
	)
	(via
		(at 233.386884 -266.57935)
		(size 0.508)
		(drill 0.254)
		(layers "F.Cu" "B.Cu")
		(net "PE_CLK100M_DR2_2_N")
	)
	(segment
		(start 233.133138 -266.833096)
		(end 230.719884 -266.833096)
		(width 0.174752)
		(layer "B.Cu")
		(net "PE_CLK100M_DR2_2_N")
	)
	(segment
		(start 230.465884 -266.579096)
		(end 230.465884 -266.044172)
		(width 0.174752)
		(layer "B.Cu")
		(net "PE_CLK100M_DR2_2_N")
	)
	(segment
		(start 233.386884 -266.57935)
		(end 233.133138 -266.833096)
		(width 0.174752)
		(layer "B.Cu")
		(net "PE_CLK100M_DR2_2_N")
	)
	(segment
		(start 230.465884 -266.044172)
		(end 230.719884 -265.790172)
		(width 0.174752)
		(layer "B.Cu")
		(net "PE_CLK100M_DR2_2_N")
	)
	(segment
		(start 230.719884 -266.833096)
		(end 230.465884 -266.579096)
		(width 0.174752)
		(layer "B.Cu")
		(net "PE_CLK100M_DR2_2_N")
	)
	(segment
		(start 100.838 -282.397454)
		(end 124.798074 -258.43738)
		(width 0.174752)
		(layer "F.Cu")
		(net "PE_CLK100M_DR2_1_P")
	)
	(segment
		(start 100.838 -294.005)
		(end 100.838 -282.397454)
		(width 0.174752)
		(layer "F.Cu")
		(net "PE_CLK100M_DR2_1_P")
	)
	(segment
		(start 99.669346 -295.173654)
		(end 100.838 -294.005)
		(width 0.174752)
		(layer "F.Cu")
		(net "PE_CLK100M_DR2_1_P")
	)
	(segment
		(start 124.798074 -258.43738)
		(end 222.885 -258.43738)
		(width 0.174752)
		(layer "F.Cu")
		(net "PE_CLK100M_DR2_1_P")
	)
	(segment
		(start 222.885 -258.43738)
		(end 223.132396 -258.189984)
		(width 0.174752)
		(layer "F.Cu")
		(net "PE_CLK100M_DR2_1_P")
	)
	(segment
		(start 99.314 -296.1005)
		(end 99.669346 -295.745154)
		(width 0.174752)
		(layer "F.Cu")
		(net "PE_CLK100M_DR2_1_P")
	)
	(segment
		(start 99.669346 -295.745154)
		(end 99.669346 -295.173654)
		(width 0.174752)
		(layer "F.Cu")
		(net "PE_CLK100M_DR2_1_P")
	)
	(segment
		(start 223.132396 -258.189984)
		(end 224.199958 -258.189984)
		(width 0.174752)
		(layer "F.Cu")
		(net "PE_CLK100M_DR2_1_P")
	)
	(segment
		(start 99.9744 -295.300146)
		(end 101.143054 -294.131492)
		(width 0.174752)
		(layer "F.Cu")
		(net "PE_CLK100M_DR2_1_N")
	)
	(segment
		(start 100.33 -296.1005)
		(end 99.9744 -295.7449)
		(width 0.174752)
		(layer "F.Cu")
		(net "PE_CLK100M_DR2_1_N")
	)
	(segment
		(start 214.077804 -258.870196)
		(end 214.205566 -258.742434)
		(width 0.174752)
		(layer "F.Cu")
		(net "PE_CLK100M_DR2_1_N")
	)
	(segment
		(start 101.143054 -294.131492)
		(end 101.143054 -282.523946)
		(width 0.174752)
		(layer "F.Cu")
		(net "PE_CLK100M_DR2_1_N")
	)
	(segment
		(start 214.205566 -258.742434)
		(end 214.729822 -258.742434)
		(width 0.174752)
		(layer "F.Cu")
		(net "PE_CLK100M_DR2_1_N")
	)
	(segment
		(start 223.13265 -258.990084)
		(end 224.199958 -258.990084)
		(width 0.174752)
		(layer "F.Cu")
		(net "PE_CLK100M_DR2_1_N")
	)
	(segment
		(start 215.509602 -258.742434)
		(end 218.049602 -258.742434)
		(width 0.174752)
		(layer "F.Cu")
		(net "PE_CLK100M_DR2_1_N")
	)
	(segment
		(start 221.309692 -258.870196)
		(end 221.437454 -258.742434)
		(width 0.174752)
		(layer "F.Cu")
		(net "PE_CLK100M_DR2_1_N")
	)
	(segment
		(start 214.729822 -258.742434)
		(end 214.857584 -258.870196)
		(width 0.174752)
		(layer "F.Cu")
		(net "PE_CLK100M_DR2_1_N")
	)
	(segment
		(start 124.924566 -258.742434)
		(end 213.425786 -258.742434)
		(width 0.174752)
		(layer "F.Cu")
		(net "PE_CLK100M_DR2_1_N")
	)
	(segment
		(start 99.9744 -295.7449)
		(end 99.9744 -295.300146)
		(width 0.174752)
		(layer "F.Cu")
		(net "PE_CLK100M_DR2_1_N")
	)
	(segment
		(start 220.133418 -258.742434)
		(end 220.657674 -258.742434)
		(width 0.174752)
		(layer "F.Cu")
		(net "PE_CLK100M_DR2_1_N")
	)
	(segment
		(start 218.177364 -258.870196)
		(end 218.70162 -258.870196)
		(width 0.174752)
		(layer "F.Cu")
		(net "PE_CLK100M_DR2_1_N")
	)
	(segment
		(start 101.143054 -282.523946)
		(end 124.924566 -258.742434)
		(width 0.174752)
		(layer "F.Cu")
		(net "PE_CLK100M_DR2_1_N")
	)
	(segment
		(start 218.049602 -258.742434)
		(end 218.177364 -258.870196)
		(width 0.174752)
		(layer "F.Cu")
		(net "PE_CLK100M_DR2_1_N")
	)
	(segment
		(start 220.005656 -258.870196)
		(end 220.133418 -258.742434)
		(width 0.174752)
		(layer "F.Cu")
		(net "PE_CLK100M_DR2_1_N")
	)
	(segment
		(start 214.857584 -258.870196)
		(end 215.38184 -258.870196)
		(width 0.174752)
		(layer "F.Cu")
		(net "PE_CLK100M_DR2_1_N")
	)
	(segment
		(start 219.4814 -258.870196)
		(end 220.005656 -258.870196)
		(width 0.174752)
		(layer "F.Cu")
		(net "PE_CLK100M_DR2_1_N")
	)
	(segment
		(start 221.437454 -258.742434)
		(end 222.885 -258.742434)
		(width 0.174752)
		(layer "F.Cu")
		(net "PE_CLK100M_DR2_1_N")
	)
	(segment
		(start 213.425786 -258.742434)
		(end 213.553548 -258.870196)
		(width 0.174752)
		(layer "F.Cu")
		(net "PE_CLK100M_DR2_1_N")
	)
	(segment
		(start 213.553548 -258.870196)
		(end 214.077804 -258.870196)
		(width 0.174752)
		(layer "F.Cu")
		(net "PE_CLK100M_DR2_1_N")
	)
	(segment
		(start 220.785436 -258.870196)
		(end 221.309692 -258.870196)
		(width 0.174752)
		(layer "F.Cu")
		(net "PE_CLK100M_DR2_1_N")
	)
	(segment
		(start 220.657674 -258.742434)
		(end 220.785436 -258.870196)
		(width 0.174752)
		(layer "F.Cu")
		(net "PE_CLK100M_DR2_1_N")
	)
	(segment
		(start 219.353638 -258.742434)
		(end 219.4814 -258.870196)
		(width 0.174752)
		(layer "F.Cu")
		(net "PE_CLK100M_DR2_1_N")
	)
	(segment
		(start 222.885 -258.742434)
		(end 223.13265 -258.990084)
		(width 0.174752)
		(layer "F.Cu")
		(net "PE_CLK100M_DR2_1_N")
	)
	(segment
		(start 215.38184 -258.870196)
		(end 215.509602 -258.742434)
		(width 0.174752)
		(layer "F.Cu")
		(net "PE_CLK100M_DR2_1_N")
	)
	(segment
		(start 218.70162 -258.870196)
		(end 218.829382 -258.742434)
		(width 0.174752)
		(layer "F.Cu")
		(net "PE_CLK100M_DR2_1_N")
	)
	(segment
		(start 218.829382 -258.742434)
		(end 219.353638 -258.742434)
		(width 0.174752)
		(layer "F.Cu")
		(net "PE_CLK100M_DR2_1_N")
	)
	(segment
		(start 19.61007 -33.40989)
		(end 18.535904 -33.40989)
		(width 0.174752)
		(layer "F.Cu")
		(net "PE_CLK100M_DR14_2_P")
	)
	(segment
		(start 60.721494 -33.162494)
		(end 41.163748 -33.162494)
		(width 0.174752)
		(layer "F.Cu")
		(net "PE_CLK100M_DR14_2_P")
	)
	(segment
		(start 31.749492 -33.162494)
		(end 31.496 -33.415986)
		(width 0.174752)
		(layer "F.Cu")
		(net "PE_CLK100M_DR14_2_P")
	)
	(segment
		(start 95.504 -92.5195)
		(end 95.833946 -92.189554)
		(width 0.174752)
		(layer "F.Cu")
		(net "PE_CLK100M_DR14_2_P")
	)
	(segment
		(start 18.535904 -33.40989)
		(end 18.288 -33.161986)
		(width 0.174752)
		(layer "F.Cu")
		(net "PE_CLK100M_DR14_2_P")
	)
	(segment
		(start 41.035986 -33.290256)
		(end 40.51173 -33.290256)
		(width 0.174752)
		(layer "F.Cu")
		(net "PE_CLK100M_DR14_2_P")
	)
	(segment
		(start 33.15208 -33.162494)
		(end 31.749492 -33.162494)
		(width 0.174752)
		(layer "F.Cu")
		(net "PE_CLK100M_DR14_2_P")
	)
	(segment
		(start 95.833946 -91.820492)
		(end 95.071946 -91.058492)
		(width 0.174752)
		(layer "F.Cu")
		(net "PE_CLK100M_DR14_2_P")
	)
	(segment
		(start 35.235896 -33.162494)
		(end 35.108134 -33.290256)
		(width 0.174752)
		(layer "F.Cu")
		(net "PE_CLK100M_DR14_2_P")
	)
	(segment
		(start 35.760152 -33.162494)
		(end 35.235896 -33.162494)
		(width 0.174752)
		(layer "F.Cu")
		(net "PE_CLK100M_DR14_2_P")
	)
	(segment
		(start 36.41217 -33.290256)
		(end 35.887914 -33.290256)
		(width 0.174752)
		(layer "F.Cu")
		(net "PE_CLK100M_DR14_2_P")
	)
	(segment
		(start 39.079932 -33.162494)
		(end 36.539932 -33.162494)
		(width 0.174752)
		(layer "F.Cu")
		(net "PE_CLK100M_DR14_2_P")
	)
	(segment
		(start 41.163748 -33.162494)
		(end 41.035986 -33.290256)
		(width 0.174752)
		(layer "F.Cu")
		(net "PE_CLK100M_DR14_2_P")
	)
	(segment
		(start 95.071946 -67.512946)
		(end 60.721494 -33.162494)
		(width 0.174752)
		(layer "F.Cu")
		(net "PE_CLK100M_DR14_2_P")
	)
	(segment
		(start 33.279842 -33.290256)
		(end 33.15208 -33.162494)
		(width 0.174752)
		(layer "F.Cu")
		(net "PE_CLK100M_DR14_2_P")
	)
	(segment
		(start 33.93186 -33.162494)
		(end 33.804098 -33.290256)
		(width 0.174752)
		(layer "F.Cu")
		(net "PE_CLK100M_DR14_2_P")
	)
	(segment
		(start 18.288 -33.161986)
		(end 17.526 -33.161986)
		(width 0.174752)
		(layer "F.Cu")
		(net "PE_CLK100M_DR14_2_P")
	)
	(segment
		(start 95.833946 -92.189554)
		(end 95.833946 -91.820492)
		(width 0.174752)
		(layer "F.Cu")
		(net "PE_CLK100M_DR14_2_P")
	)
	(segment
		(start 40.383968 -33.162494)
		(end 39.859712 -33.162494)
		(width 0.174752)
		(layer "F.Cu")
		(net "PE_CLK100M_DR14_2_P")
	)
	(segment
		(start 39.73195 -33.290256)
		(end 39.207694 -33.290256)
		(width 0.174752)
		(layer "F.Cu")
		(net "PE_CLK100M_DR14_2_P")
	)
	(segment
		(start 35.108134 -33.290256)
		(end 34.583878 -33.290256)
		(width 0.174752)
		(layer "F.Cu")
		(net "PE_CLK100M_DR14_2_P")
	)
	(segment
		(start 34.456116 -33.162494)
		(end 33.93186 -33.162494)
		(width 0.174752)
		(layer "F.Cu")
		(net "PE_CLK100M_DR14_2_P")
	)
	(segment
		(start 35.887914 -33.290256)
		(end 35.760152 -33.162494)
		(width 0.174752)
		(layer "F.Cu")
		(net "PE_CLK100M_DR14_2_P")
	)
	(segment
		(start 40.51173 -33.290256)
		(end 40.383968 -33.162494)
		(width 0.174752)
		(layer "F.Cu")
		(net "PE_CLK100M_DR14_2_P")
	)
	(segment
		(start 95.071946 -91.058492)
		(end 95.071946 -67.512946)
		(width 0.174752)
		(layer "F.Cu")
		(net "PE_CLK100M_DR14_2_P")
	)
	(segment
		(start 39.859712 -33.162494)
		(end 39.73195 -33.290256)
		(width 0.174752)
		(layer "F.Cu")
		(net "PE_CLK100M_DR14_2_P")
	)
	(segment
		(start 33.804098 -33.290256)
		(end 33.279842 -33.290256)
		(width 0.174752)
		(layer "F.Cu")
		(net "PE_CLK100M_DR14_2_P")
	)
	(segment
		(start 36.539932 -33.162494)
		(end 36.41217 -33.290256)
		(width 0.174752)
		(layer "F.Cu")
		(net "PE_CLK100M_DR14_2_P")
	)
	(segment
		(start 34.583878 -33.290256)
		(end 34.456116 -33.162494)
		(width 0.174752)
		(layer "F.Cu")
		(net "PE_CLK100M_DR14_2_P")
	)
	(segment
		(start 39.207694 -33.290256)
		(end 39.079932 -33.162494)
		(width 0.174752)
		(layer "F.Cu")
		(net "PE_CLK100M_DR14_2_P")
	)
	(segment
		(start 17.526 -33.161986)
		(end 17.272 -33.415986)
		(width 0.174752)
		(layer "F.Cu")
		(net "PE_CLK100M_DR14_2_P")
	)
	(via
		(at 31.496 -33.415986)
		(size 0.508)
		(drill 0.254)
		(layers "F.Cu" "B.Cu")
		(net "PE_CLK100M_DR14_2_P")
	)
	(via
		(at 17.272 -33.415986)
		(size 0.508)
		(drill 0.254)
		(layers "F.Cu" "B.Cu")
		(net "PE_CLK100M_DR14_2_P")
	)
	(segment
		(start 31.242 -33.161986)
		(end 31.496 -33.415986)
		(width 0.174752)
		(layer "B.Cu")
		(net "PE_CLK100M_DR14_2_P")
	)
	(segment
		(start 17.526 -33.161986)
		(end 31.242 -33.161986)
		(width 0.174752)
		(layer "B.Cu")
		(net "PE_CLK100M_DR14_2_P")
	)
	(segment
		(start 17.272 -33.415986)
		(end 17.526 -33.161986)
		(width 0.174752)
		(layer "B.Cu")
		(net "PE_CLK100M_DR14_2_P")
	)
	(segment
		(start 95.377 -67.386454)
		(end 60.847986 -32.85744)
		(width 0.174752)
		(layer "F.Cu")
		(net "PE_CLK100M_DR14_2_N")
	)
	(segment
		(start 19.61007 -32.60979)
		(end 18.535142 -32.60979)
		(width 0.174752)
		(layer "F.Cu")
		(net "PE_CLK100M_DR14_2_N")
	)
	(segment
		(start 96.52 -92.5195)
		(end 96.139 -92.1385)
		(width 0.174752)
		(layer "F.Cu")
		(net "PE_CLK100M_DR14_2_N")
	)
	(segment
		(start 96.139 -92.1385)
		(end 96.139 -91.694)
		(width 0.174752)
		(layer "F.Cu")
		(net "PE_CLK100M_DR14_2_N")
	)
	(segment
		(start 60.847986 -32.85744)
		(end 31.750254 -32.85744)
		(width 0.174752)
		(layer "F.Cu")
		(net "PE_CLK100M_DR14_2_N")
	)
	(segment
		(start 31.750254 -32.85744)
		(end 31.496 -32.603186)
		(width 0.174752)
		(layer "F.Cu")
		(net "PE_CLK100M_DR14_2_N")
	)
	(segment
		(start 95.377 -90.932)
		(end 95.377 -67.386454)
		(width 0.174752)
		(layer "F.Cu")
		(net "PE_CLK100M_DR14_2_N")
	)
	(segment
		(start 17.525746 -32.856932)
		(end 17.272 -32.603186)
		(width 0.174752)
		(layer "F.Cu")
		(net "PE_CLK100M_DR14_2_N")
	)
	(segment
		(start 18.535142 -32.60979)
		(end 18.288 -32.856932)
		(width 0.174752)
		(layer "F.Cu")
		(net "PE_CLK100M_DR14_2_N")
	)
	(segment
		(start 18.288 -32.856932)
		(end 17.525746 -32.856932)
		(width 0.174752)
		(layer "F.Cu")
		(net "PE_CLK100M_DR14_2_N")
	)
	(segment
		(start 96.139 -91.694)
		(end 95.377 -90.932)
		(width 0.174752)
		(layer "F.Cu")
		(net "PE_CLK100M_DR14_2_N")
	)
	(via
		(at 17.272 -32.603186)
		(size 0.508)
		(drill 0.254)
		(layers "F.Cu" "B.Cu")
		(net "PE_CLK100M_DR14_2_N")
	)
	(via
		(at 31.496 -32.603186)
		(size 0.508)
		(drill 0.254)
		(layers "F.Cu" "B.Cu")
		(net "PE_CLK100M_DR14_2_N")
	)
	(segment
		(start 17.272 -32.603186)
		(end 17.525746 -32.856932)
		(width 0.174752)
		(layer "B.Cu")
		(net "PE_CLK100M_DR14_2_N")
	)
	(segment
		(start 31.242254 -32.856932)
		(end 31.496 -32.603186)
		(width 0.174752)
		(layer "B.Cu")
		(net "PE_CLK100M_DR14_2_N")
	)
	(segment
		(start 17.525746 -32.856932)
		(end 31.242254 -32.856932)
		(width 0.174752)
		(layer "B.Cu")
		(net "PE_CLK100M_DR14_2_N")
	)
	(segment
		(start 31.353506 -28.168854)
		(end 30.174692 -28.168854)
		(width 0.174752)
		(layer "F.Cu")
		(net "PE_CLK100M_DR14_1_P")
	)
	(segment
		(start 47.438564 -28.168854)
		(end 46.914308 -28.168854)
		(width 0.174752)
		(layer "F.Cu")
		(net "PE_CLK100M_DR14_1_P")
	)
	(segment
		(start 46.134528 -28.168854)
		(end 34.741358 -28.168854)
		(width 0.174752)
		(layer "F.Cu")
		(net "PE_CLK100M_DR14_1_P")
	)
	(segment
		(start 34.08934 -28.296616)
		(end 33.961578 -28.168854)
		(width 0.174752)
		(layer "F.Cu")
		(net "PE_CLK100M_DR14_1_P")
	)
	(segment
		(start 32.133286 -28.168854)
		(end 32.005524 -28.296616)
		(width 0.174752)
		(layer "F.Cu")
		(net "PE_CLK100M_DR14_1_P")
	)
	(segment
		(start 32.785304 -28.296616)
		(end 32.657542 -28.168854)
		(width 0.174752)
		(layer "F.Cu")
		(net "PE_CLK100M_DR14_1_P")
	)
	(segment
		(start 99.643946 -91.618054)
		(end 101.346 -89.916)
		(width 0.174752)
		(layer "F.Cu")
		(net "PE_CLK100M_DR14_1_P")
	)
	(segment
		(start 48.090582 -28.296616)
		(end 47.566326 -28.296616)
		(width 0.174752)
		(layer "F.Cu")
		(net "PE_CLK100M_DR14_1_P")
	)
	(segment
		(start 30.174692 -28.168854)
		(end 28.015438 -30.328108)
		(width 0.174752)
		(layer "F.Cu")
		(net "PE_CLK100M_DR14_1_P")
	)
	(segment
		(start 47.566326 -28.296616)
		(end 47.438564 -28.168854)
		(width 0.174752)
		(layer "F.Cu")
		(net "PE_CLK100M_DR14_1_P")
	)
	(segment
		(start 28.015438 -30.328108)
		(end 28.015438 -36.092384)
		(width 0.174752)
		(layer "F.Cu")
		(net "PE_CLK100M_DR14_1_P")
	)
	(segment
		(start 28.575 -36.651946)
		(end 28.575 -40.690546)
		(width 0.174752)
		(layer "F.Cu")
		(net "PE_CLK100M_DR14_1_P")
	)
	(segment
		(start 33.437322 -28.168854)
		(end 33.30956 -28.296616)
		(width 0.174752)
		(layer "F.Cu")
		(net "PE_CLK100M_DR14_1_P")
	)
	(segment
		(start 33.30956 -28.296616)
		(end 32.785304 -28.296616)
		(width 0.174752)
		(layer "F.Cu")
		(net "PE_CLK100M_DR14_1_P")
	)
	(segment
		(start 32.657542 -28.168854)
		(end 32.133286 -28.168854)
		(width 0.174752)
		(layer "F.Cu")
		(net "PE_CLK100M_DR14_1_P")
	)
	(segment
		(start 101.346 -89.916)
		(end 101.346 -67.868546)
		(width 0.174752)
		(layer "F.Cu")
		(net "PE_CLK100M_DR14_1_P")
	)
	(segment
		(start 48.218344 -28.168854)
		(end 48.090582 -28.296616)
		(width 0.174752)
		(layer "F.Cu")
		(net "PE_CLK100M_DR14_1_P")
	)
	(segment
		(start 99.643946 -92.189554)
		(end 99.643946 -91.618054)
		(width 0.174752)
		(layer "F.Cu")
		(net "PE_CLK100M_DR14_1_P")
	)
	(segment
		(start 46.786546 -28.296616)
		(end 46.26229 -28.296616)
		(width 0.174752)
		(layer "F.Cu")
		(net "PE_CLK100M_DR14_1_P")
	)
	(segment
		(start 46.26229 -28.296616)
		(end 46.134528 -28.168854)
		(width 0.174752)
		(layer "F.Cu")
		(net "PE_CLK100M_DR14_1_P")
	)
	(segment
		(start 33.961578 -28.168854)
		(end 33.437322 -28.168854)
		(width 0.174752)
		(layer "F.Cu")
		(net "PE_CLK100M_DR14_1_P")
	)
	(segment
		(start 27.703018 -41.562528)
		(end 24.13 -41.562528)
		(width 0.174752)
		(layer "F.Cu")
		(net "PE_CLK100M_DR14_1_P")
	)
	(segment
		(start 32.005524 -28.296616)
		(end 31.481268 -28.296616)
		(width 0.174752)
		(layer "F.Cu")
		(net "PE_CLK100M_DR14_1_P")
	)
	(segment
		(start 34.613596 -28.296616)
		(end 34.08934 -28.296616)
		(width 0.174752)
		(layer "F.Cu")
		(net "PE_CLK100M_DR14_1_P")
	)
	(segment
		(start 61.646308 -28.168854)
		(end 48.218344 -28.168854)
		(width 0.174752)
		(layer "F.Cu")
		(net "PE_CLK100M_DR14_1_P")
	)
	(segment
		(start 99.314 -92.5195)
		(end 99.643946 -92.189554)
		(width 0.174752)
		(layer "F.Cu")
		(net "PE_CLK100M_DR14_1_P")
	)
	(segment
		(start 34.741358 -28.168854)
		(end 34.613596 -28.296616)
		(width 0.174752)
		(layer "F.Cu")
		(net "PE_CLK100M_DR14_1_P")
	)
	(segment
		(start 23.882604 -41.809924)
		(end 22.800056 -41.809924)
		(width 0.174752)
		(layer "F.Cu")
		(net "PE_CLK100M_DR14_1_P")
	)
	(segment
		(start 101.346 -67.868546)
		(end 61.646308 -28.168854)
		(width 0.174752)
		(layer "F.Cu")
		(net "PE_CLK100M_DR14_1_P")
	)
	(segment
		(start 28.015438 -36.092384)
		(end 28.575 -36.651946)
		(width 0.174752)
		(layer "F.Cu")
		(net "PE_CLK100M_DR14_1_P")
	)
	(segment
		(start 31.481268 -28.296616)
		(end 31.353506 -28.168854)
		(width 0.174752)
		(layer "F.Cu")
		(net "PE_CLK100M_DR14_1_P")
	)
	(segment
		(start 46.914308 -28.168854)
		(end 46.786546 -28.296616)
		(width 0.174752)
		(layer "F.Cu")
		(net "PE_CLK100M_DR14_1_P")
	)
	(segment
		(start 24.13 -41.562528)
		(end 23.882604 -41.809924)
		(width 0.174752)
		(layer "F.Cu")
		(net "PE_CLK100M_DR14_1_P")
	)
	(segment
		(start 28.575 -40.690546)
		(end 27.703018 -41.562528)
		(width 0.174752)
		(layer "F.Cu")
		(net "PE_CLK100M_DR14_1_P")
	)
	(segment
		(start 99.949 -91.744546)
		(end 101.651054 -90.042492)
		(width 0.174752)
		(layer "F.Cu")
		(net "PE_CLK100M_DR14_1_N")
	)
	(segment
		(start 27.710384 -36.218876)
		(end 28.269946 -36.778438)
		(width 0.174752)
		(layer "F.Cu")
		(net "PE_CLK100M_DR14_1_N")
	)
	(segment
		(start 30.0482 -27.8638)
		(end 27.710384 -30.201616)
		(width 0.174752)
		(layer "F.Cu")
		(net "PE_CLK100M_DR14_1_N")
	)
	(segment
		(start 27.710384 -30.201616)
		(end 27.710384 -36.218876)
		(width 0.174752)
		(layer "F.Cu")
		(net "PE_CLK100M_DR14_1_N")
	)
	(segment
		(start 28.269946 -36.778438)
		(end 28.269946 -40.564054)
		(width 0.174752)
		(layer "F.Cu")
		(net "PE_CLK100M_DR14_1_N")
	)
	(segment
		(start 23.88235 -41.009824)
		(end 22.800056 -41.009824)
		(width 0.174752)
		(layer "F.Cu")
		(net "PE_CLK100M_DR14_1_N")
	)
	(segment
		(start 24.13 -41.257474)
		(end 23.88235 -41.009824)
		(width 0.174752)
		(layer "F.Cu")
		(net "PE_CLK100M_DR14_1_N")
	)
	(segment
		(start 28.269946 -40.564054)
		(end 27.576526 -41.257474)
		(width 0.174752)
		(layer "F.Cu")
		(net "PE_CLK100M_DR14_1_N")
	)
	(segment
		(start 101.651054 -67.742054)
		(end 61.7728 -27.8638)
		(width 0.174752)
		(layer "F.Cu")
		(net "PE_CLK100M_DR14_1_N")
	)
	(segment
		(start 61.7728 -27.8638)
		(end 30.0482 -27.8638)
		(width 0.174752)
		(layer "F.Cu")
		(net "PE_CLK100M_DR14_1_N")
	)
	(segment
		(start 100.33 -92.5195)
		(end 99.949 -92.1385)
		(width 0.174752)
		(layer "F.Cu")
		(net "PE_CLK100M_DR14_1_N")
	)
	(segment
		(start 27.576526 -41.257474)
		(end 24.13 -41.257474)
		(width 0.174752)
		(layer "F.Cu")
		(net "PE_CLK100M_DR14_1_N")
	)
	(segment
		(start 99.949 -92.1385)
		(end 99.949 -91.744546)
		(width 0.174752)
		(layer "F.Cu")
		(net "PE_CLK100M_DR14_1_N")
	)
	(segment
		(start 101.651054 -90.042492)
		(end 101.651054 -67.742054)
		(width 0.174752)
		(layer "F.Cu")
		(net "PE_CLK100M_DR14_1_N")
	)
	(segment
		(start 19.61007 -136.409938)
		(end 18.535904 -136.409938)
		(width 0.174752)
		(layer "F.Cu")
		(net "PE_CLK100M_DR13_2_P")
	)
	(segment
		(start 91.313 -110.6805)
		(end 90.932254 -111.061246)
		(width 0.174752)
		(layer "F.Cu")
		(net "PE_CLK100M_DR13_2_P")
	)
	(segment
		(start 31.75 -136.162542)
		(end 31.496 -136.416542)
		(width 0.174752)
		(layer "F.Cu")
		(net "PE_CLK100M_DR13_2_P")
	)
	(segment
		(start 90.932254 -111.061246)
		(end 90.932254 -111.328708)
		(width 0.174752)
		(layer "F.Cu")
		(net "PE_CLK100M_DR13_2_P")
	)
	(segment
		(start 42.091864 -127.122682)
		(end 33.052004 -136.162542)
		(width 0.174752)
		(layer "F.Cu")
		(net "PE_CLK100M_DR13_2_P")
	)
	(segment
		(start 18.288 -136.162034)
		(end 17.526 -136.162034)
		(width 0.174752)
		(layer "F.Cu")
		(net "PE_CLK100M_DR13_2_P")
	)
	(segment
		(start 91.745054 -112.141508)
		(end 91.745054 -118.236492)
		(width 0.174752)
		(layer "F.Cu")
		(net "PE_CLK100M_DR13_2_P")
	)
	(segment
		(start 91.745054 -118.236492)
		(end 82.858864 -127.122682)
		(width 0.174752)
		(layer "F.Cu")
		(net "PE_CLK100M_DR13_2_P")
	)
	(segment
		(start 18.535904 -136.409938)
		(end 18.288 -136.162034)
		(width 0.174752)
		(layer "F.Cu")
		(net "PE_CLK100M_DR13_2_P")
	)
	(segment
		(start 33.052004 -136.162542)
		(end 31.75 -136.162542)
		(width 0.174752)
		(layer "F.Cu")
		(net "PE_CLK100M_DR13_2_P")
	)
	(segment
		(start 82.858864 -127.122682)
		(end 42.091864 -127.122682)
		(width 0.174752)
		(layer "F.Cu")
		(net "PE_CLK100M_DR13_2_P")
	)
	(segment
		(start 90.932254 -111.328708)
		(end 91.745054 -112.141508)
		(width 0.174752)
		(layer "F.Cu")
		(net "PE_CLK100M_DR13_2_P")
	)
	(segment
		(start 17.526 -136.162034)
		(end 17.272 -136.416034)
		(width 0.174752)
		(layer "F.Cu")
		(net "PE_CLK100M_DR13_2_P")
	)
	(via
		(at 17.272 -136.416034)
		(size 0.508)
		(drill 0.254)
		(layers "F.Cu" "B.Cu")
		(net "PE_CLK100M_DR13_2_P")
	)
	(via
		(at 31.496 -136.416542)
		(size 0.508)
		(drill 0.254)
		(layers "F.Cu" "B.Cu")
		(net "PE_CLK100M_DR13_2_P")
	)
	(segment
		(start 31.496 -136.416542)
		(end 31.242 -136.162542)
		(width 0.174752)
		(layer "B.Cu")
		(net "PE_CLK100M_DR13_2_P")
	)
	(segment
		(start 17.525492 -136.162542)
		(end 17.272 -136.416034)
		(width 0.174752)
		(layer "B.Cu")
		(net "PE_CLK100M_DR13_2_P")
	)
	(segment
		(start 31.242 -136.162542)
		(end 17.525492 -136.162542)
		(width 0.174752)
		(layer "B.Cu")
		(net "PE_CLK100M_DR13_2_P")
	)
	(segment
		(start 37.890196 -130.711956)
		(end 37.890196 -130.892804)
		(width 0.174752)
		(layer "F.Cu")
		(net "PE_CLK100M_DR13_2_N")
	)
	(segment
		(start 34.620708 -134.162292)
		(end 34.250122 -134.532878)
		(width 0.174752)
		(layer "F.Cu")
		(net "PE_CLK100M_DR13_2_N")
	)
	(segment
		(start 17.525746 -135.85698)
		(end 17.272 -135.603234)
		(width 0.174752)
		(layer "F.Cu")
		(net "PE_CLK100M_DR13_2_N")
	)
	(segment
		(start 91.44 -112.268)
		(end 91.44 -118.11)
		(width 0.174752)
		(layer "F.Cu")
		(net "PE_CLK100M_DR13_2_N")
	)
	(segment
		(start 31.749746 -135.857488)
		(end 31.496 -135.603742)
		(width 0.174752)
		(layer "F.Cu")
		(net "PE_CLK100M_DR13_2_N")
	)
	(segment
		(start 18.535142 -135.609838)
		(end 18.288 -135.85698)
		(width 0.174752)
		(layer "F.Cu")
		(net "PE_CLK100M_DR13_2_N")
	)
	(segment
		(start 34.620708 -133.981444)
		(end 34.620708 -134.162292)
		(width 0.174752)
		(layer "F.Cu")
		(net "PE_CLK100M_DR13_2_N")
	)
	(segment
		(start 35.542982 -133.240018)
		(end 35.172142 -133.610858)
		(width 0.174752)
		(layer "F.Cu")
		(net "PE_CLK100M_DR13_2_N")
	)
	(segment
		(start 18.288 -135.85698)
		(end 17.525746 -135.85698)
		(width 0.174752)
		(layer "F.Cu")
		(net "PE_CLK100M_DR13_2_N")
	)
	(segment
		(start 82.732372 -126.817628)
		(end 41.965372 -126.817628)
		(width 0.174752)
		(layer "F.Cu")
		(net "PE_CLK100M_DR13_2_N")
	)
	(segment
		(start 37.890196 -130.892804)
		(end 36.094162 -132.688838)
		(width 0.174752)
		(layer "F.Cu")
		(net "PE_CLK100M_DR13_2_N")
	)
	(segment
		(start 36.094162 -132.688838)
		(end 35.913568 -132.688838)
		(width 0.174752)
		(layer "F.Cu")
		(net "PE_CLK100M_DR13_2_N")
	)
	(segment
		(start 33.698688 -135.084312)
		(end 32.925512 -135.857488)
		(width 0.174752)
		(layer "F.Cu")
		(net "PE_CLK100M_DR13_2_N")
	)
	(segment
		(start 91.44 -118.11)
		(end 82.732372 -126.817628)
		(width 0.174752)
		(layer "F.Cu")
		(net "PE_CLK100M_DR13_2_N")
	)
	(segment
		(start 90.6272 -111.0107)
		(end 90.6272 -111.4552)
		(width 0.174752)
		(layer "F.Cu")
		(net "PE_CLK100M_DR13_2_N")
	)
	(segment
		(start 39.363904 -129.419096)
		(end 39.183056 -129.419096)
		(width 0.174752)
		(layer "F.Cu")
		(net "PE_CLK100M_DR13_2_N")
	)
	(segment
		(start 34.250122 -134.532878)
		(end 34.069274 -134.532878)
		(width 0.174752)
		(layer "F.Cu")
		(net "PE_CLK100M_DR13_2_N")
	)
	(segment
		(start 90.297 -110.6805)
		(end 90.6272 -111.0107)
		(width 0.174752)
		(layer "F.Cu")
		(net "PE_CLK100M_DR13_2_N")
	)
	(segment
		(start 38.44163 -130.34137)
		(end 38.261036 -130.34137)
		(width 0.174752)
		(layer "F.Cu")
		(net "PE_CLK100M_DR13_2_N")
	)
	(segment
		(start 35.913568 -132.688838)
		(end 35.542982 -133.059424)
		(width 0.174752)
		(layer "F.Cu")
		(net "PE_CLK100M_DR13_2_N")
	)
	(segment
		(start 32.925512 -135.857488)
		(end 31.749746 -135.857488)
		(width 0.174752)
		(layer "F.Cu")
		(net "PE_CLK100M_DR13_2_N")
	)
	(segment
		(start 19.61007 -135.609838)
		(end 18.535142 -135.609838)
		(width 0.174752)
		(layer "F.Cu")
		(net "PE_CLK100M_DR13_2_N")
	)
	(segment
		(start 35.542982 -133.059424)
		(end 35.542982 -133.240018)
		(width 0.174752)
		(layer "F.Cu")
		(net "PE_CLK100M_DR13_2_N")
	)
	(segment
		(start 33.698688 -134.903718)
		(end 33.698688 -135.084312)
		(width 0.174752)
		(layer "F.Cu")
		(net "PE_CLK100M_DR13_2_N")
	)
	(segment
		(start 90.6272 -111.4552)
		(end 91.44 -112.268)
		(width 0.174752)
		(layer "F.Cu")
		(net "PE_CLK100M_DR13_2_N")
	)
	(segment
		(start 34.069274 -134.532878)
		(end 33.698688 -134.903718)
		(width 0.174752)
		(layer "F.Cu")
		(net "PE_CLK100M_DR13_2_N")
	)
	(segment
		(start 35.172142 -133.610858)
		(end 34.991548 -133.610858)
		(width 0.174752)
		(layer "F.Cu")
		(net "PE_CLK100M_DR13_2_N")
	)
	(segment
		(start 38.261036 -130.34137)
		(end 37.890196 -130.711956)
		(width 0.174752)
		(layer "F.Cu")
		(net "PE_CLK100M_DR13_2_N")
	)
	(segment
		(start 39.183056 -129.419096)
		(end 38.81247 -129.789936)
		(width 0.174752)
		(layer "F.Cu")
		(net "PE_CLK100M_DR13_2_N")
	)
	(segment
		(start 41.965372 -126.817628)
		(end 39.363904 -129.419096)
		(width 0.174752)
		(layer "F.Cu")
		(net "PE_CLK100M_DR13_2_N")
	)
	(segment
		(start 38.81247 -129.97053)
		(end 38.44163 -130.34137)
		(width 0.174752)
		(layer "F.Cu")
		(net "PE_CLK100M_DR13_2_N")
	)
	(segment
		(start 34.991548 -133.610858)
		(end 34.620708 -133.981444)
		(width 0.174752)
		(layer "F.Cu")
		(net "PE_CLK100M_DR13_2_N")
	)
	(segment
		(start 38.81247 -129.789936)
		(end 38.81247 -129.97053)
		(width 0.174752)
		(layer "F.Cu")
		(net "PE_CLK100M_DR13_2_N")
	)
	(via
		(at 31.496 -135.603742)
		(size 0.508)
		(drill 0.254)
		(layers "F.Cu" "B.Cu")
		(net "PE_CLK100M_DR13_2_N")
	)
	(via
		(at 17.272 -135.603234)
		(size 0.508)
		(drill 0.254)
		(layers "F.Cu" "B.Cu")
		(net "PE_CLK100M_DR13_2_N")
	)
	(segment
		(start 31.242254 -135.857488)
		(end 31.496 -135.603742)
		(width 0.174752)
		(layer "B.Cu")
		(net "PE_CLK100M_DR13_2_N")
	)
	(segment
		(start 17.526254 -135.857488)
		(end 31.242254 -135.857488)
		(width 0.174752)
		(layer "B.Cu")
		(net "PE_CLK100M_DR13_2_N")
	)
	(segment
		(start 17.272 -135.603234)
		(end 17.526254 -135.857488)
		(width 0.174752)
		(layer "B.Cu")
		(net "PE_CLK100M_DR13_2_N")
	)
	(segment
		(start 87.4776 -110.6805)
		(end 87.134954 -111.023146)
		(width 0.174752)
		(layer "F.Cu")
		(net "PE_CLK100M_DR13_1_P")
	)
	(segment
		(start 23.876 -144.809972)
		(end 22.800056 -144.809972)
		(width 0.174752)
		(layer "F.Cu")
		(net "PE_CLK100M_DR13_1_P")
	)
	(segment
		(start 28.575 -134.239)
		(end 28.575 -143.637)
		(width 0.174752)
		(layer "F.Cu")
		(net "PE_CLK100M_DR13_1_P")
	)
	(segment
		(start 87.134954 -111.023146)
		(end 87.134954 -111.620046)
		(width 0.174752)
		(layer "F.Cu")
		(net "PE_CLK100M_DR13_1_P")
	)
	(segment
		(start 38.862 -123.952)
		(end 28.575 -134.239)
		(width 0.174752)
		(layer "F.Cu")
		(net "PE_CLK100M_DR13_1_P")
	)
	(segment
		(start 81.026 -123.952)
		(end 38.862 -123.952)
		(width 0.174752)
		(layer "F.Cu")
		(net "PE_CLK100M_DR13_1_P")
	)
	(segment
		(start 85.979 -112.776)
		(end 85.979 -118.999)
		(width 0.174752)
		(layer "F.Cu")
		(net "PE_CLK100M_DR13_1_P")
	)
	(segment
		(start 87.503 -110.6805)
		(end 87.4776 -110.6805)
		(width 0.174752)
		(layer "F.Cu")
		(net "PE_CLK100M_DR13_1_P")
	)
	(segment
		(start 87.134954 -111.620046)
		(end 85.979 -112.776)
		(width 0.174752)
		(layer "F.Cu")
		(net "PE_CLK100M_DR13_1_P")
	)
	(segment
		(start 85.979 -118.999)
		(end 81.026 -123.952)
		(width 0.174752)
		(layer "F.Cu")
		(net "PE_CLK100M_DR13_1_P")
	)
	(segment
		(start 27.649424 -144.562576)
		(end 24.123396 -144.562576)
		(width 0.174752)
		(layer "F.Cu")
		(net "PE_CLK100M_DR13_1_P")
	)
	(segment
		(start 24.123396 -144.562576)
		(end 23.876 -144.809972)
		(width 0.174752)
		(layer "F.Cu")
		(net "PE_CLK100M_DR13_1_P")
	)
	(segment
		(start 28.575 -143.637)
		(end 27.649424 -144.562576)
		(width 0.174752)
		(layer "F.Cu")
		(net "PE_CLK100M_DR13_1_P")
	)
	(segment
		(start 28.142184 -140.540486)
		(end 28.269946 -140.668248)
		(width 0.174752)
		(layer "F.Cu")
		(net "PE_CLK100M_DR13_1_N")
	)
	(segment
		(start 29.562806 -132.639054)
		(end 29.562806 -132.819648)
		(width 0.174752)
		(layer "F.Cu")
		(net "PE_CLK100M_DR13_1_N")
	)
	(segment
		(start 28.269946 -139.364212)
		(end 28.269946 -139.888468)
		(width 0.174752)
		(layer "F.Cu")
		(net "PE_CLK100M_DR13_1_N")
	)
	(segment
		(start 29.933392 -132.268214)
		(end 29.562806 -132.639054)
		(width 0.174752)
		(layer "F.Cu")
		(net "PE_CLK100M_DR13_1_N")
	)
	(segment
		(start 27.522932 -144.257522)
		(end 24.12365 -144.257522)
		(width 0.174752)
		(layer "F.Cu")
		(net "PE_CLK100M_DR13_1_N")
	)
	(segment
		(start 86.8299 -111.493554)
		(end 85.673946 -112.649508)
		(width 0.174752)
		(layer "F.Cu")
		(net "PE_CLK100M_DR13_1_N")
	)
	(segment
		(start 29.191966 -133.190488)
		(end 29.011372 -133.190488)
		(width 0.174752)
		(layer "F.Cu")
		(net "PE_CLK100M_DR13_1_N")
	)
	(segment
		(start 28.640532 -133.561074)
		(end 28.640532 -133.741922)
		(width 0.174752)
		(layer "F.Cu")
		(net "PE_CLK100M_DR13_1_N")
	)
	(segment
		(start 28.142184 -138.712194)
		(end 28.142184 -139.23645)
		(width 0.174752)
		(layer "F.Cu")
		(net "PE_CLK100M_DR13_1_N")
	)
	(segment
		(start 28.269946 -139.888468)
		(end 28.142184 -140.01623)
		(width 0.174752)
		(layer "F.Cu")
		(net "PE_CLK100M_DR13_1_N")
	)
	(segment
		(start 28.142184 -137.408158)
		(end 28.142184 -137.932414)
		(width 0.174752)
		(layer "F.Cu")
		(net "PE_CLK100M_DR13_1_N")
	)
	(segment
		(start 86.487 -110.6805)
		(end 86.8299 -111.0234)
		(width 0.174752)
		(layer "F.Cu")
		(net "PE_CLK100M_DR13_1_N")
	)
	(segment
		(start 28.640532 -133.741922)
		(end 28.269946 -134.112508)
		(width 0.174752)
		(layer "F.Cu")
		(net "PE_CLK100M_DR13_1_N")
	)
	(segment
		(start 28.269946 -138.584432)
		(end 28.142184 -138.712194)
		(width 0.174752)
		(layer "F.Cu")
		(net "PE_CLK100M_DR13_1_N")
	)
	(segment
		(start 28.269946 -143.510508)
		(end 27.522932 -144.257522)
		(width 0.174752)
		(layer "F.Cu")
		(net "PE_CLK100M_DR13_1_N")
	)
	(segment
		(start 24.12365 -144.257522)
		(end 23.876 -144.009872)
		(width 0.174752)
		(layer "F.Cu")
		(net "PE_CLK100M_DR13_1_N")
	)
	(segment
		(start 28.142184 -140.01623)
		(end 28.142184 -140.540486)
		(width 0.174752)
		(layer "F.Cu")
		(net "PE_CLK100M_DR13_1_N")
	)
	(segment
		(start 23.876 -144.009872)
		(end 22.800056 -144.009872)
		(width 0.174752)
		(layer "F.Cu")
		(net "PE_CLK100M_DR13_1_N")
	)
	(segment
		(start 85.673946 -118.872508)
		(end 80.899508 -123.646946)
		(width 0.174752)
		(layer "F.Cu")
		(net "PE_CLK100M_DR13_1_N")
	)
	(segment
		(start 80.899508 -123.646946)
		(end 38.735508 -123.646946)
		(width 0.174752)
		(layer "F.Cu")
		(net "PE_CLK100M_DR13_1_N")
	)
	(segment
		(start 86.8299 -111.0234)
		(end 86.8299 -111.493554)
		(width 0.174752)
		(layer "F.Cu")
		(net "PE_CLK100M_DR13_1_N")
	)
	(segment
		(start 28.269946 -137.280396)
		(end 28.142184 -137.408158)
		(width 0.174752)
		(layer "F.Cu")
		(net "PE_CLK100M_DR13_1_N")
	)
	(segment
		(start 85.673946 -112.649508)
		(end 85.673946 -118.872508)
		(width 0.174752)
		(layer "F.Cu")
		(net "PE_CLK100M_DR13_1_N")
	)
	(segment
		(start 28.269946 -138.060176)
		(end 28.269946 -138.584432)
		(width 0.174752)
		(layer "F.Cu")
		(net "PE_CLK100M_DR13_1_N")
	)
	(segment
		(start 38.735508 -123.646946)
		(end 30.11424 -132.268214)
		(width 0.174752)
		(layer "F.Cu")
		(net "PE_CLK100M_DR13_1_N")
	)
	(segment
		(start 28.269946 -140.668248)
		(end 28.269946 -143.510508)
		(width 0.174752)
		(layer "F.Cu")
		(net "PE_CLK100M_DR13_1_N")
	)
	(segment
		(start 28.142184 -137.932414)
		(end 28.269946 -138.060176)
		(width 0.174752)
		(layer "F.Cu")
		(net "PE_CLK100M_DR13_1_N")
	)
	(segment
		(start 30.11424 -132.268214)
		(end 29.933392 -132.268214)
		(width 0.174752)
		(layer "F.Cu")
		(net "PE_CLK100M_DR13_1_N")
	)
	(segment
		(start 29.562806 -132.819648)
		(end 29.191966 -133.190488)
		(width 0.174752)
		(layer "F.Cu")
		(net "PE_CLK100M_DR13_1_N")
	)
	(segment
		(start 29.011372 -133.190488)
		(end 28.640532 -133.561074)
		(width 0.174752)
		(layer "F.Cu")
		(net "PE_CLK100M_DR13_1_N")
	)
	(segment
		(start 28.269946 -134.112508)
		(end 28.269946 -137.280396)
		(width 0.174752)
		(layer "F.Cu")
		(net "PE_CLK100M_DR13_1_N")
	)
	(segment
		(start 28.142184 -139.23645)
		(end 28.269946 -139.364212)
		(width 0.174752)
		(layer "F.Cu")
		(net "PE_CLK100M_DR13_1_N")
	)
	(segment
		(start 18.288 -239.162082)
		(end 17.526 -239.162082)
		(width 0.174752)
		(layer "F.Cu")
		(net "PE_CLK100M_DR12_2_P")
	)
	(segment
		(start 90.957654 -220.574108)
		(end 90.957654 -220.255846)
		(width 0.174752)
		(layer "F.Cu")
		(net "PE_CLK100M_DR12_2_P")
	)
	(segment
		(start 45.922946 -237.668054)
		(end 81.609946 -237.668054)
		(width 0.174752)
		(layer "F.Cu")
		(net "PE_CLK100M_DR12_2_P")
	)
	(segment
		(start 17.526 -239.162082)
		(end 17.272 -239.416082)
		(width 0.174752)
		(layer "F.Cu")
		(net "PE_CLK100M_DR12_2_P")
	)
	(segment
		(start 19.61007 -239.409986)
		(end 18.535904 -239.409986)
		(width 0.174752)
		(layer "F.Cu")
		(net "PE_CLK100M_DR12_2_P")
	)
	(segment
		(start 81.609946 -237.668054)
		(end 91.745054 -227.532946)
		(width 0.174752)
		(layer "F.Cu")
		(net "PE_CLK100M_DR12_2_P")
	)
	(segment
		(start 90.957654 -220.255846)
		(end 91.313 -219.9005)
		(width 0.174752)
		(layer "F.Cu")
		(net "PE_CLK100M_DR12_2_P")
	)
	(segment
		(start 42.672254 -239.143032)
		(end 44.447968 -239.143032)
		(width 0.174752)
		(layer "F.Cu")
		(net "PE_CLK100M_DR12_2_P")
	)
	(segment
		(start 91.745054 -227.532946)
		(end 91.745054 -221.361508)
		(width 0.174752)
		(layer "F.Cu")
		(net "PE_CLK100M_DR12_2_P")
	)
	(segment
		(start 42.418 -239.397286)
		(end 42.672254 -239.143032)
		(width 0.174752)
		(layer "F.Cu")
		(net "PE_CLK100M_DR12_2_P")
	)
	(segment
		(start 44.447968 -239.143032)
		(end 45.922946 -237.668054)
		(width 0.174752)
		(layer "F.Cu")
		(net "PE_CLK100M_DR12_2_P")
	)
	(segment
		(start 91.745054 -221.361508)
		(end 90.957654 -220.574108)
		(width 0.174752)
		(layer "F.Cu")
		(net "PE_CLK100M_DR12_2_P")
	)
	(segment
		(start 18.535904 -239.409986)
		(end 18.288 -239.162082)
		(width 0.174752)
		(layer "F.Cu")
		(net "PE_CLK100M_DR12_2_P")
	)
	(via
		(at 17.272 -239.416082)
		(size 0.508)
		(drill 0.254)
		(layers "F.Cu" "B.Cu")
		(net "PE_CLK100M_DR12_2_P")
	)
	(via
		(at 42.418 -239.397286)
		(size 0.508)
		(drill 0.254)
		(layers "F.Cu" "B.Cu")
		(net "PE_CLK100M_DR12_2_P")
	)
	(segment
		(start 42.164 -239.143286)
		(end 42.418 -239.397286)
		(width 0.174752)
		(layer "B.Cu")
		(net "PE_CLK100M_DR12_2_P")
	)
	(segment
		(start 17.272 -239.416082)
		(end 17.544796 -239.143286)
		(width 0.174752)
		(layer "B.Cu")
		(net "PE_CLK100M_DR12_2_P")
	)
	(segment
		(start 17.544796 -239.143286)
		(end 42.164 -239.143286)
		(width 0.174752)
		(layer "B.Cu")
		(net "PE_CLK100M_DR12_2_P")
	)
	(segment
		(start 44.321476 -238.837978)
		(end 45.796454 -237.363)
		(width 0.174752)
		(layer "F.Cu")
		(net "PE_CLK100M_DR12_2_N")
	)
	(segment
		(start 42.671492 -238.837978)
		(end 44.321476 -238.837978)
		(width 0.174752)
		(layer "F.Cu")
		(net "PE_CLK100M_DR12_2_N")
	)
	(segment
		(start 18.294858 -238.857028)
		(end 17.525746 -238.857028)
		(width 0.174752)
		(layer "F.Cu")
		(net "PE_CLK100M_DR12_2_N")
	)
	(segment
		(start 18.542 -238.609886)
		(end 18.294858 -238.857028)
		(width 0.174752)
		(layer "F.Cu")
		(net "PE_CLK100M_DR12_2_N")
	)
	(segment
		(start 45.796454 -237.363)
		(end 81.483454 -237.363)
		(width 0.174752)
		(layer "F.Cu")
		(net "PE_CLK100M_DR12_2_N")
	)
	(segment
		(start 19.61007 -238.609886)
		(end 18.542 -238.609886)
		(width 0.174752)
		(layer "F.Cu")
		(net "PE_CLK100M_DR12_2_N")
	)
	(segment
		(start 42.418 -238.584486)
		(end 42.671492 -238.837978)
		(width 0.174752)
		(layer "F.Cu")
		(net "PE_CLK100M_DR12_2_N")
	)
	(segment
		(start 90.6526 -220.2561)
		(end 90.297 -219.9005)
		(width 0.174752)
		(layer "F.Cu")
		(net "PE_CLK100M_DR12_2_N")
	)
	(segment
		(start 91.44 -221.488)
		(end 90.6526 -220.7006)
		(width 0.174752)
		(layer "F.Cu")
		(net "PE_CLK100M_DR12_2_N")
	)
	(segment
		(start 17.525746 -238.857028)
		(end 17.272 -238.603282)
		(width 0.174752)
		(layer "F.Cu")
		(net "PE_CLK100M_DR12_2_N")
	)
	(segment
		(start 90.6526 -220.7006)
		(end 90.6526 -220.2561)
		(width 0.174752)
		(layer "F.Cu")
		(net "PE_CLK100M_DR12_2_N")
	)
	(segment
		(start 91.44 -227.406454)
		(end 91.44 -221.488)
		(width 0.174752)
		(layer "F.Cu")
		(net "PE_CLK100M_DR12_2_N")
	)
	(segment
		(start 81.483454 -237.363)
		(end 91.44 -227.406454)
		(width 0.174752)
		(layer "F.Cu")
		(net "PE_CLK100M_DR12_2_N")
	)
	(via
		(at 42.418 -238.584486)
		(size 0.508)
		(drill 0.254)
		(layers "F.Cu" "B.Cu")
		(net "PE_CLK100M_DR12_2_N")
	)
	(via
		(at 17.272 -238.603282)
		(size 0.508)
		(drill 0.254)
		(layers "F.Cu" "B.Cu")
		(net "PE_CLK100M_DR12_2_N")
	)
	(segment
		(start 42.164254 -238.838232)
		(end 36.094416 -238.838232)
		(width 0.174752)
		(layer "B.Cu")
		(net "PE_CLK100M_DR12_2_N")
	)
	(segment
		(start 31.342838 -238.71047)
		(end 30.818582 -238.71047)
		(width 0.174752)
		(layer "B.Cu")
		(net "PE_CLK100M_DR12_2_N")
	)
	(segment
		(start 28.862528 -238.838232)
		(end 28.734766 -238.71047)
		(width 0.174752)
		(layer "B.Cu")
		(net "PE_CLK100M_DR12_2_N")
	)
	(segment
		(start 36.094416 -238.838232)
		(end 35.966654 -238.71047)
		(width 0.174752)
		(layer "B.Cu")
		(net "PE_CLK100M_DR12_2_N")
	)
	(segment
		(start 35.442398 -238.71047)
		(end 35.314636 -238.838232)
		(width 0.174752)
		(layer "B.Cu")
		(net "PE_CLK100M_DR12_2_N")
	)
	(segment
		(start 30.038802 -238.71047)
		(end 29.514546 -238.71047)
		(width 0.174752)
		(layer "B.Cu")
		(net "PE_CLK100M_DR12_2_N")
	)
	(segment
		(start 30.166564 -238.838232)
		(end 30.038802 -238.71047)
		(width 0.174752)
		(layer "B.Cu")
		(net "PE_CLK100M_DR12_2_N")
	)
	(segment
		(start 35.966654 -238.71047)
		(end 35.442398 -238.71047)
		(width 0.174752)
		(layer "B.Cu")
		(net "PE_CLK100M_DR12_2_N")
	)
	(segment
		(start 29.514546 -238.71047)
		(end 29.386784 -238.838232)
		(width 0.174752)
		(layer "B.Cu")
		(net "PE_CLK100M_DR12_2_N")
	)
	(segment
		(start 35.314636 -238.838232)
		(end 34.79038 -238.838232)
		(width 0.174752)
		(layer "B.Cu")
		(net "PE_CLK100M_DR12_2_N")
	)
	(segment
		(start 42.418 -238.584486)
		(end 42.164254 -238.838232)
		(width 0.174752)
		(layer "B.Cu")
		(net "PE_CLK100M_DR12_2_N")
	)
	(segment
		(start 34.138362 -238.71047)
		(end 34.0106 -238.838232)
		(width 0.174752)
		(layer "B.Cu")
		(net "PE_CLK100M_DR12_2_N")
	)
	(segment
		(start 29.386784 -238.838232)
		(end 28.862528 -238.838232)
		(width 0.174752)
		(layer "B.Cu")
		(net "PE_CLK100M_DR12_2_N")
	)
	(segment
		(start 28.082748 -238.838232)
		(end 17.50695 -238.838232)
		(width 0.174752)
		(layer "B.Cu")
		(net "PE_CLK100M_DR12_2_N")
	)
	(segment
		(start 30.69082 -238.838232)
		(end 30.166564 -238.838232)
		(width 0.174752)
		(layer "B.Cu")
		(net "PE_CLK100M_DR12_2_N")
	)
	(segment
		(start 31.4706 -238.838232)
		(end 31.342838 -238.71047)
		(width 0.174752)
		(layer "B.Cu")
		(net "PE_CLK100M_DR12_2_N")
	)
	(segment
		(start 17.50695 -238.838232)
		(end 17.272 -238.603282)
		(width 0.174752)
		(layer "B.Cu")
		(net "PE_CLK100M_DR12_2_N")
	)
	(segment
		(start 28.734766 -238.71047)
		(end 28.21051 -238.71047)
		(width 0.174752)
		(layer "B.Cu")
		(net "PE_CLK100M_DR12_2_N")
	)
	(segment
		(start 34.79038 -238.838232)
		(end 34.662618 -238.71047)
		(width 0.174752)
		(layer "B.Cu")
		(net "PE_CLK100M_DR12_2_N")
	)
	(segment
		(start 30.818582 -238.71047)
		(end 30.69082 -238.838232)
		(width 0.174752)
		(layer "B.Cu")
		(net "PE_CLK100M_DR12_2_N")
	)
	(segment
		(start 34.0106 -238.838232)
		(end 31.4706 -238.838232)
		(width 0.174752)
		(layer "B.Cu")
		(net "PE_CLK100M_DR12_2_N")
	)
	(segment
		(start 28.21051 -238.71047)
		(end 28.082748 -238.838232)
		(width 0.174752)
		(layer "B.Cu")
		(net "PE_CLK100M_DR12_2_N")
	)
	(segment
		(start 34.662618 -238.71047)
		(end 34.138362 -238.71047)
		(width 0.174752)
		(layer "B.Cu")
		(net "PE_CLK100M_DR12_2_N")
	)
	(segment
		(start 80.22844 -234.061)
		(end 41.148 -234.061)
		(width 0.174752)
		(layer "F.Cu")
		(net "PE_CLK100M_DR12_1_P")
	)
	(segment
		(start 87.503 -219.9005)
		(end 87.122 -220.2815)
		(width 0.174752)
		(layer "F.Cu")
		(net "PE_CLK100M_DR12_1_P")
	)
	(segment
		(start 27.646376 -247.562624)
		(end 24.13 -247.562624)
		(width 0.174752)
		(layer "F.Cu")
		(net "PE_CLK100M_DR12_1_P")
	)
	(segment
		(start 85.979 -228.31044)
		(end 80.22844 -234.061)
		(width 0.174752)
		(layer "F.Cu")
		(net "PE_CLK100M_DR12_1_P")
	)
	(segment
		(start 23.882604 -247.81002)
		(end 22.800056 -247.81002)
		(width 0.174752)
		(layer "F.Cu")
		(net "PE_CLK100M_DR12_1_P")
	)
	(segment
		(start 87.122 -220.9292)
		(end 85.979 -222.0722)
		(width 0.174752)
		(layer "F.Cu")
		(net "PE_CLK100M_DR12_1_P")
	)
	(segment
		(start 85.979 -222.0722)
		(end 85.979 -228.31044)
		(width 0.174752)
		(layer "F.Cu")
		(net "PE_CLK100M_DR12_1_P")
	)
	(segment
		(start 24.13 -247.562624)
		(end 23.882604 -247.81002)
		(width 0.174752)
		(layer "F.Cu")
		(net "PE_CLK100M_DR12_1_P")
	)
	(segment
		(start 41.148 -234.061)
		(end 27.646376 -247.562624)
		(width 0.174752)
		(layer "F.Cu")
		(net "PE_CLK100M_DR12_1_P")
	)
	(segment
		(start 87.122 -220.2815)
		(end 87.122 -220.9292)
		(width 0.174752)
		(layer "F.Cu")
		(net "PE_CLK100M_DR12_1_P")
	)
	(segment
		(start 85.673946 -228.183948)
		(end 80.101948 -233.755946)
		(width 0.174752)
		(layer "F.Cu")
		(net "PE_CLK100M_DR12_1_N")
	)
	(segment
		(start 24.13 -247.25757)
		(end 23.88235 -247.00992)
		(width 0.174752)
		(layer "F.Cu")
		(net "PE_CLK100M_DR12_1_N")
	)
	(segment
		(start 30.11297 -244.48389)
		(end 30.11297 -244.664484)
		(width 0.174752)
		(layer "F.Cu")
		(net "PE_CLK100M_DR12_1_N")
	)
	(segment
		(start 27.519884 -247.25757)
		(end 24.13 -247.25757)
		(width 0.174752)
		(layer "F.Cu")
		(net "PE_CLK100M_DR12_1_N")
	)
	(segment
		(start 41.021508 -233.755946)
		(end 34.855912 -239.921542)
		(width 0.174752)
		(layer "F.Cu")
		(net "PE_CLK100M_DR12_1_N")
	)
	(segment
		(start 30.48381 -244.11305)
		(end 30.11297 -244.48389)
		(width 0.174752)
		(layer "F.Cu")
		(net "PE_CLK100M_DR12_1_N")
	)
	(segment
		(start 34.675318 -239.921542)
		(end 34.304732 -240.292128)
		(width 0.174752)
		(layer "F.Cu")
		(net "PE_CLK100M_DR12_1_N")
	)
	(segment
		(start 85.673946 -221.945708)
		(end 85.673946 -228.183948)
		(width 0.174752)
		(layer "F.Cu")
		(net "PE_CLK100M_DR12_1_N")
	)
	(segment
		(start 86.816946 -220.802708)
		(end 85.673946 -221.945708)
		(width 0.174752)
		(layer "F.Cu")
		(net "PE_CLK100M_DR12_1_N")
	)
	(segment
		(start 80.101948 -233.755946)
		(end 41.021508 -233.755946)
		(width 0.174752)
		(layer "F.Cu")
		(net "PE_CLK100M_DR12_1_N")
	)
	(segment
		(start 29.19095 -245.40591)
		(end 29.19095 -245.586504)
		(width 0.174752)
		(layer "F.Cu")
		(net "PE_CLK100M_DR12_1_N")
	)
	(segment
		(start 29.19095 -245.586504)
		(end 27.519884 -247.25757)
		(width 0.174752)
		(layer "F.Cu")
		(net "PE_CLK100M_DR12_1_N")
	)
	(segment
		(start 29.561536 -245.03507)
		(end 29.19095 -245.40591)
		(width 0.174752)
		(layer "F.Cu")
		(net "PE_CLK100M_DR12_1_N")
	)
	(segment
		(start 34.304732 -240.472722)
		(end 33.933892 -240.843562)
		(width 0.174752)
		(layer "F.Cu")
		(net "PE_CLK100M_DR12_1_N")
	)
	(segment
		(start 34.304732 -240.292128)
		(end 34.304732 -240.472722)
		(width 0.174752)
		(layer "F.Cu")
		(net "PE_CLK100M_DR12_1_N")
	)
	(segment
		(start 31.586424 -243.19103)
		(end 31.40583 -243.19103)
		(width 0.174752)
		(layer "F.Cu")
		(net "PE_CLK100M_DR12_1_N")
	)
	(segment
		(start 30.664404 -244.11305)
		(end 30.48381 -244.11305)
		(width 0.174752)
		(layer "F.Cu")
		(net "PE_CLK100M_DR12_1_N")
	)
	(segment
		(start 33.933892 -240.843562)
		(end 33.753298 -240.843562)
		(width 0.174752)
		(layer "F.Cu")
		(net "PE_CLK100M_DR12_1_N")
	)
	(segment
		(start 31.03499 -243.742464)
		(end 30.664404 -244.11305)
		(width 0.174752)
		(layer "F.Cu")
		(net "PE_CLK100M_DR12_1_N")
	)
	(segment
		(start 29.742384 -245.03507)
		(end 29.561536 -245.03507)
		(width 0.174752)
		(layer "F.Cu")
		(net "PE_CLK100M_DR12_1_N")
	)
	(segment
		(start 31.40583 -243.19103)
		(end 31.03499 -243.561616)
		(width 0.174752)
		(layer "F.Cu")
		(net "PE_CLK100M_DR12_1_N")
	)
	(segment
		(start 31.03499 -243.561616)
		(end 31.03499 -243.742464)
		(width 0.174752)
		(layer "F.Cu")
		(net "PE_CLK100M_DR12_1_N")
	)
	(segment
		(start 23.88235 -247.00992)
		(end 22.800056 -247.00992)
		(width 0.174752)
		(layer "F.Cu")
		(net "PE_CLK100M_DR12_1_N")
	)
	(segment
		(start 86.487 -219.9005)
		(end 86.816946 -220.230446)
		(width 0.174752)
		(layer "F.Cu")
		(net "PE_CLK100M_DR12_1_N")
	)
	(segment
		(start 33.753298 -240.843562)
		(end 33.382458 -241.214148)
		(width 0.174752)
		(layer "F.Cu")
		(net "PE_CLK100M_DR12_1_N")
	)
	(segment
		(start 33.382458 -241.394996)
		(end 31.586424 -243.19103)
		(width 0.174752)
		(layer "F.Cu")
		(net "PE_CLK100M_DR12_1_N")
	)
	(segment
		(start 30.11297 -244.664484)
		(end 29.742384 -245.03507)
		(width 0.174752)
		(layer "F.Cu")
		(net "PE_CLK100M_DR12_1_N")
	)
	(segment
		(start 33.382458 -241.214148)
		(end 33.382458 -241.394996)
		(width 0.174752)
		(layer "F.Cu")
		(net "PE_CLK100M_DR12_1_N")
	)
	(segment
		(start 86.816946 -220.230446)
		(end 86.816946 -220.802708)
		(width 0.174752)
		(layer "F.Cu")
		(net "PE_CLK100M_DR12_1_N")
	)
	(segment
		(start 34.855912 -239.921542)
		(end 34.675318 -239.921542)
		(width 0.174752)
		(layer "F.Cu")
		(net "PE_CLK100M_DR12_1_N")
	)
	(segment
		(start 91.745054 -321.817492)
		(end 75.004422 -338.558124)
		(width 0.174752)
		(layer "F.Cu")
		(net "PE_CLK100M_DR11_2_P")
	)
	(segment
		(start 91.745054 -315.722508)
		(end 91.745054 -321.817492)
		(width 0.174752)
		(layer "F.Cu")
		(net "PE_CLK100M_DR11_2_P")
	)
	(segment
		(start 91.313 -314.2615)
		(end 90.957654 -314.616846)
		(width 0.174752)
		(layer "F.Cu")
		(net "PE_CLK100M_DR11_2_P")
	)
	(segment
		(start 19.61007 -342.410034)
		(end 18.535904 -342.410034)
		(width 0.174752)
		(layer "F.Cu")
		(net "PE_CLK100M_DR11_2_P")
	)
	(segment
		(start 39.012876 -338.558124)
		(end 35.42792 -342.14308)
		(width 0.174752)
		(layer "F.Cu")
		(net "PE_CLK100M_DR11_2_P")
	)
	(segment
		(start 90.957654 -314.935108)
		(end 91.745054 -315.722508)
		(width 0.174752)
		(layer "F.Cu")
		(net "PE_CLK100M_DR11_2_P")
	)
	(segment
		(start 18.535904 -342.410034)
		(end 18.288 -342.16213)
		(width 0.174752)
		(layer "F.Cu")
		(net "PE_CLK100M_DR11_2_P")
	)
	(segment
		(start 75.004422 -338.558124)
		(end 39.012876 -338.558124)
		(width 0.174752)
		(layer "F.Cu")
		(net "PE_CLK100M_DR11_2_P")
	)
	(segment
		(start 35.42792 -342.14308)
		(end 33.147254 -342.14308)
		(width 0.174752)
		(layer "F.Cu")
		(net "PE_CLK100M_DR11_2_P")
	)
	(segment
		(start 33.147254 -342.14308)
		(end 32.893 -342.397334)
		(width 0.174752)
		(layer "F.Cu")
		(net "PE_CLK100M_DR11_2_P")
	)
	(segment
		(start 90.957654 -314.616846)
		(end 90.957654 -314.935108)
		(width 0.174752)
		(layer "F.Cu")
		(net "PE_CLK100M_DR11_2_P")
	)
	(segment
		(start 18.288 -342.16213)
		(end 17.526 -342.16213)
		(width 0.174752)
		(layer "F.Cu")
		(net "PE_CLK100M_DR11_2_P")
	)
	(segment
		(start 17.526 -342.16213)
		(end 17.272 -342.41613)
		(width 0.174752)
		(layer "F.Cu")
		(net "PE_CLK100M_DR11_2_P")
	)
	(via
		(at 32.893 -342.397334)
		(size 0.508)
		(drill 0.254)
		(layers "F.Cu" "B.Cu")
		(net "PE_CLK100M_DR11_2_P")
	)
	(via
		(at 17.272 -342.41613)
		(size 0.508)
		(drill 0.254)
		(layers "F.Cu" "B.Cu")
		(net "PE_CLK100M_DR11_2_P")
	)
	(segment
		(start 32.639 -342.143334)
		(end 32.893 -342.397334)
		(width 0.174752)
		(layer "B.Cu")
		(net "PE_CLK100M_DR11_2_P")
	)
	(segment
		(start 17.544796 -342.143334)
		(end 32.639 -342.143334)
		(width 0.174752)
		(layer "B.Cu")
		(net "PE_CLK100M_DR11_2_P")
	)
	(segment
		(start 17.272 -342.41613)
		(end 17.544796 -342.143334)
		(width 0.174752)
		(layer "B.Cu")
		(net "PE_CLK100M_DR11_2_P")
	)
	(segment
		(start 41.204896 -338.125308)
		(end 40.68064 -338.125308)
		(width 0.174752)
		(layer "F.Cu")
		(net "PE_CLK100M_DR11_2_N")
	)
	(segment
		(start 47.244762 -338.125308)
		(end 47.117 -338.25307)
		(width 0.174752)
		(layer "F.Cu")
		(net "PE_CLK100M_DR11_2_N")
	)
	(segment
		(start 41.984676 -338.125308)
		(end 41.856914 -338.25307)
		(width 0.174752)
		(layer "F.Cu")
		(net "PE_CLK100M_DR11_2_N")
	)
	(segment
		(start 41.856914 -338.25307)
		(end 41.332658 -338.25307)
		(width 0.174752)
		(layer "F.Cu")
		(net "PE_CLK100M_DR11_2_N")
	)
	(segment
		(start 47.89678 -338.25307)
		(end 47.769018 -338.125308)
		(width 0.174752)
		(layer "F.Cu")
		(net "PE_CLK100M_DR11_2_N")
	)
	(segment
		(start 48.421036 -338.25307)
		(end 47.89678 -338.25307)
		(width 0.174752)
		(layer "F.Cu")
		(net "PE_CLK100M_DR11_2_N")
	)
	(segment
		(start 18.542 -341.609934)
		(end 18.294858 -341.857076)
		(width 0.174752)
		(layer "F.Cu")
		(net "PE_CLK100M_DR11_2_N")
	)
	(segment
		(start 47.769018 -338.125308)
		(end 47.244762 -338.125308)
		(width 0.174752)
		(layer "F.Cu")
		(net "PE_CLK100M_DR11_2_N")
	)
	(segment
		(start 43.288712 -338.125308)
		(end 43.16095 -338.25307)
		(width 0.174752)
		(layer "F.Cu")
		(net "PE_CLK100M_DR11_2_N")
	)
	(segment
		(start 41.332658 -338.25307)
		(end 41.204896 -338.125308)
		(width 0.174752)
		(layer "F.Cu")
		(net "PE_CLK100M_DR11_2_N")
	)
	(segment
		(start 49.200816 -338.25307)
		(end 49.073054 -338.125308)
		(width 0.174752)
		(layer "F.Cu")
		(net "PE_CLK100M_DR11_2_N")
	)
	(segment
		(start 17.525746 -341.857076)
		(end 17.272 -341.60333)
		(width 0.174752)
		(layer "F.Cu")
		(net "PE_CLK100M_DR11_2_N")
	)
	(segment
		(start 40.68064 -338.125308)
		(end 40.552878 -338.25307)
		(width 0.174752)
		(layer "F.Cu")
		(net "PE_CLK100M_DR11_2_N")
	)
	(segment
		(start 90.6526 -315.0616)
		(end 91.44 -315.849)
		(width 0.174752)
		(layer "F.Cu")
		(net "PE_CLK100M_DR11_2_N")
	)
	(segment
		(start 18.294858 -341.857076)
		(end 17.525746 -341.857076)
		(width 0.174752)
		(layer "F.Cu")
		(net "PE_CLK100M_DR11_2_N")
	)
	(segment
		(start 74.87793 -338.25307)
		(end 49.200816 -338.25307)
		(width 0.174752)
		(layer "F.Cu")
		(net "PE_CLK100M_DR11_2_N")
	)
	(segment
		(start 43.94073 -338.25307)
		(end 43.812968 -338.125308)
		(width 0.174752)
		(layer "F.Cu")
		(net "PE_CLK100M_DR11_2_N")
	)
	(segment
		(start 35.301428 -341.838026)
		(end 33.146492 -341.838026)
		(width 0.174752)
		(layer "F.Cu")
		(net "PE_CLK100M_DR11_2_N")
	)
	(segment
		(start 49.073054 -338.125308)
		(end 48.548798 -338.125308)
		(width 0.174752)
		(layer "F.Cu")
		(net "PE_CLK100M_DR11_2_N")
	)
	(segment
		(start 47.117 -338.25307)
		(end 43.94073 -338.25307)
		(width 0.174752)
		(layer "F.Cu")
		(net "PE_CLK100M_DR11_2_N")
	)
	(segment
		(start 19.61007 -341.609934)
		(end 18.542 -341.609934)
		(width 0.174752)
		(layer "F.Cu")
		(net "PE_CLK100M_DR11_2_N")
	)
	(segment
		(start 43.16095 -338.25307)
		(end 42.636694 -338.25307)
		(width 0.174752)
		(layer "F.Cu")
		(net "PE_CLK100M_DR11_2_N")
	)
	(segment
		(start 91.44 -315.849)
		(end 91.44 -321.691)
		(width 0.174752)
		(layer "F.Cu")
		(net "PE_CLK100M_DR11_2_N")
	)
	(segment
		(start 40.552878 -338.25307)
		(end 38.886384 -338.25307)
		(width 0.174752)
		(layer "F.Cu")
		(net "PE_CLK100M_DR11_2_N")
	)
	(segment
		(start 90.6526 -314.6171)
		(end 90.6526 -315.0616)
		(width 0.174752)
		(layer "F.Cu")
		(net "PE_CLK100M_DR11_2_N")
	)
	(segment
		(start 90.297 -314.2615)
		(end 90.6526 -314.6171)
		(width 0.174752)
		(layer "F.Cu")
		(net "PE_CLK100M_DR11_2_N")
	)
	(segment
		(start 33.146492 -341.838026)
		(end 32.893 -341.584534)
		(width 0.174752)
		(layer "F.Cu")
		(net "PE_CLK100M_DR11_2_N")
	)
	(segment
		(start 42.508932 -338.125308)
		(end 41.984676 -338.125308)
		(width 0.174752)
		(layer "F.Cu")
		(net "PE_CLK100M_DR11_2_N")
	)
	(segment
		(start 38.886384 -338.25307)
		(end 35.301428 -341.838026)
		(width 0.174752)
		(layer "F.Cu")
		(net "PE_CLK100M_DR11_2_N")
	)
	(segment
		(start 48.548798 -338.125308)
		(end 48.421036 -338.25307)
		(width 0.174752)
		(layer "F.Cu")
		(net "PE_CLK100M_DR11_2_N")
	)
	(segment
		(start 43.812968 -338.125308)
		(end 43.288712 -338.125308)
		(width 0.174752)
		(layer "F.Cu")
		(net "PE_CLK100M_DR11_2_N")
	)
	(segment
		(start 91.44 -321.691)
		(end 74.87793 -338.25307)
		(width 0.174752)
		(layer "F.Cu")
		(net "PE_CLK100M_DR11_2_N")
	)
	(segment
		(start 42.636694 -338.25307)
		(end 42.508932 -338.125308)
		(width 0.174752)
		(layer "F.Cu")
		(net "PE_CLK100M_DR11_2_N")
	)
	(via
		(at 32.893 -341.584534)
		(size 0.508)
		(drill 0.254)
		(layers "F.Cu" "B.Cu")
		(net "PE_CLK100M_DR11_2_N")
	)
	(via
		(at 17.272 -341.60333)
		(size 0.508)
		(drill 0.254)
		(layers "F.Cu" "B.Cu")
		(net "PE_CLK100M_DR11_2_N")
	)
	(segment
		(start 32.639254 -341.83828)
		(end 32.893 -341.584534)
		(width 0.174752)
		(layer "B.Cu")
		(net "PE_CLK100M_DR11_2_N")
	)
	(segment
		(start 17.50695 -341.83828)
		(end 32.639254 -341.83828)
		(width 0.174752)
		(layer "B.Cu")
		(net "PE_CLK100M_DR11_2_N")
	)
	(segment
		(start 17.272 -341.60333)
		(end 17.50695 -341.83828)
		(width 0.174752)
		(layer "B.Cu")
		(net "PE_CLK100M_DR11_2_N")
	)
	(segment
		(start 27.566874 -350.562672)
		(end 24.214328 -350.562672)
		(width 0.174752)
		(layer "F.Cu")
		(net "PE_CLK100M_DR11_1_P")
	)
	(segment
		(start 73.406 -335.153)
		(end 33.1978 -335.153)
		(width 0.174752)
		(layer "F.Cu")
		(net "PE_CLK100M_DR11_1_P")
	)
	(segment
		(start 28.880054 -349.249492)
		(end 27.566874 -350.562672)
		(width 0.174752)
		(layer "F.Cu")
		(net "PE_CLK100M_DR11_1_P")
	)
	(segment
		(start 87.147654 -314.616846)
		(end 87.147654 -315.188346)
		(width 0.174752)
		(layer "F.Cu")
		(net "PE_CLK100M_DR11_1_P")
	)
	(segment
		(start 24.214328 -350.562672)
		(end 23.966932 -350.810068)
		(width 0.174752)
		(layer "F.Cu")
		(net "PE_CLK100M_DR11_1_P")
	)
	(segment
		(start 85.979 -316.357)
		(end 85.979 -322.58)
		(width 0.174752)
		(layer "F.Cu")
		(net "PE_CLK100M_DR11_1_P")
	)
	(segment
		(start 87.503 -314.2615)
		(end 87.147654 -314.616846)
		(width 0.174752)
		(layer "F.Cu")
		(net "PE_CLK100M_DR11_1_P")
	)
	(segment
		(start 33.1978 -335.153)
		(end 30.82036 -337.53044)
		(width 0.174752)
		(layer "F.Cu")
		(net "PE_CLK100M_DR11_1_P")
	)
	(segment
		(start 28.880054 -339.470492)
		(end 28.880054 -349.249492)
		(width 0.174752)
		(layer "F.Cu")
		(net "PE_CLK100M_DR11_1_P")
	)
	(segment
		(start 85.979 -322.58)
		(end 73.406 -335.153)
		(width 0.174752)
		(layer "F.Cu")
		(net "PE_CLK100M_DR11_1_P")
	)
	(segment
		(start 23.966932 -350.810068)
		(end 22.800056 -350.810068)
		(width 0.174752)
		(layer "F.Cu")
		(net "PE_CLK100M_DR11_1_P")
	)
	(segment
		(start 87.147654 -315.188346)
		(end 85.979 -316.357)
		(width 0.174752)
		(layer "F.Cu")
		(net "PE_CLK100M_DR11_1_P")
	)
	(segment
		(start 30.82036 -337.53044)
		(end 28.880054 -339.470492)
		(width 0.174752)
		(layer "F.Cu")
		(net "PE_CLK100M_DR11_1_P")
	)
	(segment
		(start 28.575 -344.569034)
		(end 28.447238 -344.696796)
		(width 0.174752)
		(layer "F.Cu")
		(net "PE_CLK100M_DR11_1_N")
	)
	(segment
		(start 86.487 -314.2615)
		(end 86.8426 -314.6171)
		(width 0.174752)
		(layer "F.Cu")
		(net "PE_CLK100M_DR11_1_N")
	)
	(segment
		(start 28.575 -345.348814)
		(end 28.575 -345.87307)
		(width 0.174752)
		(layer "F.Cu")
		(net "PE_CLK100M_DR11_1_N")
	)
	(segment
		(start 28.575 -349.123)
		(end 27.440382 -350.257618)
		(width 0.174752)
		(layer "F.Cu")
		(net "PE_CLK100M_DR11_1_N")
	)
	(segment
		(start 28.575 -346.65285)
		(end 28.575 -349.123)
		(width 0.174752)
		(layer "F.Cu")
		(net "PE_CLK100M_DR11_1_N")
	)
	(segment
		(start 30.238446 -337.499706)
		(end 29.86786 -337.870546)
		(width 0.174752)
		(layer "F.Cu")
		(net "PE_CLK100M_DR11_1_N")
	)
	(segment
		(start 28.575 -339.344)
		(end 28.575 -343.264998)
		(width 0.174752)
		(layer "F.Cu")
		(net "PE_CLK100M_DR11_1_N")
	)
	(segment
		(start 85.673946 -322.453508)
		(end 73.279508 -334.847946)
		(width 0.174752)
		(layer "F.Cu")
		(net "PE_CLK100M_DR11_1_N")
	)
	(segment
		(start 86.8426 -315.061854)
		(end 85.673946 -316.230508)
		(width 0.174752)
		(layer "F.Cu")
		(net "PE_CLK100M_DR11_1_N")
	)
	(segment
		(start 28.575 -343.264998)
		(end 28.447238 -343.39276)
		(width 0.174752)
		(layer "F.Cu")
		(net "PE_CLK100M_DR11_1_N")
	)
	(segment
		(start 30.419294 -337.499706)
		(end 30.238446 -337.499706)
		(width 0.174752)
		(layer "F.Cu")
		(net "PE_CLK100M_DR11_1_N")
	)
	(segment
		(start 28.945586 -338.973414)
		(end 28.575 -339.344)
		(width 0.174752)
		(layer "F.Cu")
		(net "PE_CLK100M_DR11_1_N")
	)
	(segment
		(start 73.279508 -334.847946)
		(end 33.071308 -334.847946)
		(width 0.174752)
		(layer "F.Cu")
		(net "PE_CLK100M_DR11_1_N")
	)
	(segment
		(start 29.49702 -338.42198)
		(end 29.316426 -338.42198)
		(width 0.174752)
		(layer "F.Cu")
		(net "PE_CLK100M_DR11_1_N")
	)
	(segment
		(start 28.447238 -346.000832)
		(end 28.447238 -346.525088)
		(width 0.174752)
		(layer "F.Cu")
		(net "PE_CLK100M_DR11_1_N")
	)
	(segment
		(start 29.86786 -338.05114)
		(end 29.49702 -338.42198)
		(width 0.174752)
		(layer "F.Cu")
		(net "PE_CLK100M_DR11_1_N")
	)
	(segment
		(start 28.945586 -338.792566)
		(end 28.945586 -338.973414)
		(width 0.174752)
		(layer "F.Cu")
		(net "PE_CLK100M_DR11_1_N")
	)
	(segment
		(start 28.575 -344.044778)
		(end 28.575 -344.569034)
		(width 0.174752)
		(layer "F.Cu")
		(net "PE_CLK100M_DR11_1_N")
	)
	(segment
		(start 23.966678 -350.009968)
		(end 22.800056 -350.009968)
		(width 0.174752)
		(layer "F.Cu")
		(net "PE_CLK100M_DR11_1_N")
	)
	(segment
		(start 29.316426 -338.42198)
		(end 28.945586 -338.792566)
		(width 0.174752)
		(layer "F.Cu")
		(net "PE_CLK100M_DR11_1_N")
	)
	(segment
		(start 24.214328 -350.257618)
		(end 23.966678 -350.009968)
		(width 0.174752)
		(layer "F.Cu")
		(net "PE_CLK100M_DR11_1_N")
	)
	(segment
		(start 27.440382 -350.257618)
		(end 24.214328 -350.257618)
		(width 0.174752)
		(layer "F.Cu")
		(net "PE_CLK100M_DR11_1_N")
	)
	(segment
		(start 28.447238 -345.221052)
		(end 28.575 -345.348814)
		(width 0.174752)
		(layer "F.Cu")
		(net "PE_CLK100M_DR11_1_N")
	)
	(segment
		(start 33.071308 -334.847946)
		(end 32.131 -335.788)
		(width 0.174752)
		(layer "F.Cu")
		(net "PE_CLK100M_DR11_1_N")
	)
	(segment
		(start 28.447238 -343.917016)
		(end 28.575 -344.044778)
		(width 0.174752)
		(layer "F.Cu")
		(net "PE_CLK100M_DR11_1_N")
	)
	(segment
		(start 29.86786 -337.870546)
		(end 29.86786 -338.05114)
		(width 0.174752)
		(layer "F.Cu")
		(net "PE_CLK100M_DR11_1_N")
	)
	(segment
		(start 86.8426 -314.6171)
		(end 86.8426 -315.061854)
		(width 0.174752)
		(layer "F.Cu")
		(net "PE_CLK100M_DR11_1_N")
	)
	(segment
		(start 85.673946 -316.230508)
		(end 85.673946 -322.453508)
		(width 0.174752)
		(layer "F.Cu")
		(net "PE_CLK100M_DR11_1_N")
	)
	(segment
		(start 32.131 -335.788)
		(end 30.419294 -337.499706)
		(width 0.174752)
		(layer "F.Cu")
		(net "PE_CLK100M_DR11_1_N")
	)
	(segment
		(start 28.447238 -343.39276)
		(end 28.447238 -343.917016)
		(width 0.174752)
		(layer "F.Cu")
		(net "PE_CLK100M_DR11_1_N")
	)
	(segment
		(start 28.447238 -344.696796)
		(end 28.447238 -345.221052)
		(width 0.174752)
		(layer "F.Cu")
		(net "PE_CLK100M_DR11_1_N")
	)
	(segment
		(start 28.447238 -346.525088)
		(end 28.575 -346.65285)
		(width 0.174752)
		(layer "F.Cu")
		(net "PE_CLK100M_DR11_1_N")
	)
	(segment
		(start 28.575 -345.87307)
		(end 28.447238 -346.000832)
		(width 0.174752)
		(layer "F.Cu")
		(net "PE_CLK100M_DR11_1_N")
	)
	(segment
		(start 33.528 -442.417708)
		(end 33.528 -442.941964)
		(width 0.174752)
		(layer "F.Cu")
		(net "PE_CLK100M_DR10_2_P")
	)
	(segment
		(start 32.630872 -445.143128)
		(end 32.004508 -445.143128)
		(width 0.174752)
		(layer "F.Cu")
		(net "PE_CLK100M_DR10_2_P")
	)
	(segment
		(start 33.655762 -440.98591)
		(end 33.528 -441.113672)
		(width 0.174752)
		(layer "F.Cu")
		(net "PE_CLK100M_DR10_2_P")
	)
	(segment
		(start 86.487 -422.7195)
		(end 86.791546 -422.414954)
		(width 0.174752)
		(layer "F.Cu")
		(net "PE_CLK100M_DR10_2_P")
	)
	(segment
		(start 34.998152 -434.966872)
		(end 34.998152 -435.147466)
		(width 0.174752)
		(layer "F.Cu")
		(net "PE_CLK100M_DR10_2_P")
	)
	(segment
		(start 18.188178 -445.162178)
		(end 17.526 -445.162178)
		(width 0.174752)
		(layer "F.Cu")
		(net "PE_CLK100M_DR10_2_P")
	)
	(segment
		(start 19.61007 -445.410082)
		(end 18.436082 -445.410082)
		(width 0.174752)
		(layer "F.Cu")
		(net "PE_CLK100M_DR10_2_P")
	)
	(segment
		(start 33.655762 -443.069726)
		(end 33.655762 -443.593982)
		(width 0.174752)
		(layer "F.Cu")
		(net "PE_CLK100M_DR10_2_P")
	)
	(segment
		(start 35.368992 -434.596032)
		(end 34.998152 -434.966872)
		(width 0.174752)
		(layer "F.Cu")
		(net "PE_CLK100M_DR10_2_P")
	)
	(segment
		(start 33.528 -441.113672)
		(end 33.528 -441.637928)
		(width 0.174752)
		(layer "F.Cu")
		(net "PE_CLK100M_DR10_2_P")
	)
	(segment
		(start 33.655762 -442.289946)
		(end 33.528 -442.417708)
		(width 0.174752)
		(layer "F.Cu")
		(net "PE_CLK100M_DR10_2_P")
	)
	(segment
		(start 17.526 -445.162178)
		(end 17.272 -445.416178)
		(width 0.174752)
		(layer "F.Cu")
		(net "PE_CLK100M_DR10_2_P")
	)
	(segment
		(start 33.655762 -440.461654)
		(end 33.655762 -440.98591)
		(width 0.174752)
		(layer "F.Cu")
		(net "PE_CLK100M_DR10_2_P")
	)
	(segment
		(start 86.791546 -422.414954)
		(end 86.791546 -421.995092)
		(width 0.174752)
		(layer "F.Cu")
		(net "PE_CLK100M_DR10_2_P")
	)
	(segment
		(start 33.528 -436.43677)
		(end 33.528 -440.333892)
		(width 0.174752)
		(layer "F.Cu")
		(net "PE_CLK100M_DR10_2_P")
	)
	(segment
		(start 34.076132 -435.888892)
		(end 33.528 -436.43677)
		(width 0.174752)
		(layer "F.Cu")
		(net "PE_CLK100M_DR10_2_P")
	)
	(segment
		(start 86.054946 -418.718492)
		(end 84.531454 -417.195)
		(width 0.174752)
		(layer "F.Cu")
		(net "PE_CLK100M_DR10_2_P")
	)
	(segment
		(start 33.528 -444.246)
		(end 32.630872 -445.143128)
		(width 0.174752)
		(layer "F.Cu")
		(net "PE_CLK100M_DR10_2_P")
	)
	(segment
		(start 35.920426 -434.225446)
		(end 35.549586 -434.596032)
		(width 0.174752)
		(layer "F.Cu")
		(net "PE_CLK100M_DR10_2_P")
	)
	(segment
		(start 34.627566 -435.518306)
		(end 34.446718 -435.518306)
		(width 0.174752)
		(layer "F.Cu")
		(net "PE_CLK100M_DR10_2_P")
	)
	(segment
		(start 34.446718 -435.518306)
		(end 34.076132 -435.888892)
		(width 0.174752)
		(layer "F.Cu")
		(net "PE_CLK100M_DR10_2_P")
	)
	(segment
		(start 33.528 -442.941964)
		(end 33.655762 -443.069726)
		(width 0.174752)
		(layer "F.Cu")
		(net "PE_CLK100M_DR10_2_P")
	)
	(segment
		(start 33.528 -440.333892)
		(end 33.655762 -440.461654)
		(width 0.174752)
		(layer "F.Cu")
		(net "PE_CLK100M_DR10_2_P")
	)
	(segment
		(start 52.770024 -417.195)
		(end 35.920426 -434.044598)
		(width 0.174752)
		(layer "F.Cu")
		(net "PE_CLK100M_DR10_2_P")
	)
	(segment
		(start 33.655762 -443.593982)
		(end 33.528 -443.721744)
		(width 0.174752)
		(layer "F.Cu")
		(net "PE_CLK100M_DR10_2_P")
	)
	(segment
		(start 86.791546 -421.995092)
		(end 86.054946 -421.258492)
		(width 0.174752)
		(layer "F.Cu")
		(net "PE_CLK100M_DR10_2_P")
	)
	(segment
		(start 34.998152 -435.147466)
		(end 34.627566 -435.518306)
		(width 0.174752)
		(layer "F.Cu")
		(net "PE_CLK100M_DR10_2_P")
	)
	(segment
		(start 86.054946 -421.258492)
		(end 86.054946 -418.718492)
		(width 0.174752)
		(layer "F.Cu")
		(net "PE_CLK100M_DR10_2_P")
	)
	(segment
		(start 33.528 -441.637928)
		(end 33.655762 -441.76569)
		(width 0.174752)
		(layer "F.Cu")
		(net "PE_CLK100M_DR10_2_P")
	)
	(segment
		(start 84.531454 -417.195)
		(end 52.770024 -417.195)
		(width 0.174752)
		(layer "F.Cu")
		(net "PE_CLK100M_DR10_2_P")
	)
	(segment
		(start 33.655762 -441.76569)
		(end 33.655762 -442.289946)
		(width 0.174752)
		(layer "F.Cu")
		(net "PE_CLK100M_DR10_2_P")
	)
	(segment
		(start 18.436082 -445.410082)
		(end 18.188178 -445.162178)
		(width 0.174752)
		(layer "F.Cu")
		(net "PE_CLK100M_DR10_2_P")
	)
	(segment
		(start 32.004508 -445.143128)
		(end 31.75 -445.397636)
		(width 0.174752)
		(layer "F.Cu")
		(net "PE_CLK100M_DR10_2_P")
	)
	(segment
		(start 33.528 -443.721744)
		(end 33.528 -444.246)
		(width 0.174752)
		(layer "F.Cu")
		(net "PE_CLK100M_DR10_2_P")
	)
	(segment
		(start 35.549586 -434.596032)
		(end 35.368992 -434.596032)
		(width 0.174752)
		(layer "F.Cu")
		(net "PE_CLK100M_DR10_2_P")
	)
	(segment
		(start 35.920426 -434.044598)
		(end 35.920426 -434.225446)
		(width 0.174752)
		(layer "F.Cu")
		(net "PE_CLK100M_DR10_2_P")
	)
	(via
		(at 31.75 -445.397636)
		(size 0.508)
		(drill 0.254)
		(layers "F.Cu" "B.Cu")
		(net "PE_CLK100M_DR10_2_P")
	)
	(via
		(at 17.272 -445.416178)
		(size 0.508)
		(drill 0.254)
		(layers "F.Cu" "B.Cu")
		(net "PE_CLK100M_DR10_2_P")
	)
	(segment
		(start 17.544542 -445.143636)
		(end 31.496 -445.143636)
		(width 0.174752)
		(layer "B.Cu")
		(net "PE_CLK100M_DR10_2_P")
	)
	(segment
		(start 17.272 -445.416178)
		(end 17.544542 -445.143636)
		(width 0.174752)
		(layer "B.Cu")
		(net "PE_CLK100M_DR10_2_P")
	)
	(segment
		(start 31.496 -445.143636)
		(end 31.75 -445.397636)
		(width 0.174752)
		(layer "B.Cu")
		(net "PE_CLK100M_DR10_2_P")
	)
	(segment
		(start 32.50438 -444.838074)
		(end 32.003238 -444.838074)
		(width 0.174752)
		(layer "F.Cu")
		(net "PE_CLK100M_DR10_2_N")
	)
	(segment
		(start 19.61007 -444.609982)
		(end 18.408142 -444.609982)
		(width 0.174752)
		(layer "F.Cu")
		(net "PE_CLK100M_DR10_2_N")
	)
	(segment
		(start 33.222946 -436.310278)
		(end 33.222946 -444.119508)
		(width 0.174752)
		(layer "F.Cu")
		(net "PE_CLK100M_DR10_2_N")
	)
	(segment
		(start 17.525746 -444.857124)
		(end 17.272 -444.603378)
		(width 0.174752)
		(layer "F.Cu")
		(net "PE_CLK100M_DR10_2_N")
	)
	(segment
		(start 84.657946 -416.889946)
		(end 52.643532 -416.889946)
		(width 0.174752)
		(layer "F.Cu")
		(net "PE_CLK100M_DR10_2_N")
	)
	(segment
		(start 33.222946 -444.119508)
		(end 32.50438 -444.838074)
		(width 0.174752)
		(layer "F.Cu")
		(net "PE_CLK100M_DR10_2_N")
	)
	(segment
		(start 32.003238 -444.838074)
		(end 31.75 -444.584836)
		(width 0.174752)
		(layer "F.Cu")
		(net "PE_CLK100M_DR10_2_N")
	)
	(segment
		(start 18.408142 -444.609982)
		(end 18.161 -444.857124)
		(width 0.174752)
		(layer "F.Cu")
		(net "PE_CLK100M_DR10_2_N")
	)
	(segment
		(start 52.554124 -416.979354)
		(end 52.554124 -416.9791)
		(width 0.174752)
		(layer "F.Cu")
		(net "PE_CLK100M_DR10_2_N")
	)
	(segment
		(start 86.36 -418.592)
		(end 84.657946 -416.889946)
		(width 0.174752)
		(layer "F.Cu")
		(net "PE_CLK100M_DR10_2_N")
	)
	(segment
		(start 87.0966 -421.8686)
		(end 86.36 -421.132)
		(width 0.174752)
		(layer "F.Cu")
		(net "PE_CLK100M_DR10_2_N")
	)
	(segment
		(start 87.503 -422.7195)
		(end 87.0966 -422.3131)
		(width 0.174752)
		(layer "F.Cu")
		(net "PE_CLK100M_DR10_2_N")
	)
	(segment
		(start 86.36 -421.132)
		(end 86.36 -418.592)
		(width 0.174752)
		(layer "F.Cu")
		(net "PE_CLK100M_DR10_2_N")
	)
	(segment
		(start 52.554124 -416.9791)
		(end 33.222946 -436.310278)
		(width 0.174752)
		(layer "F.Cu")
		(net "PE_CLK100M_DR10_2_N")
	)
	(segment
		(start 52.643532 -416.889946)
		(end 52.554124 -416.979354)
		(width 0.174752)
		(layer "F.Cu")
		(net "PE_CLK100M_DR10_2_N")
	)
	(segment
		(start 87.0966 -422.3131)
		(end 87.0966 -421.8686)
		(width 0.174752)
		(layer "F.Cu")
		(net "PE_CLK100M_DR10_2_N")
	)
	(segment
		(start 18.161 -444.857124)
		(end 17.525746 -444.857124)
		(width 0.174752)
		(layer "F.Cu")
		(net "PE_CLK100M_DR10_2_N")
	)
	(via
		(at 17.272 -444.603378)
		(size 0.508)
		(drill 0.254)
		(layers "F.Cu" "B.Cu")
		(net "PE_CLK100M_DR10_2_N")
	)
	(via
		(at 31.75 -444.584836)
		(size 0.508)
		(drill 0.254)
		(layers "F.Cu" "B.Cu")
		(net "PE_CLK100M_DR10_2_N")
	)
	(segment
		(start 31.496254 -444.838582)
		(end 31.75 -444.584836)
		(width 0.174752)
		(layer "B.Cu")
		(net "PE_CLK100M_DR10_2_N")
	)
	(segment
		(start 17.507204 -444.838582)
		(end 31.496254 -444.838582)
		(width 0.174752)
		(layer "B.Cu")
		(net "PE_CLK100M_DR10_2_N")
	)
	(segment
		(start 17.272 -444.603378)
		(end 17.507204 -444.838582)
		(width 0.174752)
		(layer "B.Cu")
		(net "PE_CLK100M_DR10_2_N")
	)
	(segment
		(start 28.753054 -452.230236)
		(end 28.753054 -452.754492)
		(width 0.174752)
		(layer "F.Cu")
		(net "PE_CLK100M_DR10_1_P")
	)
	(segment
		(start 28.753054 -444.218568)
		(end 28.880816 -444.34633)
		(width 0.174752)
		(layer "F.Cu")
		(net "PE_CLK100M_DR10_1_P")
	)
	(segment
		(start 91.821 -420.624)
		(end 91.821 -415.975546)
		(width 0.174752)
		(layer "F.Cu")
		(net "PE_CLK100M_DR10_1_P")
	)
	(segment
		(start 23.882604 -453.810116)
		(end 22.800056 -453.810116)
		(width 0.174752)
		(layer "F.Cu")
		(net "PE_CLK100M_DR10_1_P")
	)
	(segment
		(start 28.753054 -450.9262)
		(end 28.753054 -451.450456)
		(width 0.174752)
		(layer "F.Cu")
		(net "PE_CLK100M_DR10_1_P")
	)
	(segment
		(start 90.652346 -422.364154)
		(end 90.652346 -421.792654)
		(width 0.174752)
		(layer "F.Cu")
		(net "PE_CLK100M_DR10_1_P")
	)
	(segment
		(start 28.880816 -444.34633)
		(end 28.880816 -444.870586)
		(width 0.174752)
		(layer "F.Cu")
		(net "PE_CLK100M_DR10_1_P")
	)
	(segment
		(start 28.880816 -452.102474)
		(end 28.753054 -452.230236)
		(width 0.174752)
		(layer "F.Cu")
		(net "PE_CLK100M_DR10_1_P")
	)
	(segment
		(start 28.880816 -448.970146)
		(end 28.880816 -449.494402)
		(width 0.174752)
		(layer "F.Cu")
		(net "PE_CLK100M_DR10_1_P")
	)
	(segment
		(start 28.753054 -450.14642)
		(end 28.880816 -450.274182)
		(width 0.174752)
		(layer "F.Cu")
		(net "PE_CLK100M_DR10_1_P")
	)
	(segment
		(start 90.297 -422.7195)
		(end 90.652346 -422.364154)
		(width 0.174752)
		(layer "F.Cu")
		(net "PE_CLK100M_DR10_1_P")
	)
	(segment
		(start 28.753054 -436.879492)
		(end 28.753054 -444.218568)
		(width 0.174752)
		(layer "F.Cu")
		(net "PE_CLK100M_DR10_1_P")
	)
	(segment
		(start 24.13 -453.56272)
		(end 23.882604 -453.810116)
		(width 0.174752)
		(layer "F.Cu")
		(net "PE_CLK100M_DR10_1_P")
	)
	(segment
		(start 28.880816 -449.494402)
		(end 28.753054 -449.622164)
		(width 0.174752)
		(layer "F.Cu")
		(net "PE_CLK100M_DR10_1_P")
	)
	(segment
		(start 91.821 -415.975546)
		(end 89.230454 -413.385)
		(width 0.174752)
		(layer "F.Cu")
		(net "PE_CLK100M_DR10_1_P")
	)
	(segment
		(start 28.753054 -446.302384)
		(end 28.753054 -448.842384)
		(width 0.174752)
		(layer "F.Cu")
		(net "PE_CLK100M_DR10_1_P")
	)
	(segment
		(start 89.230454 -413.385)
		(end 52.247546 -413.385)
		(width 0.174752)
		(layer "F.Cu")
		(net "PE_CLK100M_DR10_1_P")
	)
	(segment
		(start 28.880816 -451.578218)
		(end 28.880816 -452.102474)
		(width 0.174752)
		(layer "F.Cu")
		(net "PE_CLK100M_DR10_1_P")
	)
	(segment
		(start 28.880816 -446.174622)
		(end 28.753054 -446.302384)
		(width 0.174752)
		(layer "F.Cu")
		(net "PE_CLK100M_DR10_1_P")
	)
	(segment
		(start 28.880816 -444.870586)
		(end 28.753054 -444.998348)
		(width 0.174752)
		(layer "F.Cu")
		(net "PE_CLK100M_DR10_1_P")
	)
	(segment
		(start 28.880816 -450.798438)
		(end 28.753054 -450.9262)
		(width 0.174752)
		(layer "F.Cu")
		(net "PE_CLK100M_DR10_1_P")
	)
	(segment
		(start 28.753054 -444.998348)
		(end 28.753054 -445.522604)
		(width 0.174752)
		(layer "F.Cu")
		(net "PE_CLK100M_DR10_1_P")
	)
	(segment
		(start 28.880816 -450.274182)
		(end 28.880816 -450.798438)
		(width 0.174752)
		(layer "F.Cu")
		(net "PE_CLK100M_DR10_1_P")
	)
	(segment
		(start 28.753054 -445.522604)
		(end 28.880816 -445.650366)
		(width 0.174752)
		(layer "F.Cu")
		(net "PE_CLK100M_DR10_1_P")
	)
	(segment
		(start 28.753054 -448.842384)
		(end 28.880816 -448.970146)
		(width 0.174752)
		(layer "F.Cu")
		(net "PE_CLK100M_DR10_1_P")
	)
	(segment
		(start 52.247546 -413.385)
		(end 28.753054 -436.879492)
		(width 0.174752)
		(layer "F.Cu")
		(net "PE_CLK100M_DR10_1_P")
	)
	(segment
		(start 90.652346 -421.792654)
		(end 91.821 -420.624)
		(width 0.174752)
		(layer "F.Cu")
		(net "PE_CLK100M_DR10_1_P")
	)
	(segment
		(start 28.753054 -449.622164)
		(end 28.753054 -450.14642)
		(width 0.174752)
		(layer "F.Cu")
		(net "PE_CLK100M_DR10_1_P")
	)
	(segment
		(start 27.944826 -453.56272)
		(end 24.13 -453.56272)
		(width 0.174752)
		(layer "F.Cu")
		(net "PE_CLK100M_DR10_1_P")
	)
	(segment
		(start 28.880816 -445.650366)
		(end 28.880816 -446.174622)
		(width 0.174752)
		(layer "F.Cu")
		(net "PE_CLK100M_DR10_1_P")
	)
	(segment
		(start 28.753054 -451.450456)
		(end 28.880816 -451.578218)
		(width 0.174752)
		(layer "F.Cu")
		(net "PE_CLK100M_DR10_1_P")
	)
	(segment
		(start 28.753054 -452.754492)
		(end 27.944826 -453.56272)
		(width 0.174752)
		(layer "F.Cu")
		(net "PE_CLK100M_DR10_1_P")
	)
	(segment
		(start 92.126054 -415.849054)
		(end 89.356946 -413.079946)
		(width 0.174752)
		(layer "F.Cu")
		(net "PE_CLK100M_DR10_1_N")
	)
	(segment
		(start 28.448 -436.753)
		(end 28.448 -452.628)
		(width 0.174752)
		(layer "F.Cu")
		(net "PE_CLK100M_DR10_1_N")
	)
	(segment
		(start 89.356946 -413.079946)
		(end 52.121054 -413.079946)
		(width 0.174752)
		(layer "F.Cu")
		(net "PE_CLK100M_DR10_1_N")
	)
	(segment
		(start 91.313 -422.7195)
		(end 90.9574 -422.3639)
		(width 0.174752)
		(layer "F.Cu")
		(net "PE_CLK100M_DR10_1_N")
	)
	(segment
		(start 90.9574 -422.3639)
		(end 90.9574 -421.919146)
		(width 0.174752)
		(layer "F.Cu")
		(net "PE_CLK100M_DR10_1_N")
	)
	(segment
		(start 92.126054 -420.750492)
		(end 92.126054 -415.849054)
		(width 0.174752)
		(layer "F.Cu")
		(net "PE_CLK100M_DR10_1_N")
	)
	(segment
		(start 90.9574 -421.919146)
		(end 92.126054 -420.750492)
		(width 0.174752)
		(layer "F.Cu")
		(net "PE_CLK100M_DR10_1_N")
	)
	(segment
		(start 24.12365 -453.257666)
		(end 23.876 -453.010016)
		(width 0.174752)
		(layer "F.Cu")
		(net "PE_CLK100M_DR10_1_N")
	)
	(segment
		(start 27.818334 -453.257666)
		(end 24.12365 -453.257666)
		(width 0.174752)
		(layer "F.Cu")
		(net "PE_CLK100M_DR10_1_N")
	)
	(segment
		(start 23.876 -453.010016)
		(end 22.800056 -453.010016)
		(width 0.174752)
		(layer "F.Cu")
		(net "PE_CLK100M_DR10_1_N")
	)
	(segment
		(start 52.121054 -413.079946)
		(end 28.448 -436.753)
		(width 0.174752)
		(layer "F.Cu")
		(net "PE_CLK100M_DR10_1_N")
	)
	(segment
		(start 28.448 -452.628)
		(end 27.818334 -453.257666)
		(width 0.174752)
		(layer "F.Cu")
		(net "PE_CLK100M_DR10_1_N")
	)
	(segment
		(start 129.209546 -306.07)
		(end 104.800654 -306.07)
		(width 0.174752)
		(layer "F.Cu")
		(net "PE_CLK100M_DR1_2_P")
	)
	(segment
		(start 229.564946 -355.929946)
		(end 179.069492 -355.929946)
		(width 0.174752)
		(layer "F.Cu")
		(net "PE_CLK100M_DR1_2_P")
	)
	(segment
		(start 233.386884 -370.392198)
		(end 233.640884 -370.138198)
		(width 0.174752)
		(layer "F.Cu")
		(net "PE_CLK100M_DR1_2_P")
	)
	(segment
		(start 228.473 -369.590066)
		(end 227.389944 -369.590066)
		(width 0.174752)
		(layer "F.Cu")
		(net "PE_CLK100M_DR1_2_P")
	)
	(segment
		(start 230.16083 -369.579652)
		(end 229.891336 -369.849146)
		(width 0.174752)
		(layer "F.Cu")
		(net "PE_CLK100M_DR1_2_P")
	)
	(segment
		(start 229.891336 -369.849146)
		(end 228.73208 -369.849146)
		(width 0.174752)
		(layer "F.Cu")
		(net "PE_CLK100M_DR1_2_P")
	)
	(segment
		(start 230.16083 -369.043966)
		(end 230.16083 -369.579652)
		(width 0.174752)
		(layer "F.Cu")
		(net "PE_CLK100M_DR1_2_P")
	)
	(segment
		(start 235.712 -362.077)
		(end 229.564946 -355.929946)
		(width 0.174752)
		(layer "F.Cu")
		(net "PE_CLK100M_DR1_2_P")
	)
	(segment
		(start 235.712 -369.363498)
		(end 235.712 -362.077)
		(width 0.174752)
		(layer "F.Cu")
		(net "PE_CLK100M_DR1_2_P")
	)
	(segment
		(start 179.069492 -355.929946)
		(end 129.209546 -306.07)
		(width 0.174752)
		(layer "F.Cu")
		(net "PE_CLK100M_DR1_2_P")
	)
	(segment
		(start 233.640884 -370.138198)
		(end 234.9373 -370.138198)
		(width 0.174752)
		(layer "F.Cu")
		(net "PE_CLK100M_DR1_2_P")
	)
	(segment
		(start 229.907084 -368.79022)
		(end 230.16083 -369.043966)
		(width 0.174752)
		(layer "F.Cu")
		(net "PE_CLK100M_DR1_2_P")
	)
	(segment
		(start 103.441246 -307.085746)
		(end 103.0605 -306.705)
		(width 0.174752)
		(layer "F.Cu")
		(net "PE_CLK100M_DR1_2_P")
	)
	(segment
		(start 103.784908 -307.085746)
		(end 103.441246 -307.085746)
		(width 0.174752)
		(layer "F.Cu")
		(net "PE_CLK100M_DR1_2_P")
	)
	(segment
		(start 228.73208 -369.849146)
		(end 228.473 -369.590066)
		(width 0.174752)
		(layer "F.Cu")
		(net "PE_CLK100M_DR1_2_P")
	)
	(segment
		(start 234.9373 -370.138198)
		(end 235.712 -369.363498)
		(width 0.174752)
		(layer "F.Cu")
		(net "PE_CLK100M_DR1_2_P")
	)
	(segment
		(start 104.800654 -306.07)
		(end 103.784908 -307.085746)
		(width 0.174752)
		(layer "F.Cu")
		(net "PE_CLK100M_DR1_2_P")
	)
	(via
		(at 229.907084 -368.79022)
		(size 0.508)
		(drill 0.254)
		(layers "F.Cu" "B.Cu")
		(net "PE_CLK100M_DR1_2_P")
	)
	(via
		(at 233.386884 -370.392198)
		(size 0.508)
		(drill 0.254)
		(layers "F.Cu" "B.Cu")
		(net "PE_CLK100M_DR1_2_P")
	)
	(segment
		(start 230.16083 -369.705636)
		(end 230.16083 -369.043966)
		(width 0.174752)
		(layer "B.Cu")
		(net "PE_CLK100M_DR1_2_P")
	)
	(segment
		(start 233.386884 -370.392198)
		(end 233.132884 -370.138198)
		(width 0.174752)
		(layer "B.Cu")
		(net "PE_CLK100M_DR1_2_P")
	)
	(segment
		(start 233.132884 -370.138198)
		(end 230.593392 -370.138198)
		(width 0.174752)
		(layer "B.Cu")
		(net "PE_CLK100M_DR1_2_P")
	)
	(segment
		(start 230.593392 -370.138198)
		(end 230.16083 -369.705636)
		(width 0.174752)
		(layer "B.Cu")
		(net "PE_CLK100M_DR1_2_P")
	)
	(segment
		(start 230.16083 -369.043966)
		(end 229.907084 -368.79022)
		(width 0.174752)
		(layer "B.Cu")
		(net "PE_CLK100M_DR1_2_P")
	)
	(segment
		(start 216.257632 -356.235)
		(end 216.12987 -356.362762)
		(width 0.174752)
		(layer "F.Cu")
		(net "PE_CLK100M_DR1_2_N")
	)
	(segment
		(start 212.320378 -356.362762)
		(end 211.796122 -356.362762)
		(width 0.174752)
		(layer "F.Cu")
		(net "PE_CLK100M_DR1_2_N")
	)
	(segment
		(start 206.392526 -356.362762)
		(end 205.86827 -356.362762)
		(width 0.174752)
		(layer "F.Cu")
		(net "PE_CLK100M_DR1_2_N")
	)
	(segment
		(start 228.71557 -370.1542)
		(end 228.479604 -370.390166)
		(width 0.174752)
		(layer "F.Cu")
		(net "PE_CLK100M_DR1_2_N")
	)
	(segment
		(start 216.781888 -356.235)
		(end 216.257632 -356.235)
		(width 0.174752)
		(layer "F.Cu")
		(net "PE_CLK100M_DR1_2_N")
	)
	(segment
		(start 220.881448 -356.235)
		(end 220.753686 -356.362762)
		(width 0.174752)
		(layer "F.Cu")
		(net "PE_CLK100M_DR1_2_N")
	)
	(segment
		(start 129.083054 -306.375054)
		(end 104.927146 -306.375054)
		(width 0.174752)
		(layer "F.Cu")
		(net "PE_CLK100M_DR1_2_N")
	)
	(segment
		(start 211.016342 -356.362762)
		(end 210.492086 -356.362762)
		(width 0.174752)
		(layer "F.Cu")
		(net "PE_CLK100M_DR1_2_N")
	)
	(segment
		(start 221.533466 -356.362762)
		(end 221.405704 -356.235)
		(width 0.174752)
		(layer "F.Cu")
		(net "PE_CLK100M_DR1_2_N")
	)
	(segment
		(start 209.712306 -356.362762)
		(end 209.18805 -356.362762)
		(width 0.174752)
		(layer "F.Cu")
		(net "PE_CLK100M_DR1_2_N")
	)
	(segment
		(start 215.605614 -356.362762)
		(end 215.477852 -356.235)
		(width 0.174752)
		(layer "F.Cu")
		(net "PE_CLK100M_DR1_2_N")
	)
	(segment
		(start 233.64063 -369.833144)
		(end 234.810808 -369.833144)
		(width 0.174752)
		(layer "F.Cu")
		(net "PE_CLK100M_DR1_2_N")
	)
	(segment
		(start 104.927146 -306.375054)
		(end 103.9114 -307.3908)
		(width 0.174752)
		(layer "F.Cu")
		(net "PE_CLK100M_DR1_2_N")
	)
	(segment
		(start 103.3907 -307.3908)
		(end 103.0605 -307.721)
		(width 0.174752)
		(layer "F.Cu")
		(net "PE_CLK100M_DR1_2_N")
	)
	(segment
		(start 211.144104 -356.235)
		(end 211.016342 -356.362762)
		(width 0.174752)
		(layer "F.Cu")
		(net "PE_CLK100M_DR1_2_N")
	)
	(segment
		(start 222.185484 -356.235)
		(end 222.057722 -356.362762)
		(width 0.174752)
		(layer "F.Cu")
		(net "PE_CLK100M_DR1_2_N")
	)
	(segment
		(start 220.753686 -356.362762)
		(end 220.22943 -356.362762)
		(width 0.174752)
		(layer "F.Cu")
		(net "PE_CLK100M_DR1_2_N")
	)
	(segment
		(start 217.561668 -356.235)
		(end 217.433906 -356.362762)
		(width 0.174752)
		(layer "F.Cu")
		(net "PE_CLK100M_DR1_2_N")
	)
	(segment
		(start 103.9114 -307.3908)
		(end 103.3907 -307.3908)
		(width 0.174752)
		(layer "F.Cu")
		(net "PE_CLK100M_DR1_2_N")
	)
	(segment
		(start 212.44814 -356.235)
		(end 212.320378 -356.362762)
		(width 0.174752)
		(layer "F.Cu")
		(net "PE_CLK100M_DR1_2_N")
	)
	(segment
		(start 209.840068 -356.235)
		(end 209.712306 -356.362762)
		(width 0.174752)
		(layer "F.Cu")
		(net "PE_CLK100M_DR1_2_N")
	)
	(segment
		(start 221.405704 -356.235)
		(end 220.881448 -356.235)
		(width 0.174752)
		(layer "F.Cu")
		(net "PE_CLK100M_DR1_2_N")
	)
	(segment
		(start 205.740508 -356.235)
		(end 205.216252 -356.235)
		(width 0.174752)
		(layer "F.Cu")
		(net "PE_CLK100M_DR1_2_N")
	)
	(segment
		(start 216.90965 -356.362762)
		(end 216.781888 -356.235)
		(width 0.174752)
		(layer "F.Cu")
		(net "PE_CLK100M_DR1_2_N")
	)
	(segment
		(start 215.477852 -356.235)
		(end 212.44814 -356.235)
		(width 0.174752)
		(layer "F.Cu")
		(net "PE_CLK100M_DR1_2_N")
	)
	(segment
		(start 220.101668 -356.235)
		(end 217.561668 -356.235)
		(width 0.174752)
		(layer "F.Cu")
		(net "PE_CLK100M_DR1_2_N")
	)
	(segment
		(start 223.48952 -356.235)
		(end 223.361758 -356.362762)
		(width 0.174752)
		(layer "F.Cu")
		(net "PE_CLK100M_DR1_2_N")
	)
	(segment
		(start 217.433906 -356.362762)
		(end 216.90965 -356.362762)
		(width 0.174752)
		(layer "F.Cu")
		(net "PE_CLK100M_DR1_2_N")
	)
	(segment
		(start 230.017828 -370.1542)
		(end 228.71557 -370.1542)
		(width 0.174752)
		(layer "F.Cu")
		(net "PE_CLK100M_DR1_2_N")
	)
	(segment
		(start 222.057722 -356.362762)
		(end 221.533466 -356.362762)
		(width 0.174752)
		(layer "F.Cu")
		(net "PE_CLK100M_DR1_2_N")
	)
	(segment
		(start 211.796122 -356.362762)
		(end 211.66836 -356.235)
		(width 0.174752)
		(layer "F.Cu")
		(net "PE_CLK100M_DR1_2_N")
	)
	(segment
		(start 230.719884 -368.79022)
		(end 230.465884 -369.04422)
		(width 0.174752)
		(layer "F.Cu")
		(net "PE_CLK100M_DR1_2_N")
	)
	(segment
		(start 233.386884 -369.579398)
		(end 233.64063 -369.833144)
		(width 0.174752)
		(layer "F.Cu")
		(net "PE_CLK100M_DR1_2_N")
	)
	(segment
		(start 234.810808 -369.833144)
		(end 235.406946 -369.237006)
		(width 0.174752)
		(layer "F.Cu")
		(net "PE_CLK100M_DR1_2_N")
	)
	(segment
		(start 222.70974 -356.235)
		(end 222.185484 -356.235)
		(width 0.174752)
		(layer "F.Cu")
		(net "PE_CLK100M_DR1_2_N")
	)
	(segment
		(start 216.12987 -356.362762)
		(end 215.605614 -356.362762)
		(width 0.174752)
		(layer "F.Cu")
		(net "PE_CLK100M_DR1_2_N")
	)
	(segment
		(start 223.361758 -356.362762)
		(end 222.837502 -356.362762)
		(width 0.174752)
		(layer "F.Cu")
		(net "PE_CLK100M_DR1_2_N")
	)
	(segment
		(start 209.060288 -356.235)
		(end 206.520288 -356.235)
		(width 0.174752)
		(layer "F.Cu")
		(net "PE_CLK100M_DR1_2_N")
	)
	(segment
		(start 229.438454 -356.235)
		(end 223.48952 -356.235)
		(width 0.174752)
		(layer "F.Cu")
		(net "PE_CLK100M_DR1_2_N")
	)
	(segment
		(start 209.18805 -356.362762)
		(end 209.060288 -356.235)
		(width 0.174752)
		(layer "F.Cu")
		(net "PE_CLK100M_DR1_2_N")
	)
	(segment
		(start 222.837502 -356.362762)
		(end 222.70974 -356.235)
		(width 0.174752)
		(layer "F.Cu")
		(net "PE_CLK100M_DR1_2_N")
	)
	(segment
		(start 204.564234 -356.362762)
		(end 204.436472 -356.235)
		(width 0.174752)
		(layer "F.Cu")
		(net "PE_CLK100M_DR1_2_N")
	)
	(segment
		(start 230.465884 -369.706144)
		(end 230.017828 -370.1542)
		(width 0.174752)
		(layer "F.Cu")
		(net "PE_CLK100M_DR1_2_N")
	)
	(segment
		(start 205.08849 -356.362762)
		(end 204.564234 -356.362762)
		(width 0.174752)
		(layer "F.Cu")
		(net "PE_CLK100M_DR1_2_N")
	)
	(segment
		(start 230.465884 -369.04422)
		(end 230.465884 -369.706144)
		(width 0.174752)
		(layer "F.Cu")
		(net "PE_CLK100M_DR1_2_N")
	)
	(segment
		(start 205.86827 -356.362762)
		(end 205.740508 -356.235)
		(width 0.174752)
		(layer "F.Cu")
		(net "PE_CLK100M_DR1_2_N")
	)
	(segment
		(start 205.216252 -356.235)
		(end 205.08849 -356.362762)
		(width 0.174752)
		(layer "F.Cu")
		(net "PE_CLK100M_DR1_2_N")
	)
	(segment
		(start 210.364324 -356.235)
		(end 209.840068 -356.235)
		(width 0.174752)
		(layer "F.Cu")
		(net "PE_CLK100M_DR1_2_N")
	)
	(segment
		(start 228.479604 -370.390166)
		(end 227.389944 -370.390166)
		(width 0.174752)
		(layer "F.Cu")
		(net "PE_CLK100M_DR1_2_N")
	)
	(segment
		(start 235.406946 -369.237006)
		(end 235.406946 -362.203492)
		(width 0.174752)
		(layer "F.Cu")
		(net "PE_CLK100M_DR1_2_N")
	)
	(segment
		(start 204.436472 -356.235)
		(end 178.943 -356.235)
		(width 0.174752)
		(layer "F.Cu")
		(net "PE_CLK100M_DR1_2_N")
	)
	(segment
		(start 220.22943 -356.362762)
		(end 220.101668 -356.235)
		(width 0.174752)
		(layer "F.Cu")
		(net "PE_CLK100M_DR1_2_N")
	)
	(segment
		(start 211.66836 -356.235)
		(end 211.144104 -356.235)
		(width 0.174752)
		(layer "F.Cu")
		(net "PE_CLK100M_DR1_2_N")
	)
	(segment
		(start 235.406946 -362.203492)
		(end 229.438454 -356.235)
		(width 0.174752)
		(layer "F.Cu")
		(net "PE_CLK100M_DR1_2_N")
	)
	(segment
		(start 210.492086 -356.362762)
		(end 210.364324 -356.235)
		(width 0.174752)
		(layer "F.Cu")
		(net "PE_CLK100M_DR1_2_N")
	)
	(segment
		(start 206.520288 -356.235)
		(end 206.392526 -356.362762)
		(width 0.174752)
		(layer "F.Cu")
		(net "PE_CLK100M_DR1_2_N")
	)
	(segment
		(start 178.943 -356.235)
		(end 129.083054 -306.375054)
		(width 0.174752)
		(layer "F.Cu")
		(net "PE_CLK100M_DR1_2_N")
	)
	(via
		(at 230.719884 -368.79022)
		(size 0.508)
		(drill 0.254)
		(layers "F.Cu" "B.Cu")
		(net "PE_CLK100M_DR1_2_N")
	)
	(via
		(at 233.386884 -369.579398)
		(size 0.508)
		(drill 0.254)
		(layers "F.Cu" "B.Cu")
		(net "PE_CLK100M_DR1_2_N")
	)
	(segment
		(start 233.133138 -369.833144)
		(end 230.719884 -369.833144)
		(width 0.174752)
		(layer "B.Cu")
		(net "PE_CLK100M_DR1_2_N")
	)
	(segment
		(start 230.465884 -369.04422)
		(end 230.719884 -368.79022)
		(width 0.174752)
		(layer "B.Cu")
		(net "PE_CLK100M_DR1_2_N")
	)
	(segment
		(start 230.465884 -369.579144)
		(end 230.465884 -369.04422)
		(width 0.174752)
		(layer "B.Cu")
		(net "PE_CLK100M_DR1_2_N")
	)
	(segment
		(start 233.386884 -369.579398)
		(end 233.133138 -369.833144)
		(width 0.174752)
		(layer "B.Cu")
		(net "PE_CLK100M_DR1_2_N")
	)
	(segment
		(start 230.719884 -369.833144)
		(end 230.465884 -369.579144)
		(width 0.174752)
		(layer "B.Cu")
		(net "PE_CLK100M_DR1_2_N")
	)
	(segment
		(start 105.156 -312.039)
		(end 103.9876 -310.8706)
		(width 0.174752)
		(layer "F.Cu")
		(net "PE_CLK100M_DR1_1_P")
	)
	(segment
		(start 178.303428 -361.437428)
		(end 128.905 -312.039)
		(width 0.174752)
		(layer "F.Cu")
		(net "PE_CLK100M_DR1_1_P")
	)
	(segment
		(start 224.199958 -361.190032)
		(end 223.139 -361.190032)
		(width 0.174752)
		(layer "F.Cu")
		(net "PE_CLK100M_DR1_1_P")
	)
	(segment
		(start 103.4161 -310.8706)
		(end 103.0605 -310.515)
		(width 0.174752)
		(layer "F.Cu")
		(net "PE_CLK100M_DR1_1_P")
	)
	(segment
		(start 222.891604 -361.437428)
		(end 178.303428 -361.437428)
		(width 0.174752)
		(layer "F.Cu")
		(net "PE_CLK100M_DR1_1_P")
	)
	(segment
		(start 128.905 -312.039)
		(end 105.156 -312.039)
		(width 0.174752)
		(layer "F.Cu")
		(net "PE_CLK100M_DR1_1_P")
	)
	(segment
		(start 103.9876 -310.8706)
		(end 103.4161 -310.8706)
		(width 0.174752)
		(layer "F.Cu")
		(net "PE_CLK100M_DR1_1_P")
	)
	(segment
		(start 223.139 -361.190032)
		(end 222.891604 -361.437428)
		(width 0.174752)
		(layer "F.Cu")
		(net "PE_CLK100M_DR1_1_P")
	)
	(segment
		(start 223.13265 -361.990132)
		(end 222.885 -361.742482)
		(width 0.174752)
		(layer "F.Cu")
		(net "PE_CLK100M_DR1_1_N")
	)
	(segment
		(start 128.778508 -312.344054)
		(end 105.029508 -312.344054)
		(width 0.174752)
		(layer "F.Cu")
		(net "PE_CLK100M_DR1_1_N")
	)
	(segment
		(start 103.861108 -311.175654)
		(end 103.415846 -311.175654)
		(width 0.174752)
		(layer "F.Cu")
		(net "PE_CLK100M_DR1_1_N")
	)
	(segment
		(start 222.885 -361.742482)
		(end 178.176936 -361.742482)
		(width 0.174752)
		(layer "F.Cu")
		(net "PE_CLK100M_DR1_1_N")
	)
	(segment
		(start 224.199958 -361.990132)
		(end 223.13265 -361.990132)
		(width 0.174752)
		(layer "F.Cu")
		(net "PE_CLK100M_DR1_1_N")
	)
	(segment
		(start 105.029508 -312.344054)
		(end 103.861108 -311.175654)
		(width 0.174752)
		(layer "F.Cu")
		(net "PE_CLK100M_DR1_1_N")
	)
	(segment
		(start 103.415846 -311.175654)
		(end 103.0605 -311.531)
		(width 0.174752)
		(layer "F.Cu")
		(net "PE_CLK100M_DR1_1_N")
	)
	(segment
		(start 178.176936 -361.742482)
		(end 128.778508 -312.344054)
		(width 0.174752)
		(layer "F.Cu")
		(net "PE_CLK100M_DR1_1_N")
	)
	(segment
		(start 235.712 -463.804)
		(end 235.712 -472.363546)
		(width 0.174752)
		(layer "F.Cu")
		(net "PE_CLK100M_DR0_2_P")
	)
	(segment
		(start 227.389944 -472.590114)
		(end 228.473 -472.590114)
		(width 0.174752)
		(layer "F.Cu")
		(net "PE_CLK100M_DR0_2_P")
	)
	(segment
		(start 230.16083 -472.5797)
		(end 230.16083 -472.044014)
		(width 0.174752)
		(layer "F.Cu")
		(net "PE_CLK100M_DR0_2_P")
	)
	(segment
		(start 230.16083 -472.044014)
		(end 229.907084 -471.790268)
		(width 0.174752)
		(layer "F.Cu")
		(net "PE_CLK100M_DR0_2_P")
	)
	(segment
		(start 226.498404 -458.857858)
		(end 230.765858 -458.857858)
		(width 0.174752)
		(layer "F.Cu")
		(net "PE_CLK100M_DR0_2_P")
	)
	(segment
		(start 179.318666 -434.41112)
		(end 192.658492 -447.750946)
		(width 0.174752)
		(layer "F.Cu")
		(net "PE_CLK100M_DR0_2_P")
	)
	(segment
		(start 234.9373 -473.138246)
		(end 233.640884 -473.138246)
		(width 0.174752)
		(layer "F.Cu")
		(net "PE_CLK100M_DR0_2_P")
	)
	(segment
		(start 192.658492 -447.750946)
		(end 215.391492 -447.750946)
		(width 0.174752)
		(layer "F.Cu")
		(net "PE_CLK100M_DR0_2_P")
	)
	(segment
		(start 235.712 -472.363546)
		(end 234.9373 -473.138246)
		(width 0.174752)
		(layer "F.Cu")
		(net "PE_CLK100M_DR0_2_P")
	)
	(segment
		(start 103.0605 -433.324)
		(end 103.365046 -433.628546)
		(width 0.174752)
		(layer "F.Cu")
		(net "PE_CLK100M_DR0_2_P")
	)
	(segment
		(start 233.640884 -473.138246)
		(end 233.386884 -473.392246)
		(width 0.174752)
		(layer "F.Cu")
		(net "PE_CLK100M_DR0_2_P")
	)
	(segment
		(start 103.886508 -433.628546)
		(end 104.623108 -432.891946)
		(width 0.174752)
		(layer "F.Cu")
		(net "PE_CLK100M_DR0_2_P")
	)
	(segment
		(start 113.190528 -432.891946)
		(end 114.709702 -434.41112)
		(width 0.174752)
		(layer "F.Cu")
		(net "PE_CLK100M_DR0_2_P")
	)
	(segment
		(start 104.623108 -432.891946)
		(end 113.190528 -432.891946)
		(width 0.174752)
		(layer "F.Cu")
		(net "PE_CLK100M_DR0_2_P")
	)
	(segment
		(start 114.709702 -434.41112)
		(end 179.318666 -434.41112)
		(width 0.174752)
		(layer "F.Cu")
		(net "PE_CLK100M_DR0_2_P")
	)
	(segment
		(start 230.765858 -458.857858)
		(end 235.712 -463.804)
		(width 0.174752)
		(layer "F.Cu")
		(net "PE_CLK100M_DR0_2_P")
	)
	(segment
		(start 229.902766 -472.837764)
		(end 230.16083 -472.5797)
		(width 0.174752)
		(layer "F.Cu")
		(net "PE_CLK100M_DR0_2_P")
	)
	(segment
		(start 228.72065 -472.837764)
		(end 229.902766 -472.837764)
		(width 0.174752)
		(layer "F.Cu")
		(net "PE_CLK100M_DR0_2_P")
	)
	(segment
		(start 215.391492 -447.750946)
		(end 226.498404 -458.857858)
		(width 0.174752)
		(layer "F.Cu")
		(net "PE_CLK100M_DR0_2_P")
	)
	(segment
		(start 228.473 -472.590114)
		(end 228.72065 -472.837764)
		(width 0.174752)
		(layer "F.Cu")
		(net "PE_CLK100M_DR0_2_P")
	)
	(segment
		(start 103.365046 -433.628546)
		(end 103.886508 -433.628546)
		(width 0.174752)
		(layer "F.Cu")
		(net "PE_CLK100M_DR0_2_P")
	)
	(via
		(at 233.386884 -473.392246)
		(size 0.508)
		(drill 0.254)
		(layers "F.Cu" "B.Cu")
		(net "PE_CLK100M_DR0_2_P")
	)
	(via
		(at 229.907084 -471.790268)
		(size 0.508)
		(drill 0.254)
		(layers "F.Cu" "B.Cu")
		(net "PE_CLK100M_DR0_2_P")
	)
	(segment
		(start 230.16083 -472.044014)
		(end 229.907084 -471.790268)
		(width 0.174752)
		(layer "B.Cu")
		(net "PE_CLK100M_DR0_2_P")
	)
	(segment
		(start 230.593392 -473.138246)
		(end 230.16083 -472.705684)
		(width 0.174752)
		(layer "B.Cu")
		(net "PE_CLK100M_DR0_2_P")
	)
	(segment
		(start 233.386884 -473.392246)
		(end 233.132884 -473.138246)
		(width 0.174752)
		(layer "B.Cu")
		(net "PE_CLK100M_DR0_2_P")
	)
	(segment
		(start 230.16083 -472.705684)
		(end 230.16083 -472.044014)
		(width 0.174752)
		(layer "B.Cu")
		(net "PE_CLK100M_DR0_2_P")
	)
	(segment
		(start 233.132884 -473.138246)
		(end 230.593392 -473.138246)
		(width 0.174752)
		(layer "B.Cu")
		(net "PE_CLK100M_DR0_2_P")
	)
	(segment
		(start 191.60998 -447.314574)
		(end 191.980566 -447.685414)
		(width 0.174752)
		(layer "F.Cu")
		(net "PE_CLK100M_DR0_2_N")
	)
	(segment
		(start 226.371912 -459.162912)
		(end 230.639366 -459.162912)
		(width 0.174752)
		(layer "F.Cu")
		(net "PE_CLK100M_DR0_2_N")
	)
	(segment
		(start 233.562652 -462.086198)
		(end 233.562652 -462.267046)
		(width 0.174752)
		(layer "F.Cu")
		(net "PE_CLK100M_DR0_2_N")
	)
	(segment
		(start 235.406946 -470.933018)
		(end 235.279184 -471.06078)
		(width 0.174752)
		(layer "F.Cu")
		(net "PE_CLK100M_DR0_2_N")
	)
	(segment
		(start 235.279184 -471.06078)
		(end 235.279184 -471.585036)
		(width 0.174752)
		(layer "F.Cu")
		(net "PE_CLK100M_DR0_2_N")
	)
	(segment
		(start 234.114086 -462.637632)
		(end 234.484926 -463.008472)
		(width 0.174752)
		(layer "F.Cu")
		(net "PE_CLK100M_DR0_2_N")
	)
	(segment
		(start 230.465884 -472.706192)
		(end 230.465884 -472.044268)
		(width 0.174752)
		(layer "F.Cu")
		(net "PE_CLK100M_DR0_2_N")
	)
	(segment
		(start 235.406946 -469.628982)
		(end 235.279184 -469.756744)
		(width 0.174752)
		(layer "F.Cu")
		(net "PE_CLK100M_DR0_2_N")
	)
	(segment
		(start 103.4669 -433.9336)
		(end 104.013 -433.9336)
		(width 0.174752)
		(layer "F.Cu")
		(net "PE_CLK100M_DR0_2_N")
	)
	(segment
		(start 103.0605 -434.34)
		(end 103.4669 -433.9336)
		(width 0.174752)
		(layer "F.Cu")
		(net "PE_CLK100M_DR0_2_N")
	)
	(segment
		(start 189.765686 -445.47028)
		(end 190.136526 -445.84112)
		(width 0.174752)
		(layer "F.Cu")
		(net "PE_CLK100M_DR0_2_N")
	)
	(segment
		(start 113.064036 -433.197)
		(end 114.58321 -434.716174)
		(width 0.174752)
		(layer "F.Cu")
		(net "PE_CLK100M_DR0_2_N")
	)
	(segment
		(start 114.58321 -434.716174)
		(end 179.192174 -434.716174)
		(width 0.174752)
		(layer "F.Cu")
		(net "PE_CLK100M_DR0_2_N")
	)
	(segment
		(start 189.765686 -445.289686)
		(end 189.765686 -445.47028)
		(width 0.174752)
		(layer "F.Cu")
		(net "PE_CLK100M_DR0_2_N")
	)
	(segment
		(start 235.406946 -470.408762)
		(end 235.406946 -470.933018)
		(width 0.174752)
		(layer "F.Cu")
		(net "PE_CLK100M_DR0_2_N")
	)
	(segment
		(start 234.484926 -463.189066)
		(end 234.855512 -463.559906)
		(width 0.174752)
		(layer "F.Cu")
		(net "PE_CLK100M_DR0_2_N")
	)
	(segment
		(start 235.279184 -471.585036)
		(end 235.406946 -471.712798)
		(width 0.174752)
		(layer "F.Cu")
		(net "PE_CLK100M_DR0_2_N")
	)
	(segment
		(start 191.980566 -447.685414)
		(end 192.161414 -447.685414)
		(width 0.174752)
		(layer "F.Cu")
		(net "PE_CLK100M_DR0_2_N")
	)
	(segment
		(start 235.279184 -468.976964)
		(end 235.406946 -469.104726)
		(width 0.174752)
		(layer "F.Cu")
		(net "PE_CLK100M_DR0_2_N")
	)
	(segment
		(start 191.23914 -446.76314)
		(end 191.60998 -447.13398)
		(width 0.174752)
		(layer "F.Cu")
		(net "PE_CLK100M_DR0_2_N")
	)
	(segment
		(start 235.406946 -472.237054)
		(end 234.810808 -472.833192)
		(width 0.174752)
		(layer "F.Cu")
		(net "PE_CLK100M_DR0_2_N")
	)
	(segment
		(start 234.810808 -472.833192)
		(end 233.64063 -472.833192)
		(width 0.174752)
		(layer "F.Cu")
		(net "PE_CLK100M_DR0_2_N")
	)
	(segment
		(start 235.406946 -468.324946)
		(end 235.279184 -468.452708)
		(width 0.174752)
		(layer "F.Cu")
		(net "PE_CLK100M_DR0_2_N")
	)
	(segment
		(start 192.532 -448.056)
		(end 215.265 -448.056)
		(width 0.174752)
		(layer "F.Cu")
		(net "PE_CLK100M_DR0_2_N")
	)
	(segment
		(start 233.933492 -462.637632)
		(end 234.114086 -462.637632)
		(width 0.174752)
		(layer "F.Cu")
		(net "PE_CLK100M_DR0_2_N")
	)
	(segment
		(start 191.058546 -446.76314)
		(end 191.23914 -446.76314)
		(width 0.174752)
		(layer "F.Cu")
		(net "PE_CLK100M_DR0_2_N")
	)
	(segment
		(start 190.687706 -446.211706)
		(end 190.687706 -446.392554)
		(width 0.174752)
		(layer "F.Cu")
		(net "PE_CLK100M_DR0_2_N")
	)
	(segment
		(start 227.389944 -473.390214)
		(end 228.479604 -473.390214)
		(width 0.174752)
		(layer "F.Cu")
		(net "PE_CLK100M_DR0_2_N")
	)
	(segment
		(start 179.192174 -434.716174)
		(end 189.765686 -445.289686)
		(width 0.174752)
		(layer "F.Cu")
		(net "PE_CLK100M_DR0_2_N")
	)
	(segment
		(start 235.406946 -463.930492)
		(end 235.406946 -468.324946)
		(width 0.174752)
		(layer "F.Cu")
		(net "PE_CLK100M_DR0_2_N")
	)
	(segment
		(start 233.011472 -461.715612)
		(end 233.192066 -461.715612)
		(width 0.174752)
		(layer "F.Cu")
		(net "PE_CLK100M_DR0_2_N")
	)
	(segment
		(start 230.639366 -459.162912)
		(end 232.640632 -461.164178)
		(width 0.174752)
		(layer "F.Cu")
		(net "PE_CLK100M_DR0_2_N")
	)
	(segment
		(start 232.640632 -461.344772)
		(end 233.011472 -461.715612)
		(width 0.174752)
		(layer "F.Cu")
		(net "PE_CLK100M_DR0_2_N")
	)
	(segment
		(start 235.279184 -468.452708)
		(end 235.279184 -468.976964)
		(width 0.174752)
		(layer "F.Cu")
		(net "PE_CLK100M_DR0_2_N")
	)
	(segment
		(start 191.60998 -447.13398)
		(end 191.60998 -447.314574)
		(width 0.174752)
		(layer "F.Cu")
		(net "PE_CLK100M_DR0_2_N")
	)
	(segment
		(start 232.640632 -461.164178)
		(end 232.640632 -461.344772)
		(width 0.174752)
		(layer "F.Cu")
		(net "PE_CLK100M_DR0_2_N")
	)
	(segment
		(start 235.03636 -463.559906)
		(end 235.406946 -463.930492)
		(width 0.174752)
		(layer "F.Cu")
		(net "PE_CLK100M_DR0_2_N")
	)
	(segment
		(start 228.727 -473.142818)
		(end 230.029258 -473.142818)
		(width 0.174752)
		(layer "F.Cu")
		(net "PE_CLK100M_DR0_2_N")
	)
	(segment
		(start 192.161414 -447.685414)
		(end 192.532 -448.056)
		(width 0.174752)
		(layer "F.Cu")
		(net "PE_CLK100M_DR0_2_N")
	)
	(segment
		(start 215.265 -448.056)
		(end 226.371912 -459.162912)
		(width 0.174752)
		(layer "F.Cu")
		(net "PE_CLK100M_DR0_2_N")
	)
	(segment
		(start 234.855512 -463.559906)
		(end 235.03636 -463.559906)
		(width 0.174752)
		(layer "F.Cu")
		(net "PE_CLK100M_DR0_2_N")
	)
	(segment
		(start 104.7496 -433.197)
		(end 113.064036 -433.197)
		(width 0.174752)
		(layer "F.Cu")
		(net "PE_CLK100M_DR0_2_N")
	)
	(segment
		(start 235.406946 -471.712798)
		(end 235.406946 -472.237054)
		(width 0.174752)
		(layer "F.Cu")
		(net "PE_CLK100M_DR0_2_N")
	)
	(segment
		(start 230.029258 -473.142818)
		(end 230.465884 -472.706192)
		(width 0.174752)
		(layer "F.Cu")
		(net "PE_CLK100M_DR0_2_N")
	)
	(segment
		(start 233.64063 -472.833192)
		(end 233.386884 -472.579446)
		(width 0.174752)
		(layer "F.Cu")
		(net "PE_CLK100M_DR0_2_N")
	)
	(segment
		(start 190.687706 -446.392554)
		(end 191.058546 -446.76314)
		(width 0.174752)
		(layer "F.Cu")
		(net "PE_CLK100M_DR0_2_N")
	)
	(segment
		(start 233.562652 -462.267046)
		(end 233.933492 -462.637632)
		(width 0.174752)
		(layer "F.Cu")
		(net "PE_CLK100M_DR0_2_N")
	)
	(segment
		(start 235.279184 -469.756744)
		(end 235.279184 -470.281)
		(width 0.174752)
		(layer "F.Cu")
		(net "PE_CLK100M_DR0_2_N")
	)
	(segment
		(start 190.136526 -445.84112)
		(end 190.31712 -445.84112)
		(width 0.174752)
		(layer "F.Cu")
		(net "PE_CLK100M_DR0_2_N")
	)
	(segment
		(start 230.465884 -472.044268)
		(end 230.719884 -471.790268)
		(width 0.174752)
		(layer "F.Cu")
		(net "PE_CLK100M_DR0_2_N")
	)
	(segment
		(start 235.406946 -469.104726)
		(end 235.406946 -469.628982)
		(width 0.174752)
		(layer "F.Cu")
		(net "PE_CLK100M_DR0_2_N")
	)
	(segment
		(start 233.192066 -461.715612)
		(end 233.562652 -462.086198)
		(width 0.174752)
		(layer "F.Cu")
		(net "PE_CLK100M_DR0_2_N")
	)
	(segment
		(start 104.013 -433.9336)
		(end 104.7496 -433.197)
		(width 0.174752)
		(layer "F.Cu")
		(net "PE_CLK100M_DR0_2_N")
	)
	(segment
		(start 228.479604 -473.390214)
		(end 228.727 -473.142818)
		(width 0.174752)
		(layer "F.Cu")
		(net "PE_CLK100M_DR0_2_N")
	)
	(segment
		(start 235.279184 -470.281)
		(end 235.406946 -470.408762)
		(width 0.174752)
		(layer "F.Cu")
		(net "PE_CLK100M_DR0_2_N")
	)
	(segment
		(start 190.31712 -445.84112)
		(end 190.687706 -446.211706)
		(width 0.174752)
		(layer "F.Cu")
		(net "PE_CLK100M_DR0_2_N")
	)
	(segment
		(start 234.484926 -463.008472)
		(end 234.484926 -463.189066)
		(width 0.174752)
		(layer "F.Cu")
		(net "PE_CLK100M_DR0_2_N")
	)
	(via
		(at 233.386884 -472.579446)
		(size 0.508)
		(drill 0.254)
		(layers "F.Cu" "B.Cu")
		(net "PE_CLK100M_DR0_2_N")
	)
	(via
		(at 230.719884 -471.790268)
		(size 0.508)
		(drill 0.254)
		(layers "F.Cu" "B.Cu")
		(net "PE_CLK100M_DR0_2_N")
	)
	(segment
		(start 230.719884 -472.833192)
		(end 230.465884 -472.579192)
		(width 0.174752)
		(layer "B.Cu")
		(net "PE_CLK100M_DR0_2_N")
	)
	(segment
		(start 233.133138 -472.833192)
		(end 230.719884 -472.833192)
		(width 0.174752)
		(layer "B.Cu")
		(net "PE_CLK100M_DR0_2_N")
	)
	(segment
		(start 230.465884 -472.044268)
		(end 230.719884 -471.790268)
		(width 0.174752)
		(layer "B.Cu")
		(net "PE_CLK100M_DR0_2_N")
	)
	(segment
		(start 230.465884 -472.579192)
		(end 230.465884 -472.044268)
		(width 0.174752)
		(layer "B.Cu")
		(net "PE_CLK100M_DR0_2_N")
	)
	(segment
		(start 233.386884 -472.579446)
		(end 233.133138 -472.833192)
		(width 0.174752)
		(layer "B.Cu")
		(net "PE_CLK100M_DR0_2_N")
	)
	(segment
		(start 213.537546 -450.977)
		(end 191.312546 -450.977)
		(width 0.174752)
		(layer "F.Cu")
		(net "PE_CLK100M_DR0_1_P")
	)
	(segment
		(start 191.312546 -450.977)
		(end 178.993546 -438.658)
		(width 0.174752)
		(layer "F.Cu")
		(net "PE_CLK100M_DR0_1_P")
	)
	(segment
		(start 219.71 -457.149454)
		(end 213.537546 -450.977)
		(width 0.174752)
		(layer "F.Cu")
		(net "PE_CLK100M_DR0_1_P")
	)
	(segment
		(start 221.613476 -464.437476)
		(end 219.71 -462.534)
		(width 0.174752)
		(layer "F.Cu")
		(net "PE_CLK100M_DR0_1_P")
	)
	(segment
		(start 219.71 -462.534)
		(end 219.71 -457.149454)
		(width 0.174752)
		(layer "F.Cu")
		(net "PE_CLK100M_DR0_1_P")
	)
	(segment
		(start 223.033082 -464.19008)
		(end 222.785686 -464.437476)
		(width 0.174752)
		(layer "F.Cu")
		(net "PE_CLK100M_DR0_1_P")
	)
	(segment
		(start 224.199958 -464.19008)
		(end 223.033082 -464.19008)
		(width 0.174752)
		(layer "F.Cu")
		(net "PE_CLK100M_DR0_1_P")
	)
	(segment
		(start 178.993546 -438.658)
		(end 105.156 -438.658)
		(width 0.174752)
		(layer "F.Cu")
		(net "PE_CLK100M_DR0_1_P")
	)
	(segment
		(start 103.987346 -437.489346)
		(end 103.415846 -437.489346)
		(width 0.174752)
		(layer "F.Cu")
		(net "PE_CLK100M_DR0_1_P")
	)
	(segment
		(start 103.415846 -437.489346)
		(end 103.0605 -437.134)
		(width 0.174752)
		(layer "F.Cu")
		(net "PE_CLK100M_DR0_1_P")
	)
	(segment
		(start 105.156 -438.658)
		(end 103.987346 -437.489346)
		(width 0.174752)
		(layer "F.Cu")
		(net "PE_CLK100M_DR0_1_P")
	)
	(segment
		(start 222.785686 -464.437476)
		(end 221.613476 -464.437476)
		(width 0.174752)
		(layer "F.Cu")
		(net "PE_CLK100M_DR0_1_P")
	)
	(segment
		(start 219.404946 -457.275946)
		(end 213.411054 -451.282054)
		(width 0.174752)
		(layer "F.Cu")
		(net "PE_CLK100M_DR0_1_N")
	)
	(segment
		(start 103.860854 -437.7944)
		(end 103.4161 -437.7944)
		(width 0.174752)
		(layer "F.Cu")
		(net "PE_CLK100M_DR0_1_N")
	)
	(segment
		(start 191.186054 -451.282054)
		(end 178.867054 -438.963054)
		(width 0.174752)
		(layer "F.Cu")
		(net "PE_CLK100M_DR0_1_N")
	)
	(segment
		(start 213.411054 -451.282054)
		(end 191.186054 -451.282054)
		(width 0.174752)
		(layer "F.Cu")
		(net "PE_CLK100M_DR0_1_N")
	)
	(segment
		(start 224.199958 -464.99018)
		(end 223.033336 -464.99018)
		(width 0.174752)
		(layer "F.Cu")
		(net "PE_CLK100M_DR0_1_N")
	)
	(segment
		(start 223.033336 -464.99018)
		(end 222.785686 -464.74253)
		(width 0.174752)
		(layer "F.Cu")
		(net "PE_CLK100M_DR0_1_N")
	)
	(segment
		(start 221.486984 -464.74253)
		(end 219.404946 -462.660492)
		(width 0.174752)
		(layer "F.Cu")
		(net "PE_CLK100M_DR0_1_N")
	)
	(segment
		(start 178.867054 -438.963054)
		(end 105.029508 -438.963054)
		(width 0.174752)
		(layer "F.Cu")
		(net "PE_CLK100M_DR0_1_N")
	)
	(segment
		(start 219.404946 -462.660492)
		(end 219.404946 -457.275946)
		(width 0.174752)
		(layer "F.Cu")
		(net "PE_CLK100M_DR0_1_N")
	)
	(segment
		(start 222.785686 -464.74253)
		(end 221.486984 -464.74253)
		(width 0.174752)
		(layer "F.Cu")
		(net "PE_CLK100M_DR0_1_N")
	)
	(segment
		(start 103.4161 -437.7944)
		(end 103.0605 -438.15)
		(width 0.174752)
		(layer "F.Cu")
		(net "PE_CLK100M_DR0_1_N")
	)
	(segment
		(start 105.029508 -438.963054)
		(end 103.860854 -437.7944)
		(width 0.174752)
		(layer "F.Cu")
		(net "PE_CLK100M_DR0_1_N")
	)
	(segment
		(start 88.7222 -94.5388)
		(end 89.092786 -94.909386)
		(width 0.174752)
		(layer "F.Cu")
		(net "PE_CLK_100M_DR9_2_R_P")
	)
	(segment
		(start 86.487 -93.4085)
		(end 86.5251 -93.4085)
		(width 0.174752)
		(layer "F.Cu")
		(net "PE_CLK_100M_DR9_2_R_P")
	)
	(segment
		(start 86.842346 -94.131892)
		(end 87.249254 -94.5388)
		(width 0.174752)
		(layer "F.Cu")
		(net "PE_CLK_100M_DR9_2_R_P")
	)
	(segment
		(start 90.22969 -96.43491)
		(end 90.22969 -97.049082)
		(width 0.174752)
		(layer "F.Cu")
		(net "PE_CLK_100M_DR9_2_R_P")
	)
	(segment
		(start 89.64422 -95.46082)
		(end 90.3224 -96.139)
		(width 0.174752)
		(layer "F.Cu")
		(net "PE_CLK_100M_DR9_2_R_P")
	)
	(segment
		(start 86.842346 -93.725746)
		(end 86.842346 -94.131892)
		(width 0.174752)
		(layer "F.Cu")
		(net "PE_CLK_100M_DR9_2_R_P")
	)
	(segment
		(start 87.249254 -94.5388)
		(end 88.7222 -94.5388)
		(width 0.174752)
		(layer "F.Cu")
		(net "PE_CLK_100M_DR9_2_R_P")
	)
	(segment
		(start 86.5251 -93.4085)
		(end 86.842346 -93.725746)
		(width 0.174752)
		(layer "F.Cu")
		(net "PE_CLK_100M_DR9_2_R_P")
	)
	(segment
		(start 89.092786 -95.090234)
		(end 89.463626 -95.46082)
		(width 0.174752)
		(layer "F.Cu")
		(net "PE_CLK_100M_DR9_2_R_P")
	)
	(segment
		(start 89.092786 -94.909386)
		(end 89.092786 -95.090234)
		(width 0.174752)
		(layer "F.Cu")
		(net "PE_CLK_100M_DR9_2_R_P")
	)
	(segment
		(start 90.3224 -96.3422)
		(end 90.22969 -96.43491)
		(width 0.174752)
		(layer "F.Cu")
		(net "PE_CLK_100M_DR9_2_R_P")
	)
	(segment
		(start 90.3224 -96.139)
		(end 90.3224 -96.3422)
		(width 0.174752)
		(layer "F.Cu")
		(net "PE_CLK_100M_DR9_2_R_P")
	)
	(segment
		(start 89.463626 -95.46082)
		(end 89.64422 -95.46082)
		(width 0.174752)
		(layer "F.Cu")
		(net "PE_CLK_100M_DR9_2_R_P")
	)
	(segment
		(start 87.1474 -93.7641)
		(end 87.503 -93.4085)
		(width 0.174752)
		(layer "F.Cu")
		(net "PE_CLK_100M_DR9_2_R_N")
	)
	(segment
		(start 90.73007 -97.17659)
		(end 90.73007 -96.4184)
		(width 0.174752)
		(layer "F.Cu")
		(net "PE_CLK_100M_DR9_2_R_N")
	)
	(segment
		(start 90.73007 -96.4184)
		(end 90.627454 -96.315784)
		(width 0.174752)
		(layer "F.Cu")
		(net "PE_CLK_100M_DR9_2_R_N")
	)
	(segment
		(start 88.848692 -94.233746)
		(end 87.375746 -94.233746)
		(width 0.174752)
		(layer "F.Cu")
		(net "PE_CLK_100M_DR9_2_R_N")
	)
	(segment
		(start 90.627454 -96.315784)
		(end 90.627454 -96.012508)
		(width 0.174752)
		(layer "F.Cu")
		(net "PE_CLK_100M_DR9_2_R_N")
	)
	(segment
		(start 87.1474 -94.0054)
		(end 87.1474 -93.7641)
		(width 0.174752)
		(layer "F.Cu")
		(net "PE_CLK_100M_DR9_2_R_N")
	)
	(segment
		(start 87.375746 -94.233746)
		(end 87.1474 -94.0054)
		(width 0.174752)
		(layer "F.Cu")
		(net "PE_CLK_100M_DR9_2_R_N")
	)
	(segment
		(start 90.627454 -96.012508)
		(end 88.848692 -94.233746)
		(width 0.174752)
		(layer "F.Cu")
		(net "PE_CLK_100M_DR9_2_R_N")
	)
	(segment
		(start 92.632022 -96.137476)
		(end 90.9574 -94.462854)
		(width 0.174752)
		(layer "F.Cu")
		(net "PE_CLK_100M_DR9_1_R_N")
	)
	(segment
		(start 92.73032 -97.17659)
		(end 92.73032 -96.491298)
		(width 0.174752)
		(layer "F.Cu")
		(net "PE_CLK_100M_DR9_1_R_N")
	)
	(segment
		(start 92.632022 -96.393)
		(end 92.632022 -96.137476)
		(width 0.174752)
		(layer "F.Cu")
		(net "PE_CLK_100M_DR9_1_R_N")
	)
	(segment
		(start 90.9574 -93.7641)
		(end 91.313 -93.4085)
		(width 0.174752)
		(layer "F.Cu")
		(net "PE_CLK_100M_DR9_1_R_N")
	)
	(segment
		(start 92.73032 -96.491298)
		(end 92.632022 -96.393)
		(width 0.174752)
		(layer "F.Cu")
		(net "PE_CLK_100M_DR9_1_R_N")
	)
	(segment
		(start 90.9574 -94.462854)
		(end 90.9574 -93.7641)
		(width 0.174752)
		(layer "F.Cu")
		(net "PE_CLK_100M_DR9_1_R_N")
	)
	(segment
		(start 98.298 -108.077)
		(end 99.237546 -108.077)
		(width 0.174752)
		(layer "F.Cu")
		(net "PE_CLK_100M_DR8_2_R_P")
	)
	(segment
		(start 97.13214 -106.77779)
		(end 97.13214 -106.91114)
		(width 0.174752)
		(layer "F.Cu")
		(net "PE_CLK_100M_DR8_2_R_P")
	)
	(segment
		(start 97.13214 -106.91114)
		(end 98.298 -108.077)
		(width 0.174752)
		(layer "F.Cu")
		(net "PE_CLK_100M_DR8_2_R_P")
	)
	(segment
		(start 99.237546 -108.077)
		(end 99.9744 -108.813854)
		(width 0.174752)
		(layer "F.Cu")
		(net "PE_CLK_100M_DR8_2_R_P")
	)
	(segment
		(start 99.9744 -109.4359)
		(end 100.33 -109.7915)
		(width 0.174752)
		(layer "F.Cu")
		(net "PE_CLK_100M_DR8_2_R_P")
	)
	(segment
		(start 99.9744 -108.813854)
		(end 99.9744 -109.4359)
		(width 0.174752)
		(layer "F.Cu")
		(net "PE_CLK_100M_DR8_2_R_P")
	)
	(segment
		(start 97.22993 -106.68)
		(end 97.13214 -106.77779)
		(width 0.174752)
		(layer "F.Cu")
		(net "PE_CLK_100M_DR8_2_R_P")
	)
	(segment
		(start 97.22993 -106.02341)
		(end 97.22993 -106.68)
		(width 0.174752)
		(layer "F.Cu")
		(net "PE_CLK_100M_DR8_2_R_P")
	)
	(segment
		(start 96.827086 -107.037632)
		(end 98.171508 -108.382054)
		(width 0.174752)
		(layer "F.Cu")
		(net "PE_CLK_100M_DR8_2_R_N")
	)
	(segment
		(start 96.827086 -106.807)
		(end 96.827086 -107.037632)
		(width 0.174752)
		(layer "F.Cu")
		(net "PE_CLK_100M_DR8_2_R_N")
	)
	(segment
		(start 98.171508 -108.382054)
		(end 99.111054 -108.382054)
		(width 0.174752)
		(layer "F.Cu")
		(net "PE_CLK_100M_DR8_2_R_N")
	)
	(segment
		(start 96.72955 -106.02341)
		(end 96.72955 -106.709464)
		(width 0.174752)
		(layer "F.Cu")
		(net "PE_CLK_100M_DR8_2_R_N")
	)
	(segment
		(start 99.111054 -108.382054)
		(end 99.669346 -108.940346)
		(width 0.174752)
		(layer "F.Cu")
		(net "PE_CLK_100M_DR8_2_R_N")
	)
	(segment
		(start 96.72955 -106.709464)
		(end 96.827086 -106.807)
		(width 0.174752)
		(layer "F.Cu")
		(net "PE_CLK_100M_DR8_2_R_N")
	)
	(segment
		(start 99.669346 -109.436154)
		(end 99.314 -109.7915)
		(width 0.174752)
		(layer "F.Cu")
		(net "PE_CLK_100M_DR8_2_R_N")
	)
	(segment
		(start 99.669346 -108.940346)
		(end 99.669346 -109.436154)
		(width 0.174752)
		(layer "F.Cu")
		(net "PE_CLK_100M_DR8_2_R_N")
	)
	(segment
		(start 95.22968 -106.02341)
		(end 95.22968 -106.807)
		(width 0.174752)
		(layer "F.Cu")
		(net "PE_CLK_100M_DR8_1_R_P")
	)
	(segment
		(start 96.1644 -109.4359)
		(end 96.52 -109.7915)
		(width 0.174752)
		(layer "F.Cu")
		(net "PE_CLK_100M_DR8_1_R_P")
	)
	(segment
		(start 95.132652 -106.904028)
		(end 95.132652 -107.578652)
		(width 0.174752)
		(layer "F.Cu")
		(net "PE_CLK_100M_DR8_1_R_P")
	)
	(segment
		(start 95.132652 -107.578652)
		(end 96.1644 -108.6104)
		(width 0.174752)
		(layer "F.Cu")
		(net "PE_CLK_100M_DR8_1_R_P")
	)
	(segment
		(start 95.22968 -106.807)
		(end 95.132652 -106.904028)
		(width 0.174752)
		(layer "F.Cu")
		(net "PE_CLK_100M_DR8_1_R_P")
	)
	(segment
		(start 96.1644 -108.6104)
		(end 96.1644 -109.4359)
		(width 0.174752)
		(layer "F.Cu")
		(net "PE_CLK_100M_DR8_1_R_P")
	)
	(segment
		(start 94.827598 -107.705144)
		(end 95.859346 -108.736892)
		(width 0.174752)
		(layer "F.Cu")
		(net "PE_CLK_100M_DR8_1_R_N")
	)
	(segment
		(start 94.73057 -106.02341)
		(end 94.73057 -106.807)
		(width 0.174752)
		(layer "F.Cu")
		(net "PE_CLK_100M_DR8_1_R_N")
	)
	(segment
		(start 94.827598 -106.904028)
		(end 94.827598 -107.705144)
		(width 0.174752)
		(layer "F.Cu")
		(net "PE_CLK_100M_DR8_1_R_N")
	)
	(segment
		(start 95.859346 -108.736892)
		(end 95.859346 -109.436154)
		(width 0.174752)
		(layer "F.Cu")
		(net "PE_CLK_100M_DR8_1_R_N")
	)
	(segment
		(start 95.859346 -109.436154)
		(end 95.504 -109.7915)
		(width 0.174752)
		(layer "F.Cu")
		(net "PE_CLK_100M_DR8_1_R_N")
	)
	(segment
		(start 94.73057 -106.807)
		(end 94.827598 -106.904028)
		(width 0.174752)
		(layer "F.Cu")
		(net "PE_CLK_100M_DR8_1_R_N")
	)
	(segment
		(start 97.22993 -215.9)
		(end 97.13214 -215.99779)
		(width 0.174752)
		(layer "F.Cu")
		(net "PE_CLK_100M_DR7_2_R_P")
	)
	(segment
		(start 97.13214 -215.99779)
		(end 97.13214 -216.13114)
		(width 0.174752)
		(layer "F.Cu")
		(net "PE_CLK_100M_DR7_2_R_P")
	)
	(segment
		(start 99.9744 -218.6559)
		(end 100.33 -219.0115)
		(width 0.174752)
		(layer "F.Cu")
		(net "PE_CLK_100M_DR7_2_R_P")
	)
	(segment
		(start 97.22993 -215.24341)
		(end 97.22993 -215.9)
		(width 0.174752)
		(layer "F.Cu")
		(net "PE_CLK_100M_DR7_2_R_P")
	)
	(segment
		(start 97.13214 -216.13114)
		(end 98.298 -217.297)
		(width 0.174752)
		(layer "F.Cu")
		(net "PE_CLK_100M_DR7_2_R_P")
	)
	(segment
		(start 99.237546 -217.297)
		(end 99.9744 -218.033854)
		(width 0.174752)
		(layer "F.Cu")
		(net "PE_CLK_100M_DR7_2_R_P")
	)
	(segment
		(start 98.298 -217.297)
		(end 99.237546 -217.297)
		(width 0.174752)
		(layer "F.Cu")
		(net "PE_CLK_100M_DR7_2_R_P")
	)
	(segment
		(start 99.9744 -218.033854)
		(end 99.9744 -218.6559)
		(width 0.174752)
		(layer "F.Cu")
		(net "PE_CLK_100M_DR7_2_R_P")
	)
	(segment
		(start 96.72955 -215.24341)
		(end 96.72955 -215.929464)
		(width 0.174752)
		(layer "F.Cu")
		(net "PE_CLK_100M_DR7_2_R_N")
	)
	(segment
		(start 99.669346 -218.160346)
		(end 99.669346 -218.656154)
		(width 0.174752)
		(layer "F.Cu")
		(net "PE_CLK_100M_DR7_2_R_N")
	)
	(segment
		(start 98.171508 -217.602054)
		(end 99.111054 -217.602054)
		(width 0.174752)
		(layer "F.Cu")
		(net "PE_CLK_100M_DR7_2_R_N")
	)
	(segment
		(start 99.669346 -218.656154)
		(end 99.314 -219.0115)
		(width 0.174752)
		(layer "F.Cu")
		(net "PE_CLK_100M_DR7_2_R_N")
	)
	(segment
		(start 99.111054 -217.602054)
		(end 99.669346 -218.160346)
		(width 0.174752)
		(layer "F.Cu")
		(net "PE_CLK_100M_DR7_2_R_N")
	)
	(segment
		(start 96.827086 -216.027)
		(end 96.827086 -216.257632)
		(width 0.174752)
		(layer "F.Cu")
		(net "PE_CLK_100M_DR7_2_R_N")
	)
	(segment
		(start 96.72955 -215.929464)
		(end 96.827086 -216.027)
		(width 0.174752)
		(layer "F.Cu")
		(net "PE_CLK_100M_DR7_2_R_N")
	)
	(segment
		(start 96.827086 -216.257632)
		(end 98.171508 -217.602054)
		(width 0.174752)
		(layer "F.Cu")
		(net "PE_CLK_100M_DR7_2_R_N")
	)
	(segment
		(start 95.132652 -215.997028)
		(end 95.132652 -216.544652)
		(width 0.174752)
		(layer "F.Cu")
		(net "PE_CLK_100M_DR7_1_R_P")
	)
	(segment
		(start 95.22968 -215.24341)
		(end 95.22968 -215.9)
		(width 0.174752)
		(layer "F.Cu")
		(net "PE_CLK_100M_DR7_1_R_P")
	)
	(segment
		(start 95.22968 -215.9)
		(end 95.132652 -215.997028)
		(width 0.174752)
		(layer "F.Cu")
		(net "PE_CLK_100M_DR7_1_R_P")
	)
	(segment
		(start 96.1644 -218.6559)
		(end 96.52 -219.0115)
		(width 0.174752)
		(layer "F.Cu")
		(net "PE_CLK_100M_DR7_1_R_P")
	)
	(segment
		(start 95.132652 -216.544652)
		(end 96.1644 -217.5764)
		(width 0.174752)
		(layer "F.Cu")
		(net "PE_CLK_100M_DR7_1_R_P")
	)
	(segment
		(start 96.1644 -217.5764)
		(end 96.1644 -218.6559)
		(width 0.174752)
		(layer "F.Cu")
		(net "PE_CLK_100M_DR7_1_R_P")
	)
	(segment
		(start 94.73057 -215.24341)
		(end 94.73057 -215.929972)
		(width 0.174752)
		(layer "F.Cu")
		(net "PE_CLK_100M_DR7_1_R_N")
	)
	(segment
		(start 94.827598 -216.671144)
		(end 95.859346 -217.702892)
		(width 0.174752)
		(layer "F.Cu")
		(net "PE_CLK_100M_DR7_1_R_N")
	)
	(segment
		(start 94.827598 -216.027)
		(end 94.827598 -216.671144)
		(width 0.174752)
		(layer "F.Cu")
		(net "PE_CLK_100M_DR7_1_R_N")
	)
	(segment
		(start 95.859346 -218.656154)
		(end 95.504 -219.0115)
		(width 0.174752)
		(layer "F.Cu")
		(net "PE_CLK_100M_DR7_1_R_N")
	)
	(segment
		(start 94.73057 -215.929972)
		(end 94.827598 -216.027)
		(width 0.174752)
		(layer "F.Cu")
		(net "PE_CLK_100M_DR7_1_R_N")
	)
	(segment
		(start 95.859346 -217.702892)
		(end 95.859346 -218.656154)
		(width 0.174752)
		(layer "F.Cu")
		(net "PE_CLK_100M_DR7_1_R_N")
	)
	(segment
		(start 97.940114 -311.658)
		(end 97.13214 -310.850026)
		(width 0.174752)
		(layer "F.Cu")
		(net "PE_CLK_100M_DR6_2_R_P")
	)
	(segment
		(start 100.33 -313.3725)
		(end 99.9744 -313.0169)
		(width 0.174752)
		(layer "F.Cu")
		(net "PE_CLK_100M_DR6_2_R_P")
	)
	(segment
		(start 99.9744 -313.0169)
		(end 99.9744 -312.394854)
		(width 0.174752)
		(layer "F.Cu")
		(net "PE_CLK_100M_DR6_2_R_P")
	)
	(segment
		(start 99.237546 -311.658)
		(end 97.940114 -311.658)
		(width 0.174752)
		(layer "F.Cu")
		(net "PE_CLK_100M_DR6_2_R_P")
	)
	(segment
		(start 97.13214 -310.526684)
		(end 97.22993 -310.428894)
		(width 0.174752)
		(layer "F.Cu")
		(net "PE_CLK_100M_DR6_2_R_P")
	)
	(segment
		(start 97.13214 -310.850026)
		(end 97.13214 -310.526684)
		(width 0.174752)
		(layer "F.Cu")
		(net "PE_CLK_100M_DR6_2_R_P")
	)
	(segment
		(start 99.9744 -312.394854)
		(end 99.237546 -311.658)
		(width 0.174752)
		(layer "F.Cu")
		(net "PE_CLK_100M_DR6_2_R_P")
	)
	(segment
		(start 97.22993 -310.428894)
		(end 97.22993 -309.60441)
		(width 0.174752)
		(layer "F.Cu")
		(net "PE_CLK_100M_DR6_2_R_P")
	)
	(segment
		(start 96.72955 -310.429148)
		(end 96.827086 -310.526684)
		(width 0.174752)
		(layer "F.Cu")
		(net "PE_CLK_100M_DR6_2_R_N")
	)
	(segment
		(start 96.72955 -309.60441)
		(end 96.72955 -310.429148)
		(width 0.174752)
		(layer "F.Cu")
		(net "PE_CLK_100M_DR6_2_R_N")
	)
	(segment
		(start 97.813622 -311.963054)
		(end 99.111054 -311.963054)
		(width 0.174752)
		(layer "F.Cu")
		(net "PE_CLK_100M_DR6_2_R_N")
	)
	(segment
		(start 96.827086 -310.976518)
		(end 97.813622 -311.963054)
		(width 0.174752)
		(layer "F.Cu")
		(net "PE_CLK_100M_DR6_2_R_N")
	)
	(segment
		(start 99.669346 -313.017154)
		(end 99.314 -313.3725)
		(width 0.174752)
		(layer "F.Cu")
		(net "PE_CLK_100M_DR6_2_R_N")
	)
	(segment
		(start 99.669346 -312.521346)
		(end 99.669346 -313.017154)
		(width 0.174752)
		(layer "F.Cu")
		(net "PE_CLK_100M_DR6_2_R_N")
	)
	(segment
		(start 96.827086 -310.526684)
		(end 96.827086 -310.976518)
		(width 0.174752)
		(layer "F.Cu")
		(net "PE_CLK_100M_DR6_2_R_N")
	)
	(segment
		(start 99.111054 -311.963054)
		(end 99.669346 -312.521346)
		(width 0.174752)
		(layer "F.Cu")
		(net "PE_CLK_100M_DR6_2_R_N")
	)
	(segment
		(start 96.1644 -311.9374)
		(end 95.132652 -310.905652)
		(width 0.174752)
		(layer "F.Cu")
		(net "PE_CLK_100M_DR6_1_R_P")
	)
	(segment
		(start 96.52 -313.3725)
		(end 96.1644 -313.0169)
		(width 0.174752)
		(layer "F.Cu")
		(net "PE_CLK_100M_DR6_1_R_P")
	)
	(segment
		(start 96.1644 -313.0169)
		(end 96.1644 -311.9374)
		(width 0.174752)
		(layer "F.Cu")
		(net "PE_CLK_100M_DR6_1_R_P")
	)
	(segment
		(start 95.132652 -310.905652)
		(end 95.132652 -310.526684)
		(width 0.174752)
		(layer "F.Cu")
		(net "PE_CLK_100M_DR6_1_R_P")
	)
	(segment
		(start 95.22968 -310.429656)
		(end 95.22968 -309.60441)
		(width 0.174752)
		(layer "F.Cu")
		(net "PE_CLK_100M_DR6_1_R_P")
	)
	(segment
		(start 95.132652 -310.526684)
		(end 95.22968 -310.429656)
		(width 0.174752)
		(layer "F.Cu")
		(net "PE_CLK_100M_DR6_1_R_P")
	)
	(segment
		(start 95.504 -313.3725)
		(end 95.859346 -313.017154)
		(width 0.174752)
		(layer "F.Cu")
		(net "PE_CLK_100M_DR6_1_R_N")
	)
	(segment
		(start 95.859346 -312.063892)
		(end 94.827598 -311.032144)
		(width 0.174752)
		(layer "F.Cu")
		(net "PE_CLK_100M_DR6_1_R_N")
	)
	(segment
		(start 94.827598 -311.032144)
		(end 94.827598 -310.526684)
		(width 0.174752)
		(layer "F.Cu")
		(net "PE_CLK_100M_DR6_1_R_N")
	)
	(segment
		(start 94.827598 -310.526684)
		(end 94.73057 -310.429656)
		(width 0.174752)
		(layer "F.Cu")
		(net "PE_CLK_100M_DR6_1_R_N")
	)
	(segment
		(start 94.73057 -310.429656)
		(end 94.73057 -309.60441)
		(width 0.174752)
		(layer "F.Cu")
		(net "PE_CLK_100M_DR6_1_R_N")
	)
	(segment
		(start 95.859346 -313.017154)
		(end 95.859346 -312.063892)
		(width 0.174752)
		(layer "F.Cu")
		(net "PE_CLK_100M_DR6_1_R_N")
	)
	(segment
		(start 92.63253 -437.007)
		(end 92.63253 -437.262016)
		(width 0.174752)
		(layer "F.Cu")
		(net "PE_CLK_100M_DR5_2_R_P")
	)
	(segment
		(start 92.73032 -436.22341)
		(end 92.73032 -436.90921)
		(width 0.174752)
		(layer "F.Cu")
		(net "PE_CLK_100M_DR5_2_R_P")
	)
	(segment
		(start 92.73032 -436.90921)
		(end 92.63253 -437.007)
		(width 0.174752)
		(layer "F.Cu")
		(net "PE_CLK_100M_DR5_2_R_P")
	)
	(segment
		(start 92.63253 -437.262016)
		(end 91.528646 -438.365646)
		(width 0.174752)
		(layer "F.Cu")
		(net "PE_CLK_100M_DR5_2_R_P")
	)
	(segment
		(start 90.9574 -438.937146)
		(end 90.9574 -439.6359)
		(width 0.174752)
		(layer "F.Cu")
		(net "PE_CLK_100M_DR5_2_R_P")
	)
	(segment
		(start 90.9574 -439.6359)
		(end 91.313 -439.9915)
		(width 0.174752)
		(layer "F.Cu")
		(net "PE_CLK_100M_DR5_2_R_P")
	)
	(segment
		(start 91.528646 -438.365646)
		(end 90.9574 -438.937146)
		(width 0.174752)
		(layer "F.Cu")
		(net "PE_CLK_100M_DR5_2_R_P")
	)
	(segment
		(start 91.312746 -438.149746)
		(end 91.026996 -438.435496)
		(width 0.174752)
		(layer "F.Cu")
		(net "PE_CLK_100M_DR5_2_R_N")
	)
	(segment
		(start 92.22994 -436.22341)
		(end 92.22994 -436.88)
		(width 0.174752)
		(layer "F.Cu")
		(net "PE_CLK_100M_DR5_2_R_N")
	)
	(segment
		(start 90.652346 -439.636154)
		(end 90.297 -439.9915)
		(width 0.174752)
		(layer "F.Cu")
		(net "PE_CLK_100M_DR5_2_R_N")
	)
	(segment
		(start 92.327476 -437.135524)
		(end 91.312746 -438.149746)
		(width 0.174752)
		(layer "F.Cu")
		(net "PE_CLK_100M_DR5_2_R_N")
	)
	(segment
		(start 92.327476 -436.977536)
		(end 92.327476 -437.135524)
		(width 0.174752)
		(layer "F.Cu")
		(net "PE_CLK_100M_DR5_2_R_N")
	)
	(segment
		(start 91.026996 -438.435496)
		(end 90.652346 -438.810654)
		(width 0.174752)
		(layer "F.Cu")
		(net "PE_CLK_100M_DR5_2_R_N")
	)
	(segment
		(start 92.22994 -436.88)
		(end 92.327476 -436.977536)
		(width 0.174752)
		(layer "F.Cu")
		(net "PE_CLK_100M_DR5_2_R_N")
	)
	(segment
		(start 90.652346 -438.810654)
		(end 90.652346 -439.636154)
		(width 0.174752)
		(layer "F.Cu")
		(net "PE_CLK_100M_DR5_2_R_N")
	)
	(segment
		(start 87.503 -439.9915)
		(end 87.173054 -439.661554)
		(width 0.174752)
		(layer "F.Cu")
		(net "PE_CLK_100M_DR5_1_R_P")
	)
	(segment
		(start 87.173054 -439.661554)
		(end 87.173054 -439.419492)
		(width 0.174752)
		(layer "F.Cu")
		(net "PE_CLK_100M_DR5_1_R_P")
	)
	(segment
		(start 90.73007 -437.02605)
		(end 90.73007 -436.22341)
		(width 0.174752)
		(layer "F.Cu")
		(net "PE_CLK_100M_DR5_1_R_P")
	)
	(segment
		(start 89.966546 -437.789574)
		(end 90.73007 -437.02605)
		(width 0.174752)
		(layer "F.Cu")
		(net "PE_CLK_100M_DR5_1_R_P")
	)
	(segment
		(start 88.802972 -437.789574)
		(end 89.966546 -437.789574)
		(width 0.174752)
		(layer "F.Cu")
		(net "PE_CLK_100M_DR5_1_R_P")
	)
	(segment
		(start 87.173054 -439.419492)
		(end 88.802972 -437.789574)
		(width 0.174752)
		(layer "F.Cu")
		(net "PE_CLK_100M_DR5_1_R_P")
	)
	(segment
		(start 90.22969 -437.094884)
		(end 89.840054 -437.48452)
		(width 0.174752)
		(layer "F.Cu")
		(net "PE_CLK_100M_DR5_1_R_N")
	)
	(segment
		(start 87.238586 -438.741566)
		(end 87.238586 -438.922414)
		(width 0.174752)
		(layer "F.Cu")
		(net "PE_CLK_100M_DR5_1_R_N")
	)
	(segment
		(start 90.22969 -436.350918)
		(end 90.22969 -437.094884)
		(width 0.174752)
		(layer "F.Cu")
		(net "PE_CLK_100M_DR5_1_R_N")
	)
	(segment
		(start 87.79002 -438.37098)
		(end 87.609426 -438.37098)
		(width 0.174752)
		(layer "F.Cu")
		(net "PE_CLK_100M_DR5_1_R_N")
	)
	(segment
		(start 86.868 -439.293)
		(end 86.868 -439.7502)
		(width 0.174752)
		(layer "F.Cu")
		(net "PE_CLK_100M_DR5_1_R_N")
	)
	(segment
		(start 87.238586 -438.922414)
		(end 86.868 -439.293)
		(width 0.174752)
		(layer "F.Cu")
		(net "PE_CLK_100M_DR5_1_R_N")
	)
	(segment
		(start 88.67648 -437.48452)
		(end 87.79002 -438.37098)
		(width 0.174752)
		(layer "F.Cu")
		(net "PE_CLK_100M_DR5_1_R_N")
	)
	(segment
		(start 87.609426 -438.37098)
		(end 87.238586 -438.741566)
		(width 0.174752)
		(layer "F.Cu")
		(net "PE_CLK_100M_DR5_1_R_N")
	)
	(segment
		(start 89.840054 -437.48452)
		(end 88.67648 -437.48452)
		(width 0.174752)
		(layer "F.Cu")
		(net "PE_CLK_100M_DR5_1_R_N")
	)
	(segment
		(start 86.868 -439.7502)
		(end 86.6267 -439.9915)
		(width 0.174752)
		(layer "F.Cu")
		(net "PE_CLK_100M_DR5_1_R_N")
	)
	(segment
		(start 86.6267 -439.9915)
		(end 86.487 -439.9915)
		(width 0.174752)
		(layer "F.Cu")
		(net "PE_CLK_100M_DR5_1_R_N")
	)
	(segment
		(start 94.82709 -204.986636)
		(end 94.208346 -204.367892)
		(width 0.174752)
		(layer "F.Cu")
		(net "PE_CLK_100M_DR4_2_R_P")
	)
	(segment
		(start 94.208346 -204.367892)
		(end 94.208346 -202.983846)
		(width 0.174752)
		(layer "F.Cu")
		(net "PE_CLK_100M_DR4_2_R_P")
	)
	(segment
		(start 94.73057 -205.70952)
		(end 94.82709 -205.613)
		(width 0.174752)
		(layer "F.Cu")
		(net "PE_CLK_100M_DR4_2_R_P")
	)
	(segment
		(start 94.208346 -202.983846)
		(end 93.853 -202.6285)
		(width 0.174752)
		(layer "F.Cu")
		(net "PE_CLK_100M_DR4_2_R_P")
	)
	(segment
		(start 94.82709 -205.613)
		(end 94.82709 -204.986636)
		(width 0.174752)
		(layer "F.Cu")
		(net "PE_CLK_100M_DR4_2_R_P")
	)
	(segment
		(start 94.73057 -206.39659)
		(end 94.73057 -205.70952)
		(width 0.174752)
		(layer "F.Cu")
		(net "PE_CLK_100M_DR4_2_R_P")
	)
	(segment
		(start 95.22968 -206.39659)
		(end 95.22968 -205.710536)
		(width 0.174752)
		(layer "F.Cu")
		(net "PE_CLK_100M_DR4_2_R_N")
	)
	(segment
		(start 95.132144 -204.860144)
		(end 94.5134 -204.2414)
		(width 0.174752)
		(layer "F.Cu")
		(net "PE_CLK_100M_DR4_2_R_N")
	)
	(segment
		(start 94.5134 -204.2414)
		(end 94.5134 -202.9841)
		(width 0.174752)
		(layer "F.Cu")
		(net "PE_CLK_100M_DR4_2_R_N")
	)
	(segment
		(start 94.5134 -202.9841)
		(end 94.869 -202.6285)
		(width 0.174752)
		(layer "F.Cu")
		(net "PE_CLK_100M_DR4_2_R_N")
	)
	(segment
		(start 95.22968 -205.710536)
		(end 95.132144 -205.613)
		(width 0.174752)
		(layer "F.Cu")
		(net "PE_CLK_100M_DR4_2_R_N")
	)
	(segment
		(start 95.132144 -205.613)
		(end 95.132144 -204.860144)
		(width 0.174752)
		(layer "F.Cu")
		(net "PE_CLK_100M_DR4_2_R_N")
	)
	(segment
		(start 96.857566 -204.462888)
		(end 98.018346 -203.302108)
		(width 0.174752)
		(layer "F.Cu")
		(net "PE_CLK_100M_DR4_1_R_P")
	)
	(segment
		(start 98.018346 -203.302108)
		(end 98.018346 -202.983846)
		(width 0.174752)
		(layer "F.Cu")
		(net "PE_CLK_100M_DR4_1_R_P")
	)
	(segment
		(start 96.857566 -205.611984)
		(end 96.857566 -204.462888)
		(width 0.174752)
		(layer "F.Cu")
		(net "PE_CLK_100M_DR4_1_R_P")
	)
	(segment
		(start 96.72955 -206.39659)
		(end 96.72955 -205.74)
		(width 0.174752)
		(layer "F.Cu")
		(net "PE_CLK_100M_DR4_1_R_P")
	)
	(segment
		(start 96.72955 -205.74)
		(end 96.857566 -205.611984)
		(width 0.174752)
		(layer "F.Cu")
		(net "PE_CLK_100M_DR4_1_R_P")
	)
	(segment
		(start 98.018346 -202.983846)
		(end 97.663 -202.6285)
		(width 0.174752)
		(layer "F.Cu")
		(net "PE_CLK_100M_DR4_1_R_P")
	)
	(segment
		(start 97.22993 -206.39659)
		(end 97.22993 -205.74)
		(width 0.174752)
		(layer "F.Cu")
		(net "PE_CLK_100M_DR4_1_R_N")
	)
	(segment
		(start 97.16262 -204.58938)
		(end 98.3234 -203.4286)
		(width 0.174752)
		(layer "F.Cu")
		(net "PE_CLK_100M_DR4_1_R_N")
	)
	(segment
		(start 98.3234 -203.4286)
		(end 98.3234 -202.9841)
		(width 0.174752)
		(layer "F.Cu")
		(net "PE_CLK_100M_DR4_1_R_N")
	)
	(segment
		(start 97.22993 -205.74)
		(end 97.16262 -205.67269)
		(width 0.174752)
		(layer "F.Cu")
		(net "PE_CLK_100M_DR4_1_R_N")
	)
	(segment
		(start 98.3234 -202.9841)
		(end 98.679 -202.6285)
		(width 0.174752)
		(layer "F.Cu")
		(net "PE_CLK_100M_DR4_1_R_N")
	)
	(segment
		(start 97.16262 -205.67269)
		(end 97.16262 -204.58938)
		(width 0.174752)
		(layer "F.Cu")
		(net "PE_CLK_100M_DR4_1_R_N")
	)
	(segment
		(start 100.786946 -205.232508)
		(end 101.193854 -204.8256)
		(width 0.174752)
		(layer "F.Cu")
		(net "PE_CLK_100M_DR3_2_R_P")
	)
	(segment
		(start 98.40341 -207.57007)
		(end 99.06 -207.57007)
		(width 0.174752)
		(layer "F.Cu")
		(net "PE_CLK_100M_DR3_2_R_P")
	)
	(segment
		(start 100.786946 -206.172054)
		(end 100.786946 -205.232508)
		(width 0.174752)
		(layer "F.Cu")
		(net "PE_CLK_100M_DR3_2_R_P")
	)
	(segment
		(start 101.193854 -204.8256)
		(end 101.8159 -204.8256)
		(width 0.174752)
		(layer "F.Cu")
		(net "PE_CLK_100M_DR3_2_R_P")
	)
	(segment
		(start 99.15779 -207.66786)
		(end 99.29114 -207.66786)
		(width 0.174752)
		(layer "F.Cu")
		(net "PE_CLK_100M_DR3_2_R_P")
	)
	(segment
		(start 101.8159 -204.8256)
		(end 102.1715 -204.47)
		(width 0.174752)
		(layer "F.Cu")
		(net "PE_CLK_100M_DR3_2_R_P")
	)
	(segment
		(start 99.06 -207.57007)
		(end 99.15779 -207.66786)
		(width 0.174752)
		(layer "F.Cu")
		(net "PE_CLK_100M_DR3_2_R_P")
	)
	(segment
		(start 99.29114 -207.66786)
		(end 100.786946 -206.172054)
		(width 0.174752)
		(layer "F.Cu")
		(net "PE_CLK_100M_DR3_2_R_P")
	)
	(segment
		(start 101.092 -206.298546)
		(end 101.092 -205.359)
		(width 0.174752)
		(layer "F.Cu")
		(net "PE_CLK_100M_DR3_2_R_N")
	)
	(segment
		(start 99.06 -208.07045)
		(end 99.157536 -207.972914)
		(width 0.174752)
		(layer "F.Cu")
		(net "PE_CLK_100M_DR3_2_R_N")
	)
	(segment
		(start 101.816154 -205.130654)
		(end 102.1715 -205.486)
		(width 0.174752)
		(layer "F.Cu")
		(net "PE_CLK_100M_DR3_2_R_N")
	)
	(segment
		(start 99.157536 -207.972914)
		(end 99.417632 -207.972914)
		(width 0.174752)
		(layer "F.Cu")
		(net "PE_CLK_100M_DR3_2_R_N")
	)
	(segment
		(start 101.320346 -205.130654)
		(end 101.816154 -205.130654)
		(width 0.174752)
		(layer "F.Cu")
		(net "PE_CLK_100M_DR3_2_R_N")
	)
	(segment
		(start 99.417632 -207.972914)
		(end 101.092 -206.298546)
		(width 0.174752)
		(layer "F.Cu")
		(net "PE_CLK_100M_DR3_2_R_N")
	)
	(segment
		(start 98.40341 -208.07045)
		(end 99.06 -208.07045)
		(width 0.174752)
		(layer "F.Cu")
		(net "PE_CLK_100M_DR3_2_R_N")
	)
	(segment
		(start 101.092 -205.359)
		(end 101.320346 -205.130654)
		(width 0.174752)
		(layer "F.Cu")
		(net "PE_CLK_100M_DR3_2_R_N")
	)
	(segment
		(start 99.06 -209.57032)
		(end 98.40341 -209.57032)
		(width 0.174752)
		(layer "F.Cu")
		(net "PE_CLK_100M_DR3_1_R_P")
	)
	(segment
		(start 101.841554 -208.609946)
		(end 101.016054 -208.609946)
		(width 0.174752)
		(layer "F.Cu")
		(net "PE_CLK_100M_DR3_1_R_P")
	)
	(segment
		(start 99.958652 -209.667348)
		(end 99.157028 -209.667348)
		(width 0.174752)
		(layer "F.Cu")
		(net "PE_CLK_100M_DR3_1_R_P")
	)
	(segment
		(start 99.157028 -209.667348)
		(end 99.06 -209.57032)
		(width 0.174752)
		(layer "F.Cu")
		(net "PE_CLK_100M_DR3_1_R_P")
	)
	(segment
		(start 101.016054 -208.609946)
		(end 99.958652 -209.667348)
		(width 0.174752)
		(layer "F.Cu")
		(net "PE_CLK_100M_DR3_1_R_P")
	)
	(segment
		(start 102.1715 -208.28)
		(end 101.841554 -208.609946)
		(width 0.174752)
		(layer "F.Cu")
		(net "PE_CLK_100M_DR3_1_R_P")
	)
	(segment
		(start 99.06 -210.06943)
		(end 98.40341 -210.06943)
		(width 0.174752)
		(layer "F.Cu")
		(net "PE_CLK_100M_DR3_1_R_N")
	)
	(segment
		(start 102.1715 -209.296)
		(end 101.7905 -208.915)
		(width 0.174752)
		(layer "F.Cu")
		(net "PE_CLK_100M_DR3_1_R_N")
	)
	(segment
		(start 100.085144 -209.972402)
		(end 99.157028 -209.972402)
		(width 0.174752)
		(layer "F.Cu")
		(net "PE_CLK_100M_DR3_1_R_N")
	)
	(segment
		(start 99.157028 -209.972402)
		(end 99.06 -210.06943)
		(width 0.174752)
		(layer "F.Cu")
		(net "PE_CLK_100M_DR3_1_R_N")
	)
	(segment
		(start 101.7905 -208.915)
		(end 101.142546 -208.915)
		(width 0.174752)
		(layer "F.Cu")
		(net "PE_CLK_100M_DR3_1_R_N")
	)
	(segment
		(start 101.142546 -208.915)
		(end 100.085144 -209.972402)
		(width 0.174752)
		(layer "F.Cu")
		(net "PE_CLK_100M_DR3_1_R_N")
	)
	(segment
		(start 94.827598 -299.507402)
		(end 95.859346 -298.475654)
		(width 0.174752)
		(layer "F.Cu")
		(net "PE_CLK_100M_DR2_2_R_P")
	)
	(segment
		(start 95.859346 -298.475654)
		(end 95.859346 -297.344846)
		(width 0.174752)
		(layer "F.Cu")
		(net "PE_CLK_100M_DR2_2_R_P")
	)
	(segment
		(start 94.73057 -300.75759)
		(end 94.73057 -299.932344)
		(width 0.174752)
		(layer "F.Cu")
		(net "PE_CLK_100M_DR2_2_R_P")
	)
	(segment
		(start 95.859346 -297.344846)
		(end 95.504 -296.9895)
		(width 0.174752)
		(layer "F.Cu")
		(net "PE_CLK_100M_DR2_2_R_P")
	)
	(segment
		(start 94.827598 -299.835316)
		(end 94.827598 -299.507402)
		(width 0.174752)
		(layer "F.Cu")
		(net "PE_CLK_100M_DR2_2_R_P")
	)
	(segment
		(start 94.73057 -299.932344)
		(end 94.827598 -299.835316)
		(width 0.174752)
		(layer "F.Cu")
		(net "PE_CLK_100M_DR2_2_R_P")
	)
	(segment
		(start 96.52 -296.9895)
		(end 96.1644 -297.3451)
		(width 0.174752)
		(layer "F.Cu")
		(net "PE_CLK_100M_DR2_2_R_N")
	)
	(segment
		(start 96.1644 -297.3451)
		(end 96.1644 -298.602146)
		(width 0.174752)
		(layer "F.Cu")
		(net "PE_CLK_100M_DR2_2_R_N")
	)
	(segment
		(start 95.132652 -299.835316)
		(end 95.22968 -299.932344)
		(width 0.174752)
		(layer "F.Cu")
		(net "PE_CLK_100M_DR2_2_R_N")
	)
	(segment
		(start 95.132652 -299.633894)
		(end 95.132652 -299.835316)
		(width 0.174752)
		(layer "F.Cu")
		(net "PE_CLK_100M_DR2_2_R_N")
	)
	(segment
		(start 96.1644 -298.602146)
		(end 95.132652 -299.633894)
		(width 0.174752)
		(layer "F.Cu")
		(net "PE_CLK_100M_DR2_2_R_N")
	)
	(segment
		(start 95.22968 -299.932344)
		(end 95.22968 -300.75759)
		(width 0.174752)
		(layer "F.Cu")
		(net "PE_CLK_100M_DR2_2_R_N")
	)
	(segment
		(start 99.296474 -298.322746)
		(end 99.669346 -297.949874)
		(width 0.174752)
		(layer "F.Cu")
		(net "PE_CLK_100M_DR2_1_R_P")
	)
	(segment
		(start 96.827086 -299.489368)
		(end 97.993708 -298.322746)
		(width 0.174752)
		(layer "F.Cu")
		(net "PE_CLK_100M_DR2_1_R_P")
	)
	(segment
		(start 96.72955 -299.932852)
		(end 96.827086 -299.835316)
		(width 0.174752)
		(layer "F.Cu")
		(net "PE_CLK_100M_DR2_1_R_P")
	)
	(segment
		(start 99.669346 -297.949874)
		(end 99.669346 -297.344846)
		(width 0.174752)
		(layer "F.Cu")
		(net "PE_CLK_100M_DR2_1_R_P")
	)
	(segment
		(start 99.669346 -297.344846)
		(end 99.314 -296.9895)
		(width 0.174752)
		(layer "F.Cu")
		(net "PE_CLK_100M_DR2_1_R_P")
	)
	(segment
		(start 97.993708 -298.322746)
		(end 99.296474 -298.322746)
		(width 0.174752)
		(layer "F.Cu")
		(net "PE_CLK_100M_DR2_1_R_P")
	)
	(segment
		(start 96.72955 -300.75759)
		(end 96.72955 -299.932852)
		(width 0.174752)
		(layer "F.Cu")
		(net "PE_CLK_100M_DR2_1_R_P")
	)
	(segment
		(start 96.827086 -299.835316)
		(end 96.827086 -299.489368)
		(width 0.174752)
		(layer "F.Cu")
		(net "PE_CLK_100M_DR2_1_R_P")
	)
	(segment
		(start 97.13214 -299.835316)
		(end 97.13214 -299.61586)
		(width 0.174752)
		(layer "F.Cu")
		(net "PE_CLK_100M_DR2_1_R_N")
	)
	(segment
		(start 97.22993 -299.933106)
		(end 97.13214 -299.835316)
		(width 0.174752)
		(layer "F.Cu")
		(net "PE_CLK_100M_DR2_1_R_N")
	)
	(segment
		(start 98.1202 -298.6278)
		(end 99.422966 -298.6278)
		(width 0.174752)
		(layer "F.Cu")
		(net "PE_CLK_100M_DR2_1_R_N")
	)
	(segment
		(start 99.422966 -298.6278)
		(end 99.9744 -298.076366)
		(width 0.174752)
		(layer "F.Cu")
		(net "PE_CLK_100M_DR2_1_R_N")
	)
	(segment
		(start 97.22993 -300.75759)
		(end 97.22993 -299.933106)
		(width 0.174752)
		(layer "F.Cu")
		(net "PE_CLK_100M_DR2_1_R_N")
	)
	(segment
		(start 99.9744 -297.3451)
		(end 100.33 -296.9895)
		(width 0.174752)
		(layer "F.Cu")
		(net "PE_CLK_100M_DR2_1_R_N")
	)
	(segment
		(start 99.9744 -298.076366)
		(end 99.9744 -297.3451)
		(width 0.174752)
		(layer "F.Cu")
		(net "PE_CLK_100M_DR2_1_R_N")
	)
	(segment
		(start 97.13214 -299.61586)
		(end 98.1202 -298.6278)
		(width 0.174752)
		(layer "F.Cu")
		(net "PE_CLK_100M_DR2_1_R_N")
	)
	(segment
		(start 94.73057 -97.17659)
		(end 94.73057 -96.52)
		(width 0.174752)
		(layer "F.Cu")
		(net "PE_CLK_100M_DR14_2_R_P")
	)
	(segment
		(start 94.82709 -95.876364)
		(end 95.859346 -94.844108)
		(width 0.174752)
		(layer "F.Cu")
		(net "PE_CLK_100M_DR14_2_R_P")
	)
	(segment
		(start 95.859346 -93.763846)
		(end 95.504 -93.4085)
		(width 0.174752)
		(layer "F.Cu")
		(net "PE_CLK_100M_DR14_2_R_P")
	)
	(segment
		(start 94.82709 -96.42348)
		(end 94.82709 -95.876364)
		(width 0.174752)
		(layer "F.Cu")
		(net "PE_CLK_100M_DR14_2_R_P")
	)
	(segment
		(start 95.859346 -94.844108)
		(end 95.859346 -93.763846)
		(width 0.174752)
		(layer "F.Cu")
		(net "PE_CLK_100M_DR14_2_R_P")
	)
	(segment
		(start 94.73057 -96.52)
		(end 94.82709 -96.42348)
		(width 0.174752)
		(layer "F.Cu")
		(net "PE_CLK_100M_DR14_2_R_P")
	)
	(segment
		(start 95.132144 -96.422464)
		(end 95.132144 -96.002856)
		(width 0.174752)
		(layer "F.Cu")
		(net "PE_CLK_100M_DR14_2_R_N")
	)
	(segment
		(start 95.132144 -96.002856)
		(end 96.1644 -94.9706)
		(width 0.174752)
		(layer "F.Cu")
		(net "PE_CLK_100M_DR14_2_R_N")
	)
	(segment
		(start 96.1644 -93.7641)
		(end 96.52 -93.4085)
		(width 0.174752)
		(layer "F.Cu")
		(net "PE_CLK_100M_DR14_2_R_N")
	)
	(segment
		(start 95.22968 -97.17659)
		(end 95.22968 -96.52)
		(width 0.174752)
		(layer "F.Cu")
		(net "PE_CLK_100M_DR14_2_R_N")
	)
	(segment
		(start 95.22968 -96.52)
		(end 95.132144 -96.422464)
		(width 0.174752)
		(layer "F.Cu")
		(net "PE_CLK_100M_DR14_2_R_N")
	)
	(segment
		(start 96.1644 -94.9706)
		(end 96.1644 -93.7641)
		(width 0.174752)
		(layer "F.Cu")
		(net "PE_CLK_100M_DR14_2_R_N")
	)
	(segment
		(start 96.72955 -96.352106)
		(end 96.72955 -97.17659)
		(width 0.174752)
		(layer "F.Cu")
		(net "PE_CLK_100M_DR14_1_R_P")
	)
	(segment
		(start 96.82734 -96.254316)
		(end 96.72955 -96.352106)
		(width 0.174752)
		(layer "F.Cu")
		(net "PE_CLK_100M_DR14_1_R_P")
	)
	(segment
		(start 98.247962 -94.411546)
		(end 97.2566 -95.402654)
		(width 0.174752)
		(layer "F.Cu")
		(net "PE_CLK_100M_DR14_1_R_P")
	)
	(segment
		(start 97.2566 -95.402654)
		(end 96.82734 -95.832168)
		(width 0.174752)
		(layer "F.Cu")
		(net "PE_CLK_100M_DR14_1_R_P")
	)
	(segment
		(start 99.314 -93.4085)
		(end 99.669346 -93.763846)
		(width 0.174752)
		(layer "F.Cu")
		(net "PE_CLK_100M_DR14_1_R_P")
	)
	(segment
		(start 96.82734 -95.832168)
		(end 96.82734 -96.254316)
		(width 0.174752)
		(layer "F.Cu")
		(net "PE_CLK_100M_DR14_1_R_P")
	)
	(segment
		(start 99.423474 -94.411546)
		(end 98.247962 -94.411546)
		(width 0.174752)
		(layer "F.Cu")
		(net "PE_CLK_100M_DR14_1_R_P")
	)
	(segment
		(start 99.669346 -94.165674)
		(end 99.423474 -94.411546)
		(width 0.174752)
		(layer "F.Cu")
		(net "PE_CLK_100M_DR14_1_R_P")
	)
	(segment
		(start 99.669346 -93.763846)
		(end 99.669346 -94.165674)
		(width 0.174752)
		(layer "F.Cu")
		(net "PE_CLK_100M_DR14_1_R_P")
	)
	(segment
		(start 99.549966 -94.7166)
		(end 99.9744 -94.292166)
		(width 0.174752)
		(layer "F.Cu")
		(net "PE_CLK_100M_DR14_1_R_N")
	)
	(segment
		(start 97.22993 -97.17659)
		(end 97.22993 -96.351852)
		(width 0.174752)
		(layer "F.Cu")
		(net "PE_CLK_100M_DR14_1_R_N")
	)
	(segment
		(start 99.9744 -93.7641)
		(end 100.33 -93.4085)
		(width 0.174752)
		(layer "F.Cu")
		(net "PE_CLK_100M_DR14_1_R_N")
	)
	(segment
		(start 97.132394 -95.95866)
		(end 98.374454 -94.7166)
		(width 0.174752)
		(layer "F.Cu")
		(net "PE_CLK_100M_DR14_1_R_N")
	)
	(segment
		(start 97.22993 -96.351852)
		(end 97.132394 -96.254316)
		(width 0.174752)
		(layer "F.Cu")
		(net "PE_CLK_100M_DR14_1_R_N")
	)
	(segment
		(start 98.374454 -94.7166)
		(end 99.549966 -94.7166)
		(width 0.174752)
		(layer "F.Cu")
		(net "PE_CLK_100M_DR14_1_R_N")
	)
	(segment
		(start 99.9744 -94.292166)
		(end 99.9744 -93.7641)
		(width 0.174752)
		(layer "F.Cu")
		(net "PE_CLK_100M_DR14_1_R_N")
	)
	(segment
		(start 97.132394 -96.254316)
		(end 97.132394 -95.95866)
		(width 0.174752)
		(layer "F.Cu")
		(net "PE_CLK_100M_DR14_1_R_N")
	)
	(segment
		(start 92.63253 -106.807)
		(end 92.63253 -107.13847)
		(width 0.174752)
		(layer "F.Cu")
		(net "PE_CLK_100M_DR13_2_R_P")
	)
	(segment
		(start 92.63253 -107.13847)
		(end 90.9574 -108.8136)
		(width 0.174752)
		(layer "F.Cu")
		(net "PE_CLK_100M_DR13_2_R_P")
	)
	(segment
		(start 90.9574 -108.8136)
		(end 90.9574 -109.4359)
		(width 0.174752)
		(layer "F.Cu")
		(net "PE_CLK_100M_DR13_2_R_P")
	)
	(segment
		(start 92.73032 -106.70921)
		(end 92.63253 -106.807)
		(width 0.174752)
		(layer "F.Cu")
		(net "PE_CLK_100M_DR13_2_R_P")
	)
	(segment
		(start 92.73032 -106.02341)
		(end 92.73032 -106.70921)
		(width 0.174752)
		(layer "F.Cu")
		(net "PE_CLK_100M_DR13_2_R_P")
	)
	(segment
		(start 90.9574 -109.4359)
		(end 91.313 -109.7915)
		(width 0.174752)
		(layer "F.Cu")
		(net "PE_CLK_100M_DR13_2_R_P")
	)
	(segment
		(start 92.327476 -106.807)
		(end 92.327476 -107.011978)
		(width 0.174752)
		(layer "F.Cu")
		(net "PE_CLK_100M_DR13_2_R_N")
	)
	(segment
		(start 92.22994 -106.709464)
		(end 92.327476 -106.807)
		(width 0.174752)
		(layer "F.Cu")
		(net "PE_CLK_100M_DR13_2_R_N")
	)
	(segment
		(start 90.652346 -108.687108)
		(end 90.652346 -109.436154)
		(width 0.174752)
		(layer "F.Cu")
		(net "PE_CLK_100M_DR13_2_R_N")
	)
	(segment
		(start 92.22994 -106.02341)
		(end 92.22994 -106.709464)
		(width 0.174752)
		(layer "F.Cu")
		(net "PE_CLK_100M_DR13_2_R_N")
	)
	(segment
		(start 92.327476 -107.011978)
		(end 90.652346 -108.687108)
		(width 0.174752)
		(layer "F.Cu")
		(net "PE_CLK_100M_DR13_2_R_N")
	)
	(segment
		(start 90.652346 -109.436154)
		(end 90.297 -109.7915)
		(width 0.174752)
		(layer "F.Cu")
		(net "PE_CLK_100M_DR13_2_R_N")
	)
	(segment
		(start 90.627454 -107.111292)
		(end 89.128346 -108.6104)
		(width 0.174752)
		(layer "F.Cu")
		(net "PE_CLK_100M_DR13_1_R_P")
	)
	(segment
		(start 87.1474 -109.4359)
		(end 87.503 -109.7915)
		(width 0.174752)
		(layer "F.Cu")
		(net "PE_CLK_100M_DR13_1_R_P")
	)
	(segment
		(start 87.1474 -109.118146)
		(end 87.1474 -109.4359)
		(width 0.174752)
		(layer "F.Cu")
		(net "PE_CLK_100M_DR13_1_R_P")
	)
	(segment
		(start 89.128346 -108.6104)
		(end 87.655146 -108.6104)
		(width 0.174752)
		(layer "F.Cu")
		(net "PE_CLK_100M_DR13_1_R_P")
	)
	(segment
		(start 90.73007 -106.02341)
		(end 90.73007 -106.70413)
		(width 0.174752)
		(layer "F.Cu")
		(net "PE_CLK_100M_DR13_1_R_P")
	)
	(segment
		(start 90.627454 -106.806746)
		(end 90.627454 -107.111292)
		(width 0.174752)
		(layer "F.Cu")
		(net "PE_CLK_100M_DR13_1_R_P")
	)
	(segment
		(start 87.655146 -108.6104)
		(end 87.1474 -109.118146)
		(width 0.174752)
		(layer "F.Cu")
		(net "PE_CLK_100M_DR13_1_R_P")
	)
	(segment
		(start 90.73007 -106.70413)
		(end 90.627454 -106.806746)
		(width 0.174752)
		(layer "F.Cu")
		(net "PE_CLK_100M_DR13_1_R_P")
	)
	(segment
		(start 90.3224 -106.8324)
		(end 90.22969 -106.73969)
		(width 0.174752)
		(layer "F.Cu")
		(net "PE_CLK_100M_DR13_1_R_N")
	)
	(segment
		(start 86.842346 -109.474254)
		(end 86.842346 -108.991654)
		(width 0.174752)
		(layer "F.Cu")
		(net "PE_CLK_100M_DR13_1_R_N")
	)
	(segment
		(start 86.842346 -108.991654)
		(end 87.528654 -108.305346)
		(width 0.174752)
		(layer "F.Cu")
		(net "PE_CLK_100M_DR13_1_R_N")
	)
	(segment
		(start 89.37244 -107.753912)
		(end 89.74328 -107.383326)
		(width 0.174752)
		(layer "F.Cu")
		(net "PE_CLK_100M_DR13_1_R_N")
	)
	(segment
		(start 89.923874 -107.383326)
		(end 90.3224 -106.9848)
		(width 0.174752)
		(layer "F.Cu")
		(net "PE_CLK_100M_DR13_1_R_N")
	)
	(segment
		(start 86.487 -109.7915)
		(end 86.5251 -109.7915)
		(width 0.174752)
		(layer "F.Cu")
		(net "PE_CLK_100M_DR13_1_R_N")
	)
	(segment
		(start 86.5251 -109.7915)
		(end 86.842346 -109.474254)
		(width 0.174752)
		(layer "F.Cu")
		(net "PE_CLK_100M_DR13_1_R_N")
	)
	(segment
		(start 89.74328 -107.383326)
		(end 89.923874 -107.383326)
		(width 0.174752)
		(layer "F.Cu")
		(net "PE_CLK_100M_DR13_1_R_N")
	)
	(segment
		(start 90.3224 -106.9848)
		(end 90.3224 -106.8324)
		(width 0.174752)
		(layer "F.Cu")
		(net "PE_CLK_100M_DR13_1_R_N")
	)
	(segment
		(start 87.528654 -108.305346)
		(end 89.001854 -108.305346)
		(width 0.174752)
		(layer "F.Cu")
		(net "PE_CLK_100M_DR13_1_R_N")
	)
	(segment
		(start 89.37244 -107.93476)
		(end 89.37244 -107.753912)
		(width 0.174752)
		(layer "F.Cu")
		(net "PE_CLK_100M_DR13_1_R_N")
	)
	(segment
		(start 89.001854 -108.305346)
		(end 89.37244 -107.93476)
		(width 0.174752)
		(layer "F.Cu")
		(net "PE_CLK_100M_DR13_1_R_N")
	)
	(segment
		(start 90.22969 -106.73969)
		(end 90.22969 -106.150918)
		(width 0.174752)
		(layer "F.Cu")
		(net "PE_CLK_100M_DR13_1_R_N")
	)
	(segment
		(start 92.63253 -216.027)
		(end 92.63253 -216.282016)
		(width 0.174752)
		(layer "F.Cu")
		(net "PE_CLK_100M_DR12_2_R_P")
	)
	(segment
		(start 92.73032 -215.24341)
		(end 92.73032 -215.92921)
		(width 0.174752)
		(layer "F.Cu")
		(net "PE_CLK_100M_DR12_2_R_P")
	)
	(segment
		(start 90.9574 -218.6559)
		(end 91.313 -219.0115)
		(width 0.174752)
		(layer "F.Cu")
		(net "PE_CLK_100M_DR12_2_R_P")
	)
	(segment
		(start 92.73032 -215.92921)
		(end 92.63253 -216.027)
		(width 0.174752)
		(layer "F.Cu")
		(net "PE_CLK_100M_DR12_2_R_P")
	)
	(segment
		(start 90.9574 -217.957146)
		(end 90.9574 -218.6559)
		(width 0.174752)
		(layer "F.Cu")
		(net "PE_CLK_100M_DR12_2_R_P")
	)
	(segment
		(start 92.63253 -216.282016)
		(end 90.9574 -217.957146)
		(width 0.174752)
		(layer "F.Cu")
		(net "PE_CLK_100M_DR12_2_R_P")
	)
	(segment
		(start 92.22994 -215.24341)
		(end 92.22994 -215.9)
		(width 0.174752)
		(layer "F.Cu")
		(net "PE_CLK_100M_DR12_2_R_N")
	)
	(segment
		(start 92.327476 -215.997536)
		(end 92.327476 -216.155524)
		(width 0.174752)
		(layer "F.Cu")
		(net "PE_CLK_100M_DR12_2_R_N")
	)
	(segment
		(start 92.22994 -215.9)
		(end 92.327476 -215.997536)
		(width 0.174752)
		(layer "F.Cu")
		(net "PE_CLK_100M_DR12_2_R_N")
	)
	(segment
		(start 91.642946 -216.8398)
		(end 90.652346 -217.830654)
		(width 0.174752)
		(layer "F.Cu")
		(net "PE_CLK_100M_DR12_2_R_N")
	)
	(segment
		(start 90.652346 -217.830654)
		(end 90.652346 -218.656154)
		(width 0.174752)
		(layer "F.Cu")
		(net "PE_CLK_100M_DR12_2_R_N")
	)
	(segment
		(start 90.652346 -218.656154)
		(end 90.297 -219.0115)
		(width 0.174752)
		(layer "F.Cu")
		(net "PE_CLK_100M_DR12_2_R_N")
	)
	(segment
		(start 92.327476 -216.155524)
		(end 91.642946 -216.8398)
		(width 0.174752)
		(layer "F.Cu")
		(net "PE_CLK_100M_DR12_2_R_N")
	)
	(segment
		(start 87.1474 -218.338146)
		(end 87.1474 -218.6559)
		(width 0.174752)
		(layer "F.Cu")
		(net "PE_CLK_100M_DR12_1_R_P")
	)
	(segment
		(start 90.73007 -215.24341)
		(end 90.73007 -215.94953)
		(width 0.174752)
		(layer "F.Cu")
		(net "PE_CLK_100M_DR12_1_R_P")
	)
	(segment
		(start 90.6018 -216.0778)
		(end 90.6018 -216.3826)
		(width 0.174752)
		(layer "F.Cu")
		(net "PE_CLK_100M_DR12_1_R_P")
	)
	(segment
		(start 88.848946 -218.135454)
		(end 87.350092 -218.135454)
		(width 0.174752)
		(layer "F.Cu")
		(net "PE_CLK_100M_DR12_1_R_P")
	)
	(segment
		(start 87.350092 -218.135454)
		(end 87.1474 -218.338146)
		(width 0.174752)
		(layer "F.Cu")
		(net "PE_CLK_100M_DR12_1_R_P")
	)
	(segment
		(start 90.73007 -215.94953)
		(end 90.6018 -216.0778)
		(width 0.174752)
		(layer "F.Cu")
		(net "PE_CLK_100M_DR12_1_R_P")
	)
	(segment
		(start 87.1474 -218.6559)
		(end 87.503 -219.0115)
		(width 0.174752)
		(layer "F.Cu")
		(net "PE_CLK_100M_DR12_1_R_P")
	)
	(segment
		(start 90.6018 -216.3826)
		(end 88.848946 -218.135454)
		(width 0.174752)
		(layer "F.Cu")
		(net "PE_CLK_100M_DR12_1_R_P")
	)
	(segment
		(start 89.09304 -217.278966)
		(end 89.46388 -216.90838)
		(width 0.174752)
		(layer "F.Cu")
		(net "PE_CLK_100M_DR12_1_R_N")
	)
	(segment
		(start 89.644474 -216.90838)
		(end 90.296746 -216.256108)
		(width 0.174752)
		(layer "F.Cu")
		(net "PE_CLK_100M_DR12_1_R_N")
	)
	(segment
		(start 90.296746 -216.256108)
		(end 90.296746 -216.0524)
		(width 0.174752)
		(layer "F.Cu")
		(net "PE_CLK_100M_DR12_1_R_N")
	)
	(segment
		(start 89.09304 -217.459814)
		(end 89.09304 -217.278966)
		(width 0.174752)
		(layer "F.Cu")
		(net "PE_CLK_100M_DR12_1_R_N")
	)
	(segment
		(start 90.22969 -215.985344)
		(end 90.22969 -215.370918)
		(width 0.174752)
		(layer "F.Cu")
		(net "PE_CLK_100M_DR12_1_R_N")
	)
	(segment
		(start 86.487 -219.0115)
		(end 86.5759 -219.0115)
		(width 0.174752)
		(layer "F.Cu")
		(net "PE_CLK_100M_DR12_1_R_N")
	)
	(segment
		(start 86.842346 -218.211654)
		(end 87.2236 -217.8304)
		(width 0.174752)
		(layer "F.Cu")
		(net "PE_CLK_100M_DR12_1_R_N")
	)
	(segment
		(start 86.5759 -219.0115)
		(end 86.842346 -218.745054)
		(width 0.174752)
		(layer "F.Cu")
		(net "PE_CLK_100M_DR12_1_R_N")
	)
	(segment
		(start 88.722454 -217.8304)
		(end 89.09304 -217.459814)
		(width 0.174752)
		(layer "F.Cu")
		(net "PE_CLK_100M_DR12_1_R_N")
	)
	(segment
		(start 89.46388 -216.90838)
		(end 89.644474 -216.90838)
		(width 0.174752)
		(layer "F.Cu")
		(net "PE_CLK_100M_DR12_1_R_N")
	)
	(segment
		(start 86.842346 -218.745054)
		(end 86.842346 -218.211654)
		(width 0.174752)
		(layer "F.Cu")
		(net "PE_CLK_100M_DR12_1_R_N")
	)
	(segment
		(start 90.296746 -216.0524)
		(end 90.22969 -215.985344)
		(width 0.174752)
		(layer "F.Cu")
		(net "PE_CLK_100M_DR12_1_R_N")
	)
	(segment
		(start 87.2236 -217.8304)
		(end 88.722454 -217.8304)
		(width 0.174752)
		(layer "F.Cu")
		(net "PE_CLK_100M_DR12_1_R_N")
	)
	(segment
		(start 92.73032 -309.60441)
		(end 92.73032 -310.429148)
		(width 0.174752)
		(layer "F.Cu")
		(net "PE_CLK_100M_DR11_2_R_P")
	)
	(segment
		(start 90.9574 -313.0169)
		(end 91.313 -313.3725)
		(width 0.174752)
		(layer "F.Cu")
		(net "PE_CLK_100M_DR11_2_R_P")
	)
	(segment
		(start 92.632784 -310.526684)
		(end 92.632784 -310.897016)
		(width 0.174752)
		(layer "F.Cu")
		(net "PE_CLK_100M_DR11_2_R_P")
	)
	(segment
		(start 92.227146 -311.302654)
		(end 91.998546 -311.302654)
		(width 0.174752)
		(layer "F.Cu")
		(net "PE_CLK_100M_DR11_2_R_P")
	)
	(segment
		(start 90.9574 -312.3438)
		(end 90.9574 -313.0169)
		(width 0.174752)
		(layer "F.Cu")
		(net "PE_CLK_100M_DR11_2_R_P")
	)
	(segment
		(start 92.73032 -310.429148)
		(end 92.632784 -310.526684)
		(width 0.174752)
		(layer "F.Cu")
		(net "PE_CLK_100M_DR11_2_R_P")
	)
	(segment
		(start 92.632784 -310.897016)
		(end 92.227146 -311.302654)
		(width 0.174752)
		(layer "F.Cu")
		(net "PE_CLK_100M_DR11_2_R_P")
	)
	(segment
		(start 91.998546 -311.302654)
		(end 90.9574 -312.3438)
		(width 0.174752)
		(layer "F.Cu")
		(net "PE_CLK_100M_DR11_2_R_P")
	)
	(segment
		(start 92.22994 -310.428894)
		(end 92.32773 -310.526684)
		(width 0.174752)
		(layer "F.Cu")
		(net "PE_CLK_100M_DR11_2_R_N")
	)
	(segment
		(start 92.32773 -310.770524)
		(end 92.100654 -310.9976)
		(width 0.174752)
		(layer "F.Cu")
		(net "PE_CLK_100M_DR11_2_R_N")
	)
	(segment
		(start 90.652346 -312.217308)
		(end 90.652346 -313.017154)
		(width 0.174752)
		(layer "F.Cu")
		(net "PE_CLK_100M_DR11_2_R_N")
	)
	(segment
		(start 91.872054 -310.9976)
		(end 90.652346 -312.217308)
		(width 0.174752)
		(layer "F.Cu")
		(net "PE_CLK_100M_DR11_2_R_N")
	)
	(segment
		(start 92.100654 -310.9976)
		(end 91.872054 -310.9976)
		(width 0.174752)
		(layer "F.Cu")
		(net "PE_CLK_100M_DR11_2_R_N")
	)
	(segment
		(start 92.32773 -310.526684)
		(end 92.32773 -310.770524)
		(width 0.174752)
		(layer "F.Cu")
		(net "PE_CLK_100M_DR11_2_R_N")
	)
	(segment
		(start 90.652346 -313.017154)
		(end 90.297 -313.3725)
		(width 0.174752)
		(layer "F.Cu")
		(net "PE_CLK_100M_DR11_2_R_N")
	)
	(segment
		(start 92.22994 -309.60441)
		(end 92.22994 -310.428894)
		(width 0.174752)
		(layer "F.Cu")
		(net "PE_CLK_100M_DR11_2_R_N")
	)
	(segment
		(start 87.1474 -313.0169)
		(end 87.503 -313.3725)
		(width 0.174752)
		(layer "F.Cu")
		(net "PE_CLK_100M_DR11_1_R_P")
	)
	(segment
		(start 87.1474 -312.6486)
		(end 87.1474 -313.0169)
		(width 0.174752)
		(layer "F.Cu")
		(net "PE_CLK_100M_DR11_1_R_P")
	)
	(segment
		(start 88.571324 -312.42)
		(end 87.376 -312.42)
		(width 0.174752)
		(layer "F.Cu")
		(net "PE_CLK_100M_DR11_1_R_P")
	)
	(segment
		(start 87.376 -312.42)
		(end 87.1474 -312.6486)
		(width 0.174752)
		(layer "F.Cu")
		(net "PE_CLK_100M_DR11_1_R_P")
	)
	(segment
		(start 90.73007 -309.60441)
		(end 90.73007 -310.258714)
		(width 0.174752)
		(layer "F.Cu")
		(net "PE_CLK_100M_DR11_1_R_P")
	)
	(segment
		(start 90.73007 -310.258714)
		(end 88.571324 -312.42)
		(width 0.174752)
		(layer "F.Cu")
		(net "PE_CLK_100M_DR11_1_R_P")
	)
	(segment
		(start 86.842346 -312.522108)
		(end 87.249508 -312.114946)
		(width 0.174752)
		(layer "F.Cu")
		(net "PE_CLK_100M_DR11_1_R_N")
	)
	(segment
		(start 88.444832 -312.114946)
		(end 89.282778 -311.275984)
		(width 0.174752)
		(layer "F.Cu")
		(net "PE_CLK_100M_DR11_1_R_N")
	)
	(segment
		(start 89.65311 -310.724296)
		(end 89.833704 -310.724042)
		(width 0.174752)
		(layer "F.Cu")
		(net "PE_CLK_100M_DR11_1_R_N")
	)
	(segment
		(start 86.487 -313.3725)
		(end 86.6521 -313.3725)
		(width 0.174752)
		(layer "F.Cu")
		(net "PE_CLK_100M_DR11_1_R_N")
	)
	(segment
		(start 86.842346 -313.182254)
		(end 86.842346 -312.522108)
		(width 0.174752)
		(layer "F.Cu")
		(net "PE_CLK_100M_DR11_1_R_N")
	)
	(segment
		(start 90.22969 -310.327802)
		(end 90.22969 -309.731918)
		(width 0.174752)
		(layer "F.Cu")
		(net "PE_CLK_100M_DR11_1_R_N")
	)
	(segment
		(start 89.282778 -311.095136)
		(end 89.65311 -310.724296)
		(width 0.174752)
		(layer "F.Cu")
		(net "PE_CLK_100M_DR11_1_R_N")
	)
	(segment
		(start 86.6521 -313.3725)
		(end 86.842346 -313.182254)
		(width 0.174752)
		(layer "F.Cu")
		(net "PE_CLK_100M_DR11_1_R_N")
	)
	(segment
		(start 89.282778 -311.275984)
		(end 89.282778 -311.095136)
		(width 0.174752)
		(layer "F.Cu")
		(net "PE_CLK_100M_DR11_1_R_N")
	)
	(segment
		(start 87.249508 -312.114946)
		(end 88.444832 -312.114946)
		(width 0.174752)
		(layer "F.Cu")
		(net "PE_CLK_100M_DR11_1_R_N")
	)
	(segment
		(start 89.833704 -310.724042)
		(end 90.22969 -310.327802)
		(width 0.174752)
		(layer "F.Cu")
		(net "PE_CLK_100M_DR11_1_R_N")
	)
	(segment
		(start 87.376508 -424.866054)
		(end 88.704674 -424.866054)
		(width 0.174752)
		(layer "F.Cu")
		(net "PE_CLK_100M_DR10_2_R_P")
	)
	(segment
		(start 90.22969 -426.39107)
		(end 90.22969 -427.249082)
		(width 0.174752)
		(layer "F.Cu")
		(net "PE_CLK_100M_DR10_2_R_P")
	)
	(segment
		(start 86.842346 -423.773346)
		(end 86.842346 -424.331892)
		(width 0.174752)
		(layer "F.Cu")
		(net "PE_CLK_100M_DR10_2_R_P")
	)
	(segment
		(start 89.626694 -425.788074)
		(end 90.22969 -426.39107)
		(width 0.174752)
		(layer "F.Cu")
		(net "PE_CLK_100M_DR10_2_R_P")
	)
	(segment
		(start 86.487 -423.6085)
		(end 86.6775 -423.6085)
		(width 0.174752)
		(layer "F.Cu")
		(net "PE_CLK_100M_DR10_2_R_P")
	)
	(segment
		(start 89.4461 -425.788074)
		(end 89.626694 -425.788074)
		(width 0.174752)
		(layer "F.Cu")
		(net "PE_CLK_100M_DR10_2_R_P")
	)
	(segment
		(start 88.704674 -424.866054)
		(end 89.07526 -425.23664)
		(width 0.174752)
		(layer "F.Cu")
		(net "PE_CLK_100M_DR10_2_R_P")
	)
	(segment
		(start 89.07526 -425.417488)
		(end 89.4461 -425.788074)
		(width 0.174752)
		(layer "F.Cu")
		(net "PE_CLK_100M_DR10_2_R_P")
	)
	(segment
		(start 86.842346 -424.331892)
		(end 87.376508 -424.866054)
		(width 0.174752)
		(layer "F.Cu")
		(net "PE_CLK_100M_DR10_2_R_P")
	)
	(segment
		(start 89.07526 -425.23664)
		(end 89.07526 -425.417488)
		(width 0.174752)
		(layer "F.Cu")
		(net "PE_CLK_100M_DR10_2_R_P")
	)
	(segment
		(start 86.6775 -423.6085)
		(end 86.842346 -423.773346)
		(width 0.174752)
		(layer "F.Cu")
		(net "PE_CLK_100M_DR10_2_R_P")
	)
	(segment
		(start 87.503 -424.561)
		(end 88.831166 -424.561)
		(width 0.174752)
		(layer "F.Cu")
		(net "PE_CLK_100M_DR10_2_R_N")
	)
	(segment
		(start 90.73007 -426.459904)
		(end 90.73007 -427.37659)
		(width 0.174752)
		(layer "F.Cu")
		(net "PE_CLK_100M_DR10_2_R_N")
	)
	(segment
		(start 87.1474 -423.9641)
		(end 87.1474 -424.2054)
		(width 0.174752)
		(layer "F.Cu")
		(net "PE_CLK_100M_DR10_2_R_N")
	)
	(segment
		(start 87.503 -423.6085)
		(end 87.1474 -423.9641)
		(width 0.174752)
		(layer "F.Cu")
		(net "PE_CLK_100M_DR10_2_R_N")
	)
	(segment
		(start 88.831166 -424.561)
		(end 90.73007 -426.459904)
		(width 0.174752)
		(layer "F.Cu")
		(net "PE_CLK_100M_DR10_2_R_N")
	)
	(segment
		(start 87.1474 -424.2054)
		(end 87.503 -424.561)
		(width 0.174752)
		(layer "F.Cu")
		(net "PE_CLK_100M_DR10_2_R_N")
	)
	(segment
		(start 90.652346 -424.331892)
		(end 90.652346 -423.963846)
		(width 0.174752)
		(layer "F.Cu")
		(net "PE_CLK_100M_DR10_1_R_P")
	)
	(segment
		(start 90.652346 -423.963846)
		(end 90.297 -423.6085)
		(width 0.174752)
		(layer "F.Cu")
		(net "PE_CLK_100M_DR10_1_R_P")
	)
	(segment
		(start 92.326968 -426.622972)
		(end 92.326968 -426.006514)
		(width 0.174752)
		(layer "F.Cu")
		(net "PE_CLK_100M_DR10_1_R_P")
	)
	(segment
		(start 92.326968 -426.006514)
		(end 90.652346 -424.331892)
		(width 0.174752)
		(layer "F.Cu")
		(net "PE_CLK_100M_DR10_1_R_P")
	)
	(segment
		(start 92.22994 -426.72)
		(end 92.326968 -426.622972)
		(width 0.174752)
		(layer "F.Cu")
		(net "PE_CLK_100M_DR10_1_R_P")
	)
	(segment
		(start 92.22994 -427.37659)
		(end 92.22994 -426.72)
		(width 0.174752)
		(layer "F.Cu")
		(net "PE_CLK_100M_DR10_1_R_P")
	)
	(segment
		(start 90.9574 -423.9641)
		(end 91.313 -423.6085)
		(width 0.174752)
		(layer "F.Cu")
		(net "PE_CLK_100M_DR10_1_R_N")
	)
	(segment
		(start 90.9574 -424.2054)
		(end 90.9574 -423.9641)
		(width 0.174752)
		(layer "F.Cu")
		(net "PE_CLK_100M_DR10_1_R_N")
	)
	(segment
		(start 92.73032 -427.37659)
		(end 92.73032 -426.72)
		(width 0.174752)
		(layer "F.Cu")
		(net "PE_CLK_100M_DR10_1_R_N")
	)
	(segment
		(start 92.632022 -425.880022)
		(end 90.9574 -424.2054)
		(width 0.174752)
		(layer "F.Cu")
		(net "PE_CLK_100M_DR10_1_R_N")
	)
	(segment
		(start 92.73032 -426.72)
		(end 92.632022 -426.621702)
		(width 0.174752)
		(layer "F.Cu")
		(net "PE_CLK_100M_DR10_1_R_N")
	)
	(segment
		(start 92.632022 -426.621702)
		(end 92.632022 -425.880022)
		(width 0.174752)
		(layer "F.Cu")
		(net "PE_CLK_100M_DR10_1_R_N")
	)
	(segment
		(start 99.228656 -305.93157)
		(end 99.325684 -306.028598)
		(width 0.174752)
		(layer "F.Cu")
		(net "PE_CLK_100M_DR1_2_R_P")
	)
	(segment
		(start 101.816154 -307.060346)
		(end 102.1715 -306.705)
		(width 0.174752)
		(layer "F.Cu")
		(net "PE_CLK_100M_DR1_2_R_P")
	)
	(segment
		(start 100.085144 -306.028598)
		(end 101.116892 -307.060346)
		(width 0.174752)
		(layer "F.Cu")
		(net "PE_CLK_100M_DR1_2_R_P")
	)
	(segment
		(start 99.704906 -306.027836)
		(end 99.957636 -306.027836)
		(width 0.174752)
		(layer "F.Cu")
		(net "PE_CLK_100M_DR1_2_R_P")
	)
	(segment
		(start 99.325684 -306.028598)
		(end 99.704144 -306.028598)
		(width 0.174752)
		(layer "F.Cu")
		(net "PE_CLK_100M_DR1_2_R_P")
	)
	(segment
		(start 101.116892 -307.060346)
		(end 101.816154 -307.060346)
		(width 0.174752)
		(layer "F.Cu")
		(net "PE_CLK_100M_DR1_2_R_P")
	)
	(segment
		(start 99.704144 -306.028598)
		(end 99.704906 -306.027836)
		(width 0.174752)
		(layer "F.Cu")
		(net "PE_CLK_100M_DR1_2_R_P")
	)
	(segment
		(start 98.40341 -305.93157)
		(end 99.228656 -305.93157)
		(width 0.174752)
		(layer "F.Cu")
		(net "PE_CLK_100M_DR1_2_R_P")
	)
	(segment
		(start 99.958398 -306.028598)
		(end 100.085144 -306.028598)
		(width 0.174752)
		(layer "F.Cu")
		(net "PE_CLK_100M_DR1_2_R_P")
	)
	(segment
		(start 99.957636 -306.027836)
		(end 99.958398 -306.028598)
		(width 0.174752)
		(layer "F.Cu")
		(net "PE_CLK_100M_DR1_2_R_P")
	)
	(segment
		(start 99.228656 -306.43068)
		(end 99.325684 -306.333652)
		(width 0.174752)
		(layer "F.Cu")
		(net "PE_CLK_100M_DR1_2_R_N")
	)
	(segment
		(start 101.8159 -307.3654)
		(end 102.1715 -307.721)
		(width 0.174752)
		(layer "F.Cu")
		(net "PE_CLK_100M_DR1_2_R_N")
	)
	(segment
		(start 98.40341 -306.43068)
		(end 99.228656 -306.43068)
		(width 0.174752)
		(layer "F.Cu")
		(net "PE_CLK_100M_DR1_2_R_N")
	)
	(segment
		(start 99.325684 -306.333652)
		(end 99.958652 -306.333652)
		(width 0.174752)
		(layer "F.Cu")
		(net "PE_CLK_100M_DR1_2_R_N")
	)
	(segment
		(start 100.9904 -307.3654)
		(end 101.8159 -307.3654)
		(width 0.174752)
		(layer "F.Cu")
		(net "PE_CLK_100M_DR1_2_R_N")
	)
	(segment
		(start 99.958652 -306.333652)
		(end 100.9904 -307.3654)
		(width 0.174752)
		(layer "F.Cu")
		(net "PE_CLK_100M_DR1_2_R_N")
	)
	(segment
		(start 99.227894 -307.93055)
		(end 98.40341 -307.93055)
		(width 0.174752)
		(layer "F.Cu")
		(net "PE_CLK_100M_DR1_1_R_P")
	)
	(segment
		(start 99.570032 -308.02834)
		(end 99.325684 -308.02834)
		(width 0.174752)
		(layer "F.Cu")
		(net "PE_CLK_100M_DR1_1_R_P")
	)
	(segment
		(start 100.889054 -310.548274)
		(end 100.889054 -309.347362)
		(width 0.174752)
		(layer "F.Cu")
		(net "PE_CLK_100M_DR1_1_R_P")
	)
	(segment
		(start 100.889054 -309.347362)
		(end 99.570032 -308.02834)
		(width 0.174752)
		(layer "F.Cu")
		(net "PE_CLK_100M_DR1_1_R_P")
	)
	(segment
		(start 99.325684 -308.02834)
		(end 99.227894 -307.93055)
		(width 0.174752)
		(layer "F.Cu")
		(net "PE_CLK_100M_DR1_1_R_P")
	)
	(segment
		(start 102.1715 -310.515)
		(end 101.816154 -310.870346)
		(width 0.174752)
		(layer "F.Cu")
		(net "PE_CLK_100M_DR1_1_R_P")
	)
	(segment
		(start 101.816154 -310.870346)
		(end 101.211126 -310.870346)
		(width 0.174752)
		(layer "F.Cu")
		(net "PE_CLK_100M_DR1_1_R_P")
	)
	(segment
		(start 101.211126 -310.870346)
		(end 100.889054 -310.548274)
		(width 0.174752)
		(layer "F.Cu")
		(net "PE_CLK_100M_DR1_1_R_P")
	)
	(segment
		(start 100.584 -309.473854)
		(end 99.44354 -308.333394)
		(width 0.174752)
		(layer "F.Cu")
		(net "PE_CLK_100M_DR1_1_R_N")
	)
	(segment
		(start 101.084634 -311.1754)
		(end 100.584 -310.674766)
		(width 0.174752)
		(layer "F.Cu")
		(net "PE_CLK_100M_DR1_1_R_N")
	)
	(segment
		(start 99.44354 -308.333394)
		(end 99.325684 -308.333394)
		(width 0.174752)
		(layer "F.Cu")
		(net "PE_CLK_100M_DR1_1_R_N")
	)
	(segment
		(start 102.1715 -311.531)
		(end 101.8159 -311.1754)
		(width 0.174752)
		(layer "F.Cu")
		(net "PE_CLK_100M_DR1_1_R_N")
	)
	(segment
		(start 100.584 -310.674766)
		(end 100.584 -309.473854)
		(width 0.174752)
		(layer "F.Cu")
		(net "PE_CLK_100M_DR1_1_R_N")
	)
	(segment
		(start 99.325684 -308.333394)
		(end 99.228148 -308.43093)
		(width 0.174752)
		(layer "F.Cu")
		(net "PE_CLK_100M_DR1_1_R_N")
	)
	(segment
		(start 99.228148 -308.43093)
		(end 98.40341 -308.43093)
		(width 0.174752)
		(layer "F.Cu")
		(net "PE_CLK_100M_DR1_1_R_N")
	)
	(segment
		(start 101.8159 -311.1754)
		(end 101.084634 -311.1754)
		(width 0.174752)
		(layer "F.Cu")
		(net "PE_CLK_100M_DR1_1_R_N")
	)
	(segment
		(start 101.816154 -433.679346)
		(end 102.1715 -433.324)
		(width 0.174752)
		(layer "F.Cu")
		(net "PE_CLK_100M_DR0_2_R_P")
	)
	(segment
		(start 99.187 -432.55057)
		(end 99.28352 -432.64709)
		(width 0.174752)
		(layer "F.Cu")
		(net "PE_CLK_100M_DR0_2_R_P")
	)
	(segment
		(start 98.40341 -432.55057)
		(end 99.187 -432.55057)
		(width 0.174752)
		(layer "F.Cu")
		(net "PE_CLK_100M_DR0_2_R_P")
	)
	(segment
		(start 100.989892 -433.679346)
		(end 101.816154 -433.679346)
		(width 0.174752)
		(layer "F.Cu")
		(net "PE_CLK_100M_DR0_2_R_P")
	)
	(segment
		(start 99.28352 -432.64709)
		(end 99.957636 -432.64709)
		(width 0.174752)
		(layer "F.Cu")
		(net "PE_CLK_100M_DR0_2_R_P")
	)
	(segment
		(start 99.957636 -432.64709)
		(end 100.989892 -433.679346)
		(width 0.174752)
		(layer "F.Cu")
		(net "PE_CLK_100M_DR0_2_R_P")
	)
	(segment
		(start 101.8159 -433.9844)
		(end 102.1715 -434.34)
		(width 0.174752)
		(layer "F.Cu")
		(net "PE_CLK_100M_DR0_2_R_N")
	)
	(segment
		(start 98.40341 -433.04968)
		(end 99.187 -433.04968)
		(width 0.174752)
		(layer "F.Cu")
		(net "PE_CLK_100M_DR0_2_R_N")
	)
	(segment
		(start 100.8634 -433.9844)
		(end 101.8159 -433.9844)
		(width 0.174752)
		(layer "F.Cu")
		(net "PE_CLK_100M_DR0_2_R_N")
	)
	(segment
		(start 99.187 -433.04968)
		(end 99.284536 -432.952144)
		(width 0.174752)
		(layer "F.Cu")
		(net "PE_CLK_100M_DR0_2_R_N")
	)
	(segment
		(start 99.831144 -432.952144)
		(end 100.8634 -433.9844)
		(width 0.174752)
		(layer "F.Cu")
		(net "PE_CLK_100M_DR0_2_R_N")
	)
	(segment
		(start 99.284536 -432.952144)
		(end 99.831144 -432.952144)
		(width 0.174752)
		(layer "F.Cu")
		(net "PE_CLK_100M_DR0_2_R_N")
	)
	(segment
		(start 101.816154 -437.489346)
		(end 102.1715 -437.134)
		(width 0.174752)
		(layer "F.Cu")
		(net "PE_CLK_100M_DR0_1_R_P")
	)
	(segment
		(start 99.227894 -434.54955)
		(end 99.325684 -434.64734)
		(width 0.174752)
		(layer "F.Cu")
		(net "PE_CLK_100M_DR0_1_R_P")
	)
	(segment
		(start 100.889054 -435.909466)
		(end 100.889054 -437.167274)
		(width 0.174752)
		(layer "F.Cu")
		(net "PE_CLK_100M_DR0_1_R_P")
	)
	(segment
		(start 100.889054 -437.167274)
		(end 101.211126 -437.489346)
		(width 0.174752)
		(layer "F.Cu")
		(net "PE_CLK_100M_DR0_1_R_P")
	)
	(segment
		(start 99.325684 -434.64734)
		(end 99.626928 -434.64734)
		(width 0.174752)
		(layer "F.Cu")
		(net "PE_CLK_100M_DR0_1_R_P")
	)
	(segment
		(start 99.626928 -434.64734)
		(end 100.889054 -435.909466)
		(width 0.174752)
		(layer "F.Cu")
		(net "PE_CLK_100M_DR0_1_R_P")
	)
	(segment
		(start 101.211126 -437.489346)
		(end 101.816154 -437.489346)
		(width 0.174752)
		(layer "F.Cu")
		(net "PE_CLK_100M_DR0_1_R_P")
	)
	(segment
		(start 98.40341 -434.54955)
		(end 99.227894 -434.54955)
		(width 0.174752)
		(layer "F.Cu")
		(net "PE_CLK_100M_DR0_1_R_P")
	)
	(segment
		(start 99.228148 -435.04993)
		(end 99.325684 -434.952394)
		(width 0.174752)
		(layer "F.Cu")
		(net "PE_CLK_100M_DR0_1_R_N")
	)
	(segment
		(start 101.084634 -437.7944)
		(end 101.8159 -437.7944)
		(width 0.174752)
		(layer "F.Cu")
		(net "PE_CLK_100M_DR0_1_R_N")
	)
	(segment
		(start 98.40341 -435.04993)
		(end 99.228148 -435.04993)
		(width 0.174752)
		(layer "F.Cu")
		(net "PE_CLK_100M_DR0_1_R_N")
	)
	(segment
		(start 99.325684 -434.952394)
		(end 99.500436 -434.952394)
		(width 0.174752)
		(layer "F.Cu")
		(net "PE_CLK_100M_DR0_1_R_N")
	)
	(segment
		(start 101.8159 -437.7944)
		(end 102.1715 -438.15)
		(width 0.174752)
		(layer "F.Cu")
		(net "PE_CLK_100M_DR0_1_R_N")
	)
	(segment
		(start 99.500436 -434.952394)
		(end 100.584 -436.035958)
		(width 0.174752)
		(layer "F.Cu")
		(net "PE_CLK_100M_DR0_1_R_N")
	)
	(segment
		(start 100.584 -437.293766)
		(end 101.084634 -437.7944)
		(width 0.174752)
		(layer "F.Cu")
		(net "PE_CLK_100M_DR0_1_R_N")
	)
	(segment
		(start 100.584 -436.035958)
		(end 100.584 -437.293766)
		(width 0.174752)
		(layer "F.Cu")
		(net "PE_CLK_100M_DR0_1_R_N")
	)
	(segment
		(start 8.3693 -450.9389)
		(end 8.661146 -451.230746)
		(width 0.174752)
		(layer "F.Cu")
		(net "PE_100M_CLK4_P")
	)
	(segment
		(start 78.8162 -431.8)
		(end 78.460854 -431.444654)
		(width 0.174752)
		(layer "F.Cu")
		(net "PE_100M_CLK4_P")
	)
	(segment
		(start 26.606754 -459.561946)
		(end 32.166052 -454.002648)
		(width 0.174752)
		(layer "F.Cu")
		(net "PE_100M_CLK4_P")
	)
	(segment
		(start 20.735036 -459.561946)
		(end 26.606754 -459.561946)
		(width 0.174752)
		(layer "F.Cu")
		(net "PE_100M_CLK4_P")
	)
	(segment
		(start 74.536046 -431.050192)
		(end 74.937874 -431.45202)
		(width 0.174752)
		(layer "F.Cu")
		(net "PE_100M_CLK4_P")
	)
	(segment
		(start 83.59648 -431.45202)
		(end 88.634316 -431.45202)
		(width 0.174752)
		(layer "F.Cu")
		(net "PE_100M_CLK4_P")
	)
	(segment
		(start 19.62023 -458.44714)
		(end 20.735036 -459.561946)
		(width 0.174752)
		(layer "F.Cu")
		(net "PE_100M_CLK4_P")
	)
	(segment
		(start 8.661146 -451.230746)
		(end 11.277092 -451.230746)
		(width 0.174752)
		(layer "F.Cu")
		(net "PE_100M_CLK4_P")
	)
	(segment
		(start 83.4644 -431.5841)
		(end 83.59648 -431.45202)
		(width 0.174752)
		(layer "F.Cu")
		(net "PE_100M_CLK4_P")
	)
	(segment
		(start 78.130146 -431.444654)
		(end 77.7748 -431.8)
		(width 0.174752)
		(layer "F.Cu")
		(net "PE_100M_CLK4_P")
	)
	(segment
		(start 78.8162 -431.8)
		(end 79.16418 -431.45202)
		(width 0.174752)
		(layer "F.Cu")
		(net "PE_100M_CLK4_P")
	)
	(segment
		(start 74.2696 -430.1236)
		(end 74.536046 -430.390046)
		(width 0.174752)
		(layer "F.Cu")
		(net "PE_100M_CLK4_P")
	)
	(segment
		(start 11.277092 -451.230746)
		(end 18.493486 -458.44714)
		(width 0.174752)
		(layer "F.Cu")
		(net "PE_100M_CLK4_P")
	)
	(segment
		(start 88.634316 -431.45202)
		(end 88.732106 -431.54981)
		(width 0.174752)
		(layer "F.Cu")
		(net "PE_100M_CLK4_P")
	)
	(segment
		(start 32.166052 -454.002648)
		(end 32.166052 -450.377052)
		(width 0.174752)
		(layer "F.Cu")
		(net "PE_100M_CLK4_P")
	)
	(segment
		(start 79.16418 -431.45202)
		(end 83.33232 -431.45202)
		(width 0.174752)
		(layer "F.Cu")
		(net "PE_100M_CLK4_P")
	)
	(segment
		(start 74.937874 -431.45202)
		(end 77.42682 -431.45202)
		(width 0.174752)
		(layer "F.Cu")
		(net "PE_100M_CLK4_P")
	)
	(segment
		(start 74.536046 -430.390046)
		(end 74.536046 -431.050192)
		(width 0.174752)
		(layer "F.Cu")
		(net "PE_100M_CLK4_P")
	)
	(segment
		(start 72.128634 -431.400966)
		(end 72.39 -431.1396)
		(width 0.174752)
		(layer "F.Cu")
		(net "PE_100M_CLK4_P")
	)
	(segment
		(start 77.42682 -431.45202)
		(end 77.7748 -431.8)
		(width 0.174752)
		(layer "F.Cu")
		(net "PE_100M_CLK4_P")
	)
	(segment
		(start 18.493486 -458.44714)
		(end 19.62023 -458.44714)
		(width 0.174752)
		(layer "F.Cu")
		(net "PE_100M_CLK4_P")
	)
	(segment
		(start 78.460854 -431.444654)
		(end 78.130146 -431.444654)
		(width 0.174752)
		(layer "F.Cu")
		(net "PE_100M_CLK4_P")
	)
	(segment
		(start 32.166052 -450.377052)
		(end 51.142138 -431.400966)
		(width 0.174752)
		(layer "F.Cu")
		(net "PE_100M_CLK4_P")
	)
	(segment
		(start 88.732106 -431.54981)
		(end 89.55659 -431.54981)
		(width 0.174752)
		(layer "F.Cu")
		(net "PE_100M_CLK4_P")
	)
	(segment
		(start 51.142138 -431.400966)
		(end 72.128634 -431.400966)
		(width 0.174752)
		(layer "F.Cu")
		(net "PE_100M_CLK4_P")
	)
	(segment
		(start 83.33232 -431.45202)
		(end 83.4644 -431.5841)
		(width 0.174752)
		(layer "F.Cu")
		(net "PE_100M_CLK4_P")
	)
	(via
		(at 74.2696 -430.1236)
		(size 0.508)
		(drill 0.254)
		(layers "F.Cu" "B.Cu")
		(net "PE_100M_CLK4_P")
	)
	(via
		(at 72.39 -431.1396)
		(size 0.508)
		(drill 0.254)
		(layers "F.Cu" "B.Cu")
		(net "PE_100M_CLK4_P")
	)
	(segment
		(start 74.168508 -431.393346)
		(end 72.643746 -431.393346)
		(width 0.174752)
		(layer "B.Cu")
		(net "PE_100M_CLK4_P")
	)
	(segment
		(start 74.2696 -430.1236)
		(end 74.523346 -430.377346)
		(width 0.174752)
		(layer "B.Cu")
		(net "PE_100M_CLK4_P")
	)
	(segment
		(start 74.523346 -431.038508)
		(end 74.168508 -431.393346)
		(width 0.174752)
		(layer "B.Cu")
		(net "PE_100M_CLK4_P")
	)
	(segment
		(start 72.643746 -431.393346)
		(end 72.39 -431.1396)
		(width 0.174752)
		(layer "B.Cu")
		(net "PE_100M_CLK4_P")
	)
	(segment
		(start 74.523346 -430.377346)
		(end 74.523346 -431.038508)
		(width 0.174752)
		(layer "B.Cu")
		(net "PE_100M_CLK4_P")
	)
	(segment
		(start 88.731852 -431.04943)
		(end 89.55659 -431.04943)
		(width 0.174752)
		(layer "F.Cu")
		(net "PE_100M_CLK4_N")
	)
	(segment
		(start 75.0824 -430.1236)
		(end 74.8411 -430.3649)
		(width 0.174752)
		(layer "F.Cu")
		(net "PE_100M_CLK4_N")
	)
	(segment
		(start 72.14362 -431.70602)
		(end 72.39 -431.9524)
		(width 0.174752)
		(layer "F.Cu")
		(net "PE_100M_CLK4_N")
	)
	(segment
		(start 83.586066 -431.146966)
		(end 88.634316 -431.146966)
		(width 0.174752)
		(layer "F.Cu")
		(net "PE_100M_CLK4_N")
	)
	(segment
		(start 74.8411 -430.9237)
		(end 75.064366 -431.146966)
		(width 0.174752)
		(layer "F.Cu")
		(net "PE_100M_CLK4_N")
	)
	(segment
		(start 75.064366 -431.146966)
		(end 77.411834 -431.146966)
		(width 0.174752)
		(layer "F.Cu")
		(net "PE_100M_CLK4_N")
	)
	(segment
		(start 78.1304 -431.1396)
		(end 77.7748 -430.784)
		(width 0.174752)
		(layer "F.Cu")
		(net "PE_100M_CLK4_N")
	)
	(segment
		(start 74.8411 -430.3649)
		(end 74.8411 -430.9237)
		(width 0.174752)
		(layer "F.Cu")
		(net "PE_100M_CLK4_N")
	)
	(segment
		(start 20.608544 -459.867)
		(end 26.733246 -459.867)
		(width 0.174752)
		(layer "F.Cu")
		(net "PE_100M_CLK4_N")
	)
	(segment
		(start 19.493738 -458.752194)
		(end 20.608544 -459.867)
		(width 0.174752)
		(layer "F.Cu")
		(net "PE_100M_CLK4_N")
	)
	(segment
		(start 79.179166 -431.146966)
		(end 83.342734 -431.146966)
		(width 0.174752)
		(layer "F.Cu")
		(net "PE_100M_CLK4_N")
	)
	(segment
		(start 26.733246 -459.867)
		(end 32.471106 -454.12914)
		(width 0.174752)
		(layer "F.Cu")
		(net "PE_100M_CLK4_N")
	)
	(segment
		(start 83.342734 -431.146966)
		(end 83.4644 -431.0253)
		(width 0.174752)
		(layer "F.Cu")
		(net "PE_100M_CLK4_N")
	)
	(segment
		(start 51.26863 -431.70602)
		(end 72.14362 -431.70602)
		(width 0.174752)
		(layer "F.Cu")
		(net "PE_100M_CLK4_N")
	)
	(segment
		(start 32.471106 -450.503544)
		(end 51.26863 -431.70602)
		(width 0.174752)
		(layer "F.Cu")
		(net "PE_100M_CLK4_N")
	)
	(segment
		(start 83.4644 -431.0253)
		(end 83.586066 -431.146966)
		(width 0.174752)
		(layer "F.Cu")
		(net "PE_100M_CLK4_N")
	)
	(segment
		(start 8.6614 -451.5358)
		(end 11.1506 -451.5358)
		(width 0.174752)
		(layer "F.Cu")
		(net "PE_100M_CLK4_N")
	)
	(segment
		(start 88.634316 -431.146966)
		(end 88.731852 -431.04943)
		(width 0.174752)
		(layer "F.Cu")
		(net "PE_100M_CLK4_N")
	)
	(segment
		(start 77.411834 -431.146966)
		(end 77.7748 -430.784)
		(width 0.174752)
		(layer "F.Cu")
		(net "PE_100M_CLK4_N")
	)
	(segment
		(start 8.3693 -451.8279)
		(end 8.6614 -451.5358)
		(width 0.174752)
		(layer "F.Cu")
		(net "PE_100M_CLK4_N")
	)
	(segment
		(start 18.366994 -458.752194)
		(end 19.493738 -458.752194)
		(width 0.174752)
		(layer "F.Cu")
		(net "PE_100M_CLK4_N")
	)
	(segment
		(start 78.4606 -431.1396)
		(end 78.1304 -431.1396)
		(width 0.174752)
		(layer "F.Cu")
		(net "PE_100M_CLK4_N")
	)
	(segment
		(start 78.8162 -430.784)
		(end 78.4606 -431.1396)
		(width 0.174752)
		(layer "F.Cu")
		(net "PE_100M_CLK4_N")
	)
	(segment
		(start 78.8162 -430.784)
		(end 79.179166 -431.146966)
		(width 0.174752)
		(layer "F.Cu")
		(net "PE_100M_CLK4_N")
	)
	(segment
		(start 32.471106 -454.12914)
		(end 32.471106 -450.503544)
		(width 0.174752)
		(layer "F.Cu")
		(net "PE_100M_CLK4_N")
	)
	(segment
		(start 11.1506 -451.5358)
		(end 18.366994 -458.752194)
		(width 0.174752)
		(layer "F.Cu")
		(net "PE_100M_CLK4_N")
	)
	(via
		(at 72.39 -431.9524)
		(size 0.508)
		(drill 0.254)
		(layers "F.Cu" "B.Cu")
		(net "PE_100M_CLK4_N")
	)
	(via
		(at 75.0824 -430.1236)
		(size 0.508)
		(drill 0.254)
		(layers "F.Cu" "B.Cu")
		(net "PE_100M_CLK4_N")
	)
	(segment
		(start 72.644 -431.6984)
		(end 72.39 -431.9524)
		(width 0.174752)
		(layer "B.Cu")
		(net "PE_100M_CLK4_N")
	)
	(segment
		(start 74.8284 -431.165)
		(end 74.295 -431.6984)
		(width 0.174752)
		(layer "B.Cu")
		(net "PE_100M_CLK4_N")
	)
	(segment
		(start 74.295 -431.6984)
		(end 72.644 -431.6984)
		(width 0.174752)
		(layer "B.Cu")
		(net "PE_100M_CLK4_N")
	)
	(segment
		(start 75.0824 -430.1236)
		(end 74.8284 -430.3776)
		(width 0.174752)
		(layer "B.Cu")
		(net "PE_100M_CLK4_N")
	)
	(segment
		(start 74.8284 -430.3776)
		(end 74.8284 -431.165)
		(width 0.174752)
		(layer "B.Cu")
		(net "PE_100M_CLK4_N")
	)
	(segment
		(start 76.31938 -304.83302)
		(end 77.17282 -304.83302)
		(width 0.174752)
		(layer "F.Cu")
		(net "PE_100M_CLK3_P")
	)
	(segment
		(start 14.656816 -405.085042)
		(end 14.529054 -404.95728)
		(width 0.174752)
		(layer "F.Cu")
		(net "PE_100M_CLK3_P")
	)
	(segment
		(start 15.254224 -306.716176)
		(end 16.306546 -305.663854)
		(width 0.174752)
		(layer "F.Cu")
		(net "PE_100M_CLK3_P")
	)
	(segment
		(start 14.644878 -407.681176)
		(end 14.529054 -407.565352)
		(width 0.174752)
		(layer "F.Cu")
		(net "PE_100M_CLK3_P")
	)
	(segment
		(start 14.529054 -382.161796)
		(end 14.529054 -381.63754)
		(width 0.174752)
		(layer "F.Cu")
		(net "PE_100M_CLK3_P")
	)
	(segment
		(start 14.656816 -382.813814)
		(end 14.656816 -382.289558)
		(width 0.174752)
		(layer "F.Cu")
		(net "PE_100M_CLK3_P")
	)
	(segment
		(start 14.529054 -382.941576)
		(end 14.656816 -382.813814)
		(width 0.174752)
		(layer "F.Cu")
		(net "PE_100M_CLK3_P")
	)
	(segment
		(start 78.5622 -305.181)
		(end 78.206854 -304.825654)
		(width 0.174752)
		(layer "F.Cu")
		(net "PE_100M_CLK3_P")
	)
	(segment
		(start 77.17282 -304.83302)
		(end 77.5208 -305.181)
		(width 0.174752)
		(layer "F.Cu")
		(net "PE_100M_CLK3_P")
	)
	(segment
		(start 88.732106 -304.93081)
		(end 89.55659 -304.93081)
		(width 0.174752)
		(layer "F.Cu")
		(net "PE_100M_CLK3_P")
	)
	(segment
		(start 77.876146 -304.825654)
		(end 77.5208 -305.181)
		(width 0.174752)
		(layer "F.Cu")
		(net "PE_100M_CLK3_P")
	)
	(segment
		(start 14.640306 -406.929844)
		(end 14.640306 -406.372568)
		(width 0.174752)
		(layer "F.Cu")
		(net "PE_100M_CLK3_P")
	)
	(segment
		(start 15.254224 -327.42759)
		(end 15.254224 -306.716176)
		(width 0.174752)
		(layer "F.Cu")
		(net "PE_100M_CLK3_P")
	)
	(segment
		(start 14.529054 -404.95728)
		(end 14.529054 -382.941576)
		(width 0.174752)
		(layer "F.Cu")
		(net "PE_100M_CLK3_P")
	)
	(segment
		(start 14.529054 -380.85776)
		(end 14.529054 -374.574308)
		(width 0.174752)
		(layer "F.Cu")
		(net "PE_100M_CLK3_P")
	)
	(segment
		(start 14.656816 -381.509778)
		(end 14.656816 -380.985522)
		(width 0.174752)
		(layer "F.Cu")
		(net "PE_100M_CLK3_P")
	)
	(segment
		(start 14.529054 -406.261316)
		(end 14.529054 -405.73706)
		(width 0.174752)
		(layer "F.Cu")
		(net "PE_100M_CLK3_P")
	)
	(segment
		(start 78.91018 -304.83302)
		(end 85.59292 -304.83302)
		(width 0.174752)
		(layer "F.Cu")
		(net "PE_100M_CLK3_P")
	)
	(segment
		(start 14.656816 -380.985522)
		(end 14.529054 -380.85776)
		(width 0.174752)
		(layer "F.Cu")
		(net "PE_100M_CLK3_P")
	)
	(segment
		(start 85.59292 -304.83302)
		(end 85.725 -304.9651)
		(width 0.174752)
		(layer "F.Cu")
		(net "PE_100M_CLK3_P")
	)
	(segment
		(start 85.85708 -304.83302)
		(end 88.634316 -304.83302)
		(width 0.174752)
		(layer "F.Cu")
		(net "PE_100M_CLK3_P")
	)
	(segment
		(start 14.529054 -405.73706)
		(end 14.656816 -405.609298)
		(width 0.174752)
		(layer "F.Cu")
		(net "PE_100M_CLK3_P")
	)
	(segment
		(start 14.656816 -405.609298)
		(end 14.656816 -405.085042)
		(width 0.174752)
		(layer "F.Cu")
		(net "PE_100M_CLK3_P")
	)
	(segment
		(start 14.826488 -425.398692)
		(end 14.529054 -425.101258)
		(width 0.174752)
		(layer "F.Cu")
		(net "PE_100M_CLK3_P")
	)
	(segment
		(start 14.107922 -374.153176)
		(end 14.107922 -328.573892)
		(width 0.174752)
		(layer "F.Cu")
		(net "PE_100M_CLK3_P")
	)
	(segment
		(start 78.206854 -304.825654)
		(end 77.876146 -304.825654)
		(width 0.174752)
		(layer "F.Cu")
		(net "PE_100M_CLK3_P")
	)
	(segment
		(start 14.529054 -381.63754)
		(end 14.656816 -381.509778)
		(width 0.174752)
		(layer "F.Cu")
		(net "PE_100M_CLK3_P")
	)
	(segment
		(start 14.644878 -408.229308)
		(end 14.644878 -407.681176)
		(width 0.174752)
		(layer "F.Cu")
		(net "PE_100M_CLK3_P")
	)
	(segment
		(start 85.725 -304.9651)
		(end 85.85708 -304.83302)
		(width 0.174752)
		(layer "F.Cu")
		(net "PE_100M_CLK3_P")
	)
	(segment
		(start 14.529054 -374.574308)
		(end 14.107922 -374.153176)
		(width 0.174752)
		(layer "F.Cu")
		(net "PE_100M_CLK3_P")
	)
	(segment
		(start 88.634316 -304.83302)
		(end 88.732106 -304.93081)
		(width 0.174752)
		(layer "F.Cu")
		(net "PE_100M_CLK3_P")
	)
	(segment
		(start 14.656816 -382.289558)
		(end 14.529054 -382.161796)
		(width 0.174752)
		(layer "F.Cu")
		(net "PE_100M_CLK3_P")
	)
	(segment
		(start 14.107922 -328.573892)
		(end 15.254224 -327.42759)
		(width 0.174752)
		(layer "F.Cu")
		(net "PE_100M_CLK3_P")
	)
	(segment
		(start 14.529054 -425.101258)
		(end 14.529054 -408.345132)
		(width 0.174752)
		(layer "F.Cu")
		(net "PE_100M_CLK3_P")
	)
	(segment
		(start 14.529054 -408.345132)
		(end 14.644878 -408.229308)
		(width 0.174752)
		(layer "F.Cu")
		(net "PE_100M_CLK3_P")
	)
	(segment
		(start 14.640306 -406.372568)
		(end 14.529054 -406.261316)
		(width 0.174752)
		(layer "F.Cu")
		(net "PE_100M_CLK3_P")
	)
	(segment
		(start 75.488546 -305.663854)
		(end 76.31938 -304.83302)
		(width 0.174752)
		(layer "F.Cu")
		(net "PE_100M_CLK3_P")
	)
	(segment
		(start 78.5622 -305.181)
		(end 78.91018 -304.83302)
		(width 0.174752)
		(layer "F.Cu")
		(net "PE_100M_CLK3_P")
	)
	(segment
		(start 16.306546 -305.663854)
		(end 75.488546 -305.663854)
		(width 0.174752)
		(layer "F.Cu")
		(net "PE_100M_CLK3_P")
	)
	(segment
		(start 14.529054 -407.041096)
		(end 14.640306 -406.929844)
		(width 0.174752)
		(layer "F.Cu")
		(net "PE_100M_CLK3_P")
	)
	(segment
		(start 14.529054 -407.565352)
		(end 14.529054 -407.041096)
		(width 0.174752)
		(layer "F.Cu")
		(net "PE_100M_CLK3_P")
	)
	(segment
		(start 16.180054 -305.3588)
		(end 75.362054 -305.3588)
		(width 0.174752)
		(layer "F.Cu")
		(net "PE_100M_CLK3_N")
	)
	(segment
		(start 85.846666 -304.527966)
		(end 88.634316 -304.527966)
		(width 0.174752)
		(layer "F.Cu")
		(net "PE_100M_CLK3_N")
	)
	(segment
		(start 13.802868 -328.4474)
		(end 14.94917 -327.301098)
		(width 0.174752)
		(layer "F.Cu")
		(net "PE_100M_CLK3_N")
	)
	(segment
		(start 78.5622 -304.165)
		(end 78.2066 -304.5206)
		(width 0.174752)
		(layer "F.Cu")
		(net "PE_100M_CLK3_N")
	)
	(segment
		(start 77.157834 -304.527966)
		(end 77.5208 -304.165)
		(width 0.174752)
		(layer "F.Cu")
		(net "PE_100M_CLK3_N")
	)
	(segment
		(start 85.603334 -304.527966)
		(end 85.725 -304.4063)
		(width 0.174752)
		(layer "F.Cu")
		(net "PE_100M_CLK3_N")
	)
	(segment
		(start 75.362054 -305.3588)
		(end 76.192888 -304.527966)
		(width 0.174752)
		(layer "F.Cu")
		(net "PE_100M_CLK3_N")
	)
	(segment
		(start 88.731852 -304.43043)
		(end 89.55659 -304.43043)
		(width 0.174752)
		(layer "F.Cu")
		(net "PE_100M_CLK3_N")
	)
	(segment
		(start 14.224 -374.7008)
		(end 13.802868 -374.279668)
		(width 0.174752)
		(layer "F.Cu")
		(net "PE_100M_CLK3_N")
	)
	(segment
		(start 14.94917 -306.589684)
		(end 16.180054 -305.3588)
		(width 0.174752)
		(layer "F.Cu")
		(net "PE_100M_CLK3_N")
	)
	(segment
		(start 13.937488 -425.398692)
		(end 14.224 -425.11218)
		(width 0.174752)
		(layer "F.Cu")
		(net "PE_100M_CLK3_N")
	)
	(segment
		(start 13.802868 -374.279668)
		(end 13.802868 -328.4474)
		(width 0.174752)
		(layer "F.Cu")
		(net "PE_100M_CLK3_N")
	)
	(segment
		(start 88.634316 -304.527966)
		(end 88.731852 -304.43043)
		(width 0.174752)
		(layer "F.Cu")
		(net "PE_100M_CLK3_N")
	)
	(segment
		(start 85.725 -304.4063)
		(end 85.846666 -304.527966)
		(width 0.174752)
		(layer "F.Cu")
		(net "PE_100M_CLK3_N")
	)
	(segment
		(start 77.8764 -304.5206)
		(end 77.5208 -304.165)
		(width 0.174752)
		(layer "F.Cu")
		(net "PE_100M_CLK3_N")
	)
	(segment
		(start 14.224 -425.11218)
		(end 14.224 -374.7008)
		(width 0.174752)
		(layer "F.Cu")
		(net "PE_100M_CLK3_N")
	)
	(segment
		(start 78.925166 -304.527966)
		(end 85.603334 -304.527966)
		(width 0.174752)
		(layer "F.Cu")
		(net "PE_100M_CLK3_N")
	)
	(segment
		(start 78.5622 -304.165)
		(end 78.925166 -304.527966)
		(width 0.174752)
		(layer "F.Cu")
		(net "PE_100M_CLK3_N")
	)
	(segment
		(start 14.94917 -327.301098)
		(end 14.94917 -306.589684)
		(width 0.174752)
		(layer "F.Cu")
		(net "PE_100M_CLK3_N")
	)
	(segment
		(start 76.192888 -304.527966)
		(end 77.157834 -304.527966)
		(width 0.174752)
		(layer "F.Cu")
		(net "PE_100M_CLK3_N")
	)
	(segment
		(start 78.2066 -304.5206)
		(end 77.8764 -304.5206)
		(width 0.174752)
		(layer "F.Cu")
		(net "PE_100M_CLK3_N")
	)
	(segment
		(start 78.029054 -210.477354)
		(end 77.698346 -210.477354)
		(width 0.174752)
		(layer "F.Cu")
		(net "PE_100M_CLK2_P")
	)
	(segment
		(start 85.41512 -210.47202)
		(end 85.5472 -210.6041)
		(width 0.174752)
		(layer "F.Cu")
		(net "PE_100M_CLK2_P")
	)
	(segment
		(start 8.9408 -382.1938)
		(end 8.9408 -383.3622)
		(width 0.174752)
		(layer "F.Cu")
		(net "PE_100M_CLK2_P")
	)
	(segment
		(start 9.2456 -377.011946)
		(end 9.2456 -378.78893)
		(width 0.174752)
		(layer "F.Cu")
		(net "PE_100M_CLK2_P")
	)
	(segment
		(start 69.245226 -210.47202)
		(end 48.29302 -210.47202)
		(width 0.174752)
		(layer "F.Cu")
		(net "PE_100M_CLK2_P")
	)
	(segment
		(start 88.732106 -210.56981)
		(end 89.55659 -210.56981)
		(width 0.174752)
		(layer "F.Cu")
		(net "PE_100M_CLK2_P")
	)
	(segment
		(start 77.343 -210.8327)
		(end 76.98232 -210.47202)
		(width 0.174752)
		(layer "F.Cu")
		(net "PE_100M_CLK2_P")
	)
	(segment
		(start 78.3844 -210.8327)
		(end 78.74508 -210.47202)
		(width 0.174752)
		(layer "F.Cu")
		(net "PE_100M_CLK2_P")
	)
	(segment
		(start 9.2456 -380.872746)
		(end 9.2456 -381.889)
		(width 0.174752)
		(layer "F.Cu")
		(net "PE_100M_CLK2_P")
	)
	(segment
		(start 76.98232 -210.47202)
		(end 71.329042 -210.47202)
		(width 0.174752)
		(layer "F.Cu")
		(net "PE_100M_CLK2_P")
	)
	(segment
		(start 78.74508 -210.47202)
		(end 85.41512 -210.47202)
		(width 0.174752)
		(layer "F.Cu")
		(net "PE_100M_CLK2_P")
	)
	(segment
		(start 85.67928 -210.47202)
		(end 88.634316 -210.47202)
		(width 0.174752)
		(layer "F.Cu")
		(net "PE_100M_CLK2_P")
	)
	(segment
		(start 12.7 -328.009758)
		(end 12.7 -373.557546)
		(width 0.174752)
		(layer "F.Cu")
		(net "PE_100M_CLK2_P")
	)
	(segment
		(start 14.4018 -205.9686)
		(end 14.4018 -267.318744)
		(width 0.174752)
		(layer "F.Cu")
		(net "PE_100M_CLK2_P")
	)
	(segment
		(start 69.372988 -210.599782)
		(end 69.245226 -210.47202)
		(width 0.174752)
		(layer "F.Cu")
		(net "PE_100M_CLK2_P")
	)
	(segment
		(start 9.394444 -380.723902)
		(end 9.2456 -380.872746)
		(width 0.174752)
		(layer "F.Cu")
		(net "PE_100M_CLK2_P")
	)
	(segment
		(start 15.113 -301.244254)
		(end 13.860018 -302.497236)
		(width 0.174752)
		(layer "F.Cu")
		(net "PE_100M_CLK2_P")
	)
	(segment
		(start 70.025006 -210.47202)
		(end 69.897244 -210.599782)
		(width 0.174752)
		(layer "F.Cu")
		(net "PE_100M_CLK2_P")
	)
	(segment
		(start 70.694804 -210.617562)
		(end 70.549262 -210.47202)
		(width 0.174752)
		(layer "F.Cu")
		(net "PE_100M_CLK2_P")
	)
	(segment
		(start 13.860018 -302.497236)
		(end 13.860018 -326.84974)
		(width 0.174752)
		(layer "F.Cu")
		(net "PE_100M_CLK2_P")
	)
	(segment
		(start 9.394444 -380.24181)
		(end 9.394444 -380.723902)
		(width 0.174752)
		(layer "F.Cu")
		(net "PE_100M_CLK2_P")
	)
	(segment
		(start 48.29302 -210.47202)
		(end 40.411654 -202.590654)
		(width 0.174752)
		(layer "F.Cu")
		(net "PE_100M_CLK2_P")
	)
	(segment
		(start 9.407906 -378.951236)
		(end 9.407906 -379.406404)
		(width 0.174752)
		(layer "F.Cu")
		(net "PE_100M_CLK2_P")
	)
	(segment
		(start 69.897244 -210.599782)
		(end 69.372988 -210.599782)
		(width 0.174752)
		(layer "F.Cu")
		(net "PE_100M_CLK2_P")
	)
	(segment
		(start 12.7 -373.557546)
		(end 9.2456 -377.011946)
		(width 0.174752)
		(layer "F.Cu")
		(net "PE_100M_CLK2_P")
	)
	(segment
		(start 13.860018 -326.84974)
		(end 12.7 -328.009758)
		(width 0.174752)
		(layer "F.Cu")
		(net "PE_100M_CLK2_P")
	)
	(segment
		(start 88.634316 -210.47202)
		(end 88.732106 -210.56981)
		(width 0.174752)
		(layer "F.Cu")
		(net "PE_100M_CLK2_P")
	)
	(segment
		(start 9.2456 -381.889)
		(end 8.9408 -382.1938)
		(width 0.174752)
		(layer "F.Cu")
		(net "PE_100M_CLK2_P")
	)
	(segment
		(start 9.2456 -379.56871)
		(end 9.2456 -380.092966)
		(width 0.174752)
		(layer "F.Cu")
		(net "PE_100M_CLK2_P")
	)
	(segment
		(start 71.1835 -210.617562)
		(end 70.694804 -210.617562)
		(width 0.174752)
		(layer "F.Cu")
		(net "PE_100M_CLK2_P")
	)
	(segment
		(start 40.411654 -202.590654)
		(end 17.779746 -202.590654)
		(width 0.174752)
		(layer "F.Cu")
		(net "PE_100M_CLK2_P")
	)
	(segment
		(start 70.549262 -210.47202)
		(end 70.025006 -210.47202)
		(width 0.174752)
		(layer "F.Cu")
		(net "PE_100M_CLK2_P")
	)
	(segment
		(start 15.113 -268.029944)
		(end 15.113 -301.244254)
		(width 0.174752)
		(layer "F.Cu")
		(net "PE_100M_CLK2_P")
	)
	(segment
		(start 9.407906 -379.406404)
		(end 9.2456 -379.56871)
		(width 0.174752)
		(layer "F.Cu")
		(net "PE_100M_CLK2_P")
	)
	(segment
		(start 17.779746 -202.590654)
		(end 14.4018 -205.9686)
		(width 0.174752)
		(layer "F.Cu")
		(net "PE_100M_CLK2_P")
	)
	(segment
		(start 85.5472 -210.6041)
		(end 85.67928 -210.47202)
		(width 0.174752)
		(layer "F.Cu")
		(net "PE_100M_CLK2_P")
	)
	(segment
		(start 9.2456 -378.78893)
		(end 9.407906 -378.951236)
		(width 0.174752)
		(layer "F.Cu")
		(net "PE_100M_CLK2_P")
	)
	(segment
		(start 78.3844 -210.8327)
		(end 78.029054 -210.477354)
		(width 0.174752)
		(layer "F.Cu")
		(net "PE_100M_CLK2_P")
	)
	(segment
		(start 71.329042 -210.47202)
		(end 71.1835 -210.617562)
		(width 0.174752)
		(layer "F.Cu")
		(net "PE_100M_CLK2_P")
	)
	(segment
		(start 8.9408 -383.3622)
		(end 9.2329 -383.6543)
		(width 0.174752)
		(layer "F.Cu")
		(net "PE_100M_CLK2_P")
	)
	(segment
		(start 14.4018 -267.318744)
		(end 15.113 -268.029944)
		(width 0.174752)
		(layer "F.Cu")
		(net "PE_100M_CLK2_P")
	)
	(segment
		(start 9.2456 -380.092966)
		(end 9.394444 -380.24181)
		(width 0.174752)
		(layer "F.Cu")
		(net "PE_100M_CLK2_P")
	)
	(segment
		(start 77.698346 -210.477354)
		(end 77.343 -210.8327)
		(width 0.174752)
		(layer "F.Cu")
		(net "PE_100M_CLK2_P")
	)
	(segment
		(start 12.394946 -373.431054)
		(end 8.940546 -376.885454)
		(width 0.174752)
		(layer "F.Cu")
		(net "PE_100M_CLK2_N")
	)
	(segment
		(start 85.5472 -210.0453)
		(end 85.668866 -210.166966)
		(width 0.174752)
		(layer "F.Cu")
		(net "PE_100M_CLK2_N")
	)
	(segment
		(start 8.635746 -382.067308)
		(end 8.635746 -383.362454)
		(width 0.174752)
		(layer "F.Cu")
		(net "PE_100M_CLK2_N")
	)
	(segment
		(start 76.992734 -210.166966)
		(end 48.419512 -210.166966)
		(width 0.174752)
		(layer "F.Cu")
		(net "PE_100M_CLK2_N")
	)
	(segment
		(start 85.425534 -210.166966)
		(end 85.5472 -210.0453)
		(width 0.174752)
		(layer "F.Cu")
		(net "PE_100M_CLK2_N")
	)
	(segment
		(start 77.343 -209.8167)
		(end 76.992734 -210.166966)
		(width 0.174752)
		(layer "F.Cu")
		(net "PE_100M_CLK2_N")
	)
	(segment
		(start 78.0288 -210.1723)
		(end 77.6986 -210.1723)
		(width 0.174752)
		(layer "F.Cu")
		(net "PE_100M_CLK2_N")
	)
	(segment
		(start 85.668866 -210.166966)
		(end 88.634316 -210.166966)
		(width 0.174752)
		(layer "F.Cu")
		(net "PE_100M_CLK2_N")
	)
	(segment
		(start 78.3844 -209.8167)
		(end 78.0288 -210.1723)
		(width 0.174752)
		(layer "F.Cu")
		(net "PE_100M_CLK2_N")
	)
	(segment
		(start 88.634316 -210.166966)
		(end 88.731852 -210.06943)
		(width 0.174752)
		(layer "F.Cu")
		(net "PE_100M_CLK2_N")
	)
	(segment
		(start 88.731852 -210.06943)
		(end 89.55659 -210.06943)
		(width 0.174752)
		(layer "F.Cu")
		(net "PE_100M_CLK2_N")
	)
	(segment
		(start 13.554964 -302.370744)
		(end 13.554964 -326.723248)
		(width 0.174752)
		(layer "F.Cu")
		(net "PE_100M_CLK2_N")
	)
	(segment
		(start 8.940546 -376.885454)
		(end 8.940546 -381.762508)
		(width 0.174752)
		(layer "F.Cu")
		(net "PE_100M_CLK2_N")
	)
	(segment
		(start 8.940546 -381.762508)
		(end 8.635746 -382.067308)
		(width 0.174752)
		(layer "F.Cu")
		(net "PE_100M_CLK2_N")
	)
	(segment
		(start 17.653254 -202.2856)
		(end 14.096746 -205.842108)
		(width 0.174752)
		(layer "F.Cu")
		(net "PE_100M_CLK2_N")
	)
	(segment
		(start 78.3844 -209.8167)
		(end 78.734666 -210.166966)
		(width 0.174752)
		(layer "F.Cu")
		(net "PE_100M_CLK2_N")
	)
	(segment
		(start 8.635746 -383.362454)
		(end 8.3439 -383.6543)
		(width 0.174752)
		(layer "F.Cu")
		(net "PE_100M_CLK2_N")
	)
	(segment
		(start 48.419512 -210.166966)
		(end 40.538146 -202.2856)
		(width 0.174752)
		(layer "F.Cu")
		(net "PE_100M_CLK2_N")
	)
	(segment
		(start 13.554964 -326.723248)
		(end 12.394946 -327.883266)
		(width 0.174752)
		(layer "F.Cu")
		(net "PE_100M_CLK2_N")
	)
	(segment
		(start 40.538146 -202.2856)
		(end 17.653254 -202.2856)
		(width 0.174752)
		(layer "F.Cu")
		(net "PE_100M_CLK2_N")
	)
	(segment
		(start 12.394946 -327.883266)
		(end 12.394946 -373.431054)
		(width 0.174752)
		(layer "F.Cu")
		(net "PE_100M_CLK2_N")
	)
	(segment
		(start 14.807946 -301.117762)
		(end 13.554964 -302.370744)
		(width 0.174752)
		(layer "F.Cu")
		(net "PE_100M_CLK2_N")
	)
	(segment
		(start 14.807946 -268.156436)
		(end 14.807946 -301.117762)
		(width 0.174752)
		(layer "F.Cu")
		(net "PE_100M_CLK2_N")
	)
	(segment
		(start 77.6986 -210.1723)
		(end 77.343 -209.8167)
		(width 0.174752)
		(layer "F.Cu")
		(net "PE_100M_CLK2_N")
	)
	(segment
		(start 14.096746 -267.445236)
		(end 14.807946 -268.156436)
		(width 0.174752)
		(layer "F.Cu")
		(net "PE_100M_CLK2_N")
	)
	(segment
		(start 78.734666 -210.166966)
		(end 85.425534 -210.166966)
		(width 0.174752)
		(layer "F.Cu")
		(net "PE_100M_CLK2_N")
	)
	(segment
		(start 14.096746 -205.842108)
		(end 14.096746 -267.445236)
		(width 0.174752)
		(layer "F.Cu")
		(net "PE_100M_CLK2_N")
	)
	(segment
		(start 12.465812 -326.243188)
		(end 12.465812 -301.470822)
		(width 0.174752)
		(layer "F.Cu")
		(net "PE_100M_CLK1_P")
	)
	(segment
		(start 73.288144 -101.397054)
		(end 73.415906 -101.524816)
		(width 0.174752)
		(layer "F.Cu")
		(net "PE_100M_CLK1_P")
	)
	(segment
		(start 73.940162 -101.524816)
		(end 74.067924 -101.397054)
		(width 0.174752)
		(layer "F.Cu")
		(net "PE_100M_CLK1_P")
	)
	(segment
		(start 7.6708 -378.0409)
		(end 7.37489 -377.74499)
		(width 0.174752)
		(layer "F.Cu")
		(net "PE_100M_CLK1_P")
	)
	(segment
		(start 65.087754 -101.397054)
		(end 65.61201 -101.397054)
		(width 0.174752)
		(layer "F.Cu")
		(net "PE_100M_CLK1_P")
	)
	(segment
		(start 64.307974 -101.397054)
		(end 64.435736 -101.524816)
		(width 0.174752)
		(layer "F.Cu")
		(net "PE_100M_CLK1_P")
	)
	(segment
		(start 77.152754 -101.397054)
		(end 77.4954 -101.7397)
		(width 0.174752)
		(layer "F.Cu")
		(net "PE_100M_CLK1_P")
	)
	(segment
		(start 11.305794 -372.234206)
		(end 11.305794 -327.403206)
		(width 0.174752)
		(layer "F.Cu")
		(net "PE_100M_CLK1_P")
	)
	(segment
		(start 58.14695 -101.524816)
		(end 58.274712 -101.397054)
		(width 0.174752)
		(layer "F.Cu")
		(net "PE_100M_CLK1_P")
	)
	(segment
		(start 72.11187 -101.524816)
		(end 72.636126 -101.524816)
		(width 0.174752)
		(layer "F.Cu")
		(net "PE_100M_CLK1_P")
	)
	(segment
		(start 11.305794 -327.403206)
		(end 12.465812 -326.243188)
		(width 0.174752)
		(layer "F.Cu")
		(net "PE_100M_CLK1_P")
	)
	(segment
		(start 78.5622 -101.7397)
		(end 78.206854 -101.384354)
		(width 0.174752)
		(layer "F.Cu")
		(net "PE_100M_CLK1_P")
	)
	(segment
		(start 46.177708 -99.568254)
		(end 48.006508 -101.397054)
		(width 0.174752)
		(layer "F.Cu")
		(net "PE_100M_CLK1_P")
	)
	(segment
		(start 58.798968 -101.397054)
		(end 58.92673 -101.524816)
		(width 0.174752)
		(layer "F.Cu")
		(net "PE_100M_CLK1_P")
	)
	(segment
		(start 59.450986 -101.524816)
		(end 59.578748 -101.397054)
		(width 0.174752)
		(layer "F.Cu")
		(net "PE_100M_CLK1_P")
	)
	(segment
		(start 6.477 -266.954)
		(end 3.302 -263.779)
		(width 0.174752)
		(layer "F.Cu")
		(net "PE_100M_CLK1_P")
	)
	(segment
		(start 14.234922 -101.208078)
		(end 15.874746 -99.568254)
		(width 0.174752)
		(layer "F.Cu")
		(net "PE_100M_CLK1_P")
	)
	(segment
		(start 7.37489 -376.16511)
		(end 11.305794 -372.234206)
		(width 0.174752)
		(layer "F.Cu")
		(net "PE_100M_CLK1_P")
	)
	(segment
		(start 66.39179 -101.397054)
		(end 71.984108 -101.397054)
		(width 0.174752)
		(layer "F.Cu")
		(net "PE_100M_CLK1_P")
	)
	(segment
		(start 73.415906 -101.524816)
		(end 73.940162 -101.524816)
		(width 0.174752)
		(layer "F.Cu")
		(net "PE_100M_CLK1_P")
	)
	(segment
		(start 88.615774 -101.397054)
		(end 88.663018 -101.34981)
		(width 0.174752)
		(layer "F.Cu")
		(net "PE_100M_CLK1_P")
	)
	(segment
		(start 10.830306 -201.202544)
		(end 14.234922 -197.797928)
		(width 0.174752)
		(layer "F.Cu")
		(net "PE_100M_CLK1_P")
	)
	(segment
		(start 58.274712 -101.397054)
		(end 58.798968 -101.397054)
		(width 0.174752)
		(layer "F.Cu")
		(net "PE_100M_CLK1_P")
	)
	(segment
		(start 12.465812 -301.470822)
		(end 13.718794 -300.21784)
		(width 0.174752)
		(layer "F.Cu")
		(net "PE_100M_CLK1_P")
	)
	(segment
		(start 59.578748 -101.397054)
		(end 64.307974 -101.397054)
		(width 0.174752)
		(layer "F.Cu")
		(net "PE_100M_CLK1_P")
	)
	(segment
		(start 58.92673 -101.524816)
		(end 59.450986 -101.524816)
		(width 0.174752)
		(layer "F.Cu")
		(net "PE_100M_CLK1_P")
	)
	(segment
		(start 66.264028 -101.524816)
		(end 66.39179 -101.397054)
		(width 0.174752)
		(layer "F.Cu")
		(net "PE_100M_CLK1_P")
	)
	(segment
		(start 78.5622 -101.7397)
		(end 78.904846 -101.397054)
		(width 0.174752)
		(layer "F.Cu")
		(net "PE_100M_CLK1_P")
	)
	(segment
		(start 57.622694 -101.524816)
		(end 58.14695 -101.524816)
		(width 0.174752)
		(layer "F.Cu")
		(net "PE_100M_CLK1_P")
	)
	(segment
		(start 74.067924 -101.397054)
		(end 77.152754 -101.397054)
		(width 0.174752)
		(layer "F.Cu")
		(net "PE_100M_CLK1_P")
	)
	(segment
		(start 65.61201 -101.397054)
		(end 65.739772 -101.524816)
		(width 0.174752)
		(layer "F.Cu")
		(net "PE_100M_CLK1_P")
	)
	(segment
		(start 72.636126 -101.524816)
		(end 72.763888 -101.397054)
		(width 0.174752)
		(layer "F.Cu")
		(net "PE_100M_CLK1_P")
	)
	(segment
		(start 78.206854 -101.384354)
		(end 77.850746 -101.384354)
		(width 0.174752)
		(layer "F.Cu")
		(net "PE_100M_CLK1_P")
	)
	(segment
		(start 77.850746 -101.384354)
		(end 77.4954 -101.7397)
		(width 0.174752)
		(layer "F.Cu")
		(net "PE_100M_CLK1_P")
	)
	(segment
		(start 72.763888 -101.397054)
		(end 73.288144 -101.397054)
		(width 0.174752)
		(layer "F.Cu")
		(net "PE_100M_CLK1_P")
	)
	(segment
		(start 71.984108 -101.397054)
		(end 72.11187 -101.524816)
		(width 0.174752)
		(layer "F.Cu")
		(net "PE_100M_CLK1_P")
	)
	(segment
		(start 78.904846 -101.397054)
		(end 85.674454 -101.397054)
		(width 0.174752)
		(layer "F.Cu")
		(net "PE_100M_CLK1_P")
	)
	(segment
		(start 13.718794 -268.607794)
		(end 12.065 -266.954)
		(width 0.174752)
		(layer "F.Cu")
		(net "PE_100M_CLK1_P")
	)
	(segment
		(start 3.302 -258.749546)
		(end 10.830306 -251.22124)
		(width 0.174752)
		(layer "F.Cu")
		(net "PE_100M_CLK1_P")
	)
	(segment
		(start 85.674454 -101.397054)
		(end 85.8012 -101.5238)
		(width 0.174752)
		(layer "F.Cu")
		(net "PE_100M_CLK1_P")
	)
	(segment
		(start 85.8012 -101.5238)
		(end 85.927946 -101.397054)
		(width 0.174752)
		(layer "F.Cu")
		(net "PE_100M_CLK1_P")
	)
	(segment
		(start 48.006508 -101.397054)
		(end 57.494932 -101.397054)
		(width 0.174752)
		(layer "F.Cu")
		(net "PE_100M_CLK1_P")
	)
	(segment
		(start 12.065 -266.954)
		(end 6.477 -266.954)
		(width 0.174752)
		(layer "F.Cu")
		(net "PE_100M_CLK1_P")
	)
	(segment
		(start 88.663018 -101.34981)
		(end 89.55659 -101.34981)
		(width 0.174752)
		(layer "F.Cu")
		(net "PE_100M_CLK1_P")
	)
	(segment
		(start 64.959992 -101.524816)
		(end 65.087754 -101.397054)
		(width 0.174752)
		(layer "F.Cu")
		(net "PE_100M_CLK1_P")
	)
	(segment
		(start 57.494932 -101.397054)
		(end 57.622694 -101.524816)
		(width 0.174752)
		(layer "F.Cu")
		(net "PE_100M_CLK1_P")
	)
	(segment
		(start 14.234922 -197.797928)
		(end 14.234922 -101.208078)
		(width 0.174752)
		(layer "F.Cu")
		(net "PE_100M_CLK1_P")
	)
	(segment
		(start 15.874746 -99.568254)
		(end 46.177708 -99.568254)
		(width 0.174752)
		(layer "F.Cu")
		(net "PE_100M_CLK1_P")
	)
	(segment
		(start 10.830306 -251.22124)
		(end 10.830306 -201.202544)
		(width 0.174752)
		(layer "F.Cu")
		(net "PE_100M_CLK1_P")
	)
	(segment
		(start 85.927946 -101.397054)
		(end 88.615774 -101.397054)
		(width 0.174752)
		(layer "F.Cu")
		(net "PE_100M_CLK1_P")
	)
	(segment
		(start 3.302 -263.779)
		(end 3.302 -258.749546)
		(width 0.174752)
		(layer "F.Cu")
		(net "PE_100M_CLK1_P")
	)
	(segment
		(start 64.435736 -101.524816)
		(end 64.959992 -101.524816)
		(width 0.174752)
		(layer "F.Cu")
		(net "PE_100M_CLK1_P")
	)
	(segment
		(start 7.37489 -377.74499)
		(end 7.37489 -376.16511)
		(width 0.174752)
		(layer "F.Cu")
		(net "PE_100M_CLK1_P")
	)
	(segment
		(start 13.718794 -300.21784)
		(end 13.718794 -268.607794)
		(width 0.174752)
		(layer "F.Cu")
		(net "PE_100M_CLK1_P")
	)
	(segment
		(start 65.739772 -101.524816)
		(end 66.264028 -101.524816)
		(width 0.174752)
		(layer "F.Cu")
		(net "PE_100M_CLK1_P")
	)
	(segment
		(start 78.5622 -100.7237)
		(end 78.2066 -101.0793)
		(width 0.174752)
		(layer "F.Cu")
		(net "PE_100M_CLK1_N")
	)
	(segment
		(start 78.2066 -101.0793)
		(end 77.851 -101.0793)
		(width 0.174752)
		(layer "F.Cu")
		(net "PE_100M_CLK1_N")
	)
	(segment
		(start 6.7564 -378.0409)
		(end 7.069836 -377.727464)
		(width 0.174752)
		(layer "F.Cu")
		(net "PE_100M_CLK1_N")
	)
	(segment
		(start 77.851 -101.0793)
		(end 77.4954 -100.7237)
		(width 0.174752)
		(layer "F.Cu")
		(net "PE_100M_CLK1_N")
	)
	(segment
		(start 77.1271 -101.092)
		(end 77.4954 -100.7237)
		(width 0.174752)
		(layer "F.Cu")
		(net "PE_100M_CLK1_N")
	)
	(segment
		(start 13.929868 -101.081586)
		(end 15.748254 -99.2632)
		(width 0.174752)
		(layer "F.Cu")
		(net "PE_100M_CLK1_N")
	)
	(segment
		(start 10.525252 -201.076052)
		(end 13.929868 -197.671436)
		(width 0.174752)
		(layer "F.Cu")
		(net "PE_100M_CLK1_N")
	)
	(segment
		(start 12.160758 -326.116696)
		(end 12.160758 -301.34433)
		(width 0.174752)
		(layer "F.Cu")
		(net "PE_100M_CLK1_N")
	)
	(segment
		(start 15.748254 -99.2632)
		(end 46.3042 -99.2632)
		(width 0.174752)
		(layer "F.Cu")
		(net "PE_100M_CLK1_N")
	)
	(segment
		(start 85.6742 -101.092)
		(end 85.8012 -100.965)
		(width 0.174752)
		(layer "F.Cu")
		(net "PE_100M_CLK1_N")
	)
	(segment
		(start 13.41374 -300.091348)
		(end 13.41374 -268.734286)
		(width 0.174752)
		(layer "F.Cu")
		(net "PE_100M_CLK1_N")
	)
	(segment
		(start 78.9305 -101.092)
		(end 85.6742 -101.092)
		(width 0.174752)
		(layer "F.Cu")
		(net "PE_100M_CLK1_N")
	)
	(segment
		(start 88.489282 -101.092)
		(end 88.731852 -100.84943)
		(width 0.174752)
		(layer "F.Cu")
		(net "PE_100M_CLK1_N")
	)
	(segment
		(start 12.160758 -301.34433)
		(end 13.41374 -300.091348)
		(width 0.174752)
		(layer "F.Cu")
		(net "PE_100M_CLK1_N")
	)
	(segment
		(start 10.525252 -251.094748)
		(end 10.525252 -201.076052)
		(width 0.174752)
		(layer "F.Cu")
		(net "PE_100M_CLK1_N")
	)
	(segment
		(start 7.069836 -376.038618)
		(end 11.00074 -372.107714)
		(width 0.174752)
		(layer "F.Cu")
		(net "PE_100M_CLK1_N")
	)
	(segment
		(start 46.3042 -99.2632)
		(end 48.133 -101.092)
		(width 0.174752)
		(layer "F.Cu")
		(net "PE_100M_CLK1_N")
	)
	(segment
		(start 2.996946 -263.905492)
		(end 2.996946 -258.623054)
		(width 0.174752)
		(layer "F.Cu")
		(net "PE_100M_CLK1_N")
	)
	(segment
		(start 88.731852 -100.84943)
		(end 89.55659 -100.84943)
		(width 0.174752)
		(layer "F.Cu")
		(net "PE_100M_CLK1_N")
	)
	(segment
		(start 85.8012 -100.965)
		(end 85.9282 -101.092)
		(width 0.174752)
		(layer "F.Cu")
		(net "PE_100M_CLK1_N")
	)
	(segment
		(start 6.350508 -267.259054)
		(end 2.996946 -263.905492)
		(width 0.174752)
		(layer "F.Cu")
		(net "PE_100M_CLK1_N")
	)
	(segment
		(start 85.9282 -101.092)
		(end 88.489282 -101.092)
		(width 0.174752)
		(layer "F.Cu")
		(net "PE_100M_CLK1_N")
	)
	(segment
		(start 13.41374 -268.734286)
		(end 11.938508 -267.259054)
		(width 0.174752)
		(layer "F.Cu")
		(net "PE_100M_CLK1_N")
	)
	(segment
		(start 48.133 -101.092)
		(end 77.1271 -101.092)
		(width 0.174752)
		(layer "F.Cu")
		(net "PE_100M_CLK1_N")
	)
	(segment
		(start 11.00074 -327.276714)
		(end 12.160758 -326.116696)
		(width 0.174752)
		(layer "F.Cu")
		(net "PE_100M_CLK1_N")
	)
	(segment
		(start 2.996946 -258.623054)
		(end 10.525252 -251.094748)
		(width 0.174752)
		(layer "F.Cu")
		(net "PE_100M_CLK1_N")
	)
	(segment
		(start 78.5622 -100.7237)
		(end 78.9305 -101.092)
		(width 0.174752)
		(layer "F.Cu")
		(net "PE_100M_CLK1_N")
	)
	(segment
		(start 11.938508 -267.259054)
		(end 6.350508 -267.259054)
		(width 0.174752)
		(layer "F.Cu")
		(net "PE_100M_CLK1_N")
	)
	(segment
		(start 11.00074 -372.107714)
		(end 11.00074 -327.276714)
		(width 0.174752)
		(layer "F.Cu")
		(net "PE_100M_CLK1_N")
	)
	(segment
		(start 7.069836 -377.727464)
		(end 7.069836 -376.038618)
		(width 0.174752)
		(layer "F.Cu")
		(net "PE_100M_CLK1_N")
	)
	(segment
		(start 13.929868 -197.671436)
		(end 13.929868 -101.081586)
		(width 0.174752)
		(layer "F.Cu")
		(net "PE_100M_CLK1_N")
	)
	(segment
		(start 2.249932 -234.342178)
		(end 3.683 -234.342178)
		(width 0.17145)
		(layer "F.Cu")
		(net "PCIE_MATED#_B")
	)
	(segment
		(start 3.683 -234.342178)
		(end 3.909822 -234.569)
		(width 0.17145)
		(layer "F.Cu")
		(net "PCIE_MATED#_B")
	)
	(segment
		(start 6.5151 -250.7869)
		(end 6.35 -250.952)
		(width 0.17145)
		(layer "F.Cu")
		(net "PCIE_MATED#_B")
	)
	(segment
		(start 3.909822 -234.569)
		(end 4.507992 -234.569)
		(width 0.17145)
		(layer "F.Cu")
		(net "PCIE_MATED#_B")
	)
	(segment
		(start 4.507992 -234.569)
		(end 6.5151 -236.576108)
		(width 0.17145)
		(layer "F.Cu")
		(net "PCIE_MATED#_B")
	)
	(segment
		(start 6.5151 -236.576108)
		(end 6.5151 -250.7869)
		(width 0.17145)
		(layer "F.Cu")
		(net "PCIE_MATED#_B")
	)
	(segment
		(start 5.915914 -269.948914)
		(end 8.053578 -269.948914)
		(width 0.17145)
		(layer "F.Cu")
		(net "PCIE_MATED#_B")
	)
	(via
		(at 5.915914 -269.948914)
		(size 0.508)
		(drill 0.254)
		(layers "F.Cu" "B.Cu")
		(net "PCIE_MATED#_B")
	)
	(via
		(at 6.35 -250.952)
		(size 0.5588)
		(drill 0.3048)
		(layers "F.Cu" "B.Cu")
		(net "PCIE_MATED#_B")
	)
	(segment
		(start 2.032 -265.303)
		(end 5.915914 -269.186914)
		(width 0.1524)
		(layer "In5.Cu")
		(net "PCIE_MATED#_B")
	)
	(segment
		(start 2.032 -255.27)
		(end 2.032 -265.303)
		(width 0.1524)
		(layer "In5.Cu")
		(net "PCIE_MATED#_B")
	)
	(segment
		(start 6.35 -250.952)
		(end 2.032 -255.27)
		(width 0.1524)
		(layer "In5.Cu")
		(net "PCIE_MATED#_B")
	)
	(segment
		(start 5.915914 -269.186914)
		(end 5.915914 -269.948914)
		(width 0.1524)
		(layer "In5.Cu")
		(net "PCIE_MATED#_B")
	)
	(segment
		(start 7.755128 -422.454324)
		(end 10.4394 -419.770052)
		(width 0.17145)
		(layer "F.Cu")
		(net "PCIE_MATED#_A")
	)
	(segment
		(start 3.986276 -422.454324)
		(end 7.755128 -422.454324)
		(width 0.17145)
		(layer "F.Cu")
		(net "PCIE_MATED#_A")
	)
	(segment
		(start 2.249932 -423.141902)
		(end 3.298698 -423.141902)
		(width 0.17145)
		(layer "F.Cu")
		(net "PCIE_MATED#_A")
	)
	(segment
		(start 10.4394 -419.770052)
		(end 10.4394 -414.9471)
		(width 0.17145)
		(layer "F.Cu")
		(net "PCIE_MATED#_A")
	)
	(segment
		(start 3.298698 -423.141902)
		(end 3.986276 -422.454324)
		(width 0.17145)
		(layer "F.Cu")
		(net "PCIE_MATED#_A")
	)
	(segment
		(start 229.67696 -447.56324)
		(end 228.0285 -447.56324)
		(width 0.381)
		(layer "F.Cu")
		(net "P3V3")
	)
	(segment
		(start 16.26616 -257.309874)
		(end 16.11503 -257.158744)
		(width 0.508)
		(layer "F.Cu")
		(net "P3V3")
	)
	(segment
		(start 212.0265 -460.9465)
		(end 212.0265 -461.518)
		(width 0.3556)
		(layer "F.Cu")
		(net "P3V3")
	)
	(segment
		(start 96.266 -440.1185)
		(end 96.266 -440.944)
		(width 0.508)
		(layer "F.Cu")
		(net "P3V3")
	)
	(segment
		(start 207.01 -453.39)
		(end 207.01 -454.2155)
		(width 0.508)
		(layer "F.Cu")
		(net "P3V3")
	)
	(segment
		(start 32.004 -318.0207)
		(end 32.8041 -318.0207)
		(width 0.508)
		(layer "F.Cu")
		(net "P3V3")
	)
	(segment
		(start 27.6987 -392.0998)
		(end 27.6987 -391.3124)
		(width 0.508)
		(layer "F.Cu")
		(net "P3V3")
	)
	(segment
		(start 207.391 -196.7865)
		(end 206.0575 -196.7865)
		(width 0.508)
		(layer "F.Cu")
		(net "P3V3")
	)
	(segment
		(start 18.68424 -466.66658)
		(end 18.68424 -467.295484)
		(width 0.508)
		(layer "F.Cu")
		(net "P3V3")
	)
	(segment
		(start 226.505262 -450.025516)
		(end 226.505262 -450.850762)
		(width 0.508)
		(layer "F.Cu")
		(net "P3V3")
	)
	(segment
		(start 70.358 -456.692)
		(end 69.977 -456.311)
		(width 0.508)
		(layer "F.Cu")
		(net "P3V3")
	)
	(segment
		(start 23.656544 -467.026244)
		(end 23.656544 -466.695028)
		(width 0.508)
		(layer "F.Cu")
		(net "P3V3")
	)
	(segment
		(start 20.358862 -161.40811)
		(end 20.358862 -161.482532)
		(width 0.508)
		(layer "F.Cu")
		(net "P3V3")
	)
	(segment
		(start 90.4875 -417.60648)
		(end 90.486738 -417.607242)
		(width 0.508)
		(layer "F.Cu")
		(net "P3V3")
	)
	(segment
		(start 16.160242 -154.669998)
		(end 15.856204 -154.36596)
		(width 0.508)
		(layer "F.Cu")
		(net "P3V3")
	)
	(segment
		(start 74.422 -445.008)
		(end 73.152 -445.008)
		(width 0.508)
		(layer "F.Cu")
		(net "P3V3")
	)
	(segment
		(start 49.416208 -43.464226)
		(end 47.039276 -43.464226)
		(width 0.508)
		(layer "F.Cu")
		(net "P3V3")
	)
	(segment
		(start 108.966 -310.7055)
		(end 108.077 -310.7055)
		(width 0.508)
		(layer "F.Cu")
		(net "P3V3")
	)
	(segment
		(start 73.787 -104.648)
		(end 74.803 -103.632)
		(width 1.016)
		(layer "F.Cu")
		(net "P3V3")
	)
	(segment
		(start 72.3646 -352.2345)
		(end 72.3646 -351.409)
		(width 0.508)
		(layer "F.Cu")
		(net "P3V3")
	)
	(segment
		(start 39.9288 -104.648)
		(end 73.787 -104.648)
		(width 1.016)
		(layer "F.Cu")
		(net "P3V3")
	)
	(segment
		(start 218.8845 -346.579952)
		(end 217.852752 -346.579952)
		(width 0.508)
		(layer "F.Cu")
		(net "P3V3")
	)
	(segment
		(start 48.3235 -349.885)
		(end 49.1236 -349.885)
		(width 0.508)
		(layer "F.Cu")
		(net "P3V3")
	)
	(segment
		(start 40.32504 -145.796)
		(end 40.88765 -145.23339)
		(width 0.508)
		(layer "F.Cu")
		(net "P3V3")
	)
	(segment
		(start 51.471576 -447.8909)
		(end 51.637946 -447.8909)
		(width 0.508)
		(layer "F.Cu")
		(net "P3V3")
	)
	(segment
		(start 96.3295 -115.7986)
		(end 96.331532 -115.796568)
		(width 0.508)
		(layer "F.Cu")
		(net "P3V3")
	)
	(segment
		(start 70.2945 -358.521)
		(end 69.469 -358.521)
		(width 0.508)
		(layer "F.Cu")
		(net "P3V3")
	)
	(segment
		(start 212.026754 -51.562254)
		(end 212.0265 -51.562)
		(width 0.508)
		(layer "F.Cu")
		(net "P3V3")
	)
	(segment
		(start 98.3615 -320.167)
		(end 98.3615 -319.380108)
		(width 0.508)
		(layer "F.Cu")
		(net "P3V3")
	)
	(segment
		(start 108.966 -206.4385)
		(end 108.176314 -206.4385)
		(width 0.508)
		(layer "F.Cu")
		(net "P3V3")
	)
	(segment
		(start 227.389944 -165.189916)
		(end 228.966014 -165.189916)
		(width 0.508)
		(layer "F.Cu")
		(net "P3V3")
	)
	(segment
		(start 224.663 -143.2052)
		(end 224.480374 -143.387826)
		(width 0.508)
		(layer "F.Cu")
		(net "P3V3")
	)
	(segment
		(start 97.028 -25.7175)
		(end 97.028 -24.892)
		(width 0.508)
		(layer "F.Cu")
		(net "P3V3")
	)
	(segment
		(start 40.597074 -232.029)
		(end 36.406074 -236.22)
		(width 1.016)
		(layer "F.Cu")
		(net "P3V3")
	)
	(segment
		(start 40.5384 -147.6756)
		(end 32.2961 -147.6756)
		(width 1.016)
		(layer "F.Cu")
		(net "P3V3")
	)
	(segment
		(start 82.1055 -359.029)
		(end 82.931 -359.029)
		(width 0.508)
		(layer "F.Cu")
		(net "P3V3")
	)
	(segment
		(start 84.5185 -144.92732)
		(end 85.344 -144.92732)
		(width 0.508)
		(layer "F.Cu")
		(net "P3V3")
	)
	(segment
		(start 108.181394 -208.4705)
		(end 108.17606 -208.465166)
		(width 0.508)
		(layer "F.Cu")
		(net "P3V3")
	)
	(segment
		(start 57.3024 -95.504)
		(end 63.130938 -95.504)
		(width 1.016)
		(layer "F.Cu")
		(net "P3V3")
	)
	(segment
		(start 229.67696 -242.503198)
		(end 228.7905 -243.389658)
		(width 0.508)
		(layer "F.Cu")
		(net "P3V3")
	)
	(segment
		(start 25.4 -133.35)
		(end 26.797 -133.35)
		(width 0.508)
		(layer "F.Cu")
		(net "P3V3")
	)
	(segment
		(start 217.1446 -345.8718)
		(end 217.852752 -346.579952)
		(width 1.016)
		(layer "F.Cu")
		(net "P3V3")
	)
	(segment
		(start 97.4725 -290.994592)
		(end 97.474278 -290.99637)
		(width 0.508)
		(layer "F.Cu")
		(net "P3V3")
	)
	(segment
		(start 9.4742 -497.64696)
		(end 11.18108 -495.94008)
		(width 0.508)
		(layer "F.Cu")
		(net "P3V3")
	)
	(segment
		(start 40.91813 -249.077988)
		(end 41.627298 -249.077988)
		(width 0.508)
		(layer "F.Cu")
		(net "P3V3")
	)
	(segment
		(start 228.7905 -346.389452)
		(end 229.67696 -345.502992)
		(width 0.508)
		(layer "F.Cu")
		(net "P3V3")
	)
	(segment
		(start 228.331268 -454.867264)
		(end 233.730546 -454.867264)
		(width 0.508)
		(layer "F.Cu")
		(net "P3V3")
	)
	(segment
		(start 103.7082 -313.055)
		(end 103.7082 -314.325)
		(width 0.508)
		(layer "F.Cu")
		(net "P3V3")
	)
	(segment
		(start 14.224 -480.314)
		(end 25.564338 -480.314)
		(width 1.016)
		(layer "F.Cu")
		(net "P3V3")
	)
	(segment
		(start 224.924874 -41.860216)
		(end 224.924874 -42.372026)
		(width 0.508)
		(layer "F.Cu")
		(net "P3V3")
	)
	(segment
		(start 22.86 -299.4152)
		(end 22.479 -299.0342)
		(width 0.508)
		(layer "F.Cu")
		(net "P3V3")
	)
	(segment
		(start 206.502 -402.7805)
		(end 207.391 -402.7805)
		(width 0.508)
		(layer "F.Cu")
		(net "P3V3")
	)
	(segment
		(start 28.546552 -478.537778)
		(end 28.540964 -478.53219)
		(width 1.016)
		(layer "F.Cu")
		(net "P3V3")
	)
	(segment
		(start 203.962 -203.073)
		(end 197.0786 -209.9564)
		(width 1.016)
		(layer "F.Cu")
		(net "P3V3")
	)
	(segment
		(start 228.7905 -449.3895)
		(end 228.2952 -449.3895)
		(width 0.508)
		(layer "F.Cu")
		(net "P3V3")
	)
	(segment
		(start 43.282108 -37.516562)
		(end 42.493692 -37.516562)
		(width 0.508)
		(layer "F.Cu")
		(net "P3V3")
	)
	(segment
		(start 75.184 -154.6225)
		(end 75.184 -155.448)
		(width 0.508)
		(layer "F.Cu")
		(net "P3V3")
	)
	(segment
		(start 90.4875 -86.614)
		(end 90.4875 -87.418926)
		(width 0.508)
		(layer "F.Cu")
		(net "P3V3")
	)
	(segment
		(start 224.663 -245.421658)
		(end 224.663 -246.205248)
		(width 0.508)
		(layer "F.Cu")
		(net "P3V3")
	)
	(segment
		(start 229.904036 -35.563302)
		(end 229.904036 -36.503102)
		(width 0.508)
		(layer "F.Cu")
		(net "P3V3")
	)
	(segment
		(start 212.55482 -49.975262)
		(end 212.55482 -50.46218)
		(width 0.3556)
		(layer "F.Cu")
		(net "P3V3")
	)
	(segment
		(start 75.438 -454.279)
		(end 74.6125 -455.1045)
		(width 0.508)
		(layer "F.Cu")
		(net "P3V3")
	)
	(segment
		(start 50.8635 -144.526)
		(end 50.8635 -145.3134)
		(width 0.508)
		(layer "F.Cu")
		(net "P3V3")
	)
	(segment
		(start 243.586 -421.7035)
		(end 243.586 -420.878)
		(width 0.508)
		(layer "F.Cu")
		(net "P3V3")
	)
	(segment
		(start 20.2819 -469.8111)
		(end 20.4724 -469.6206)
		(width 0.508)
		(layer "F.Cu")
		(net "P3V3")
	)
	(segment
		(start 40.91813 -249.077988)
		(end 40.765984 -248.925842)
		(width 0.508)
		(layer "F.Cu")
		(net "P3V3")
	)
	(segment
		(start 229.904036 -35.563302)
		(end 228.2825 -35.563302)
		(width 0.381)
		(layer "F.Cu")
		(net "P3V3")
	)
	(segment
		(start 21.336 -264.8585)
		(end 20.749006 -264.271506)
		(width 0.508)
		(layer "F.Cu")
		(net "P3V3")
	)
	(segment
		(start 227.617782 -37.389562)
		(end 227.001832 -38.005512)
		(width 0.508)
		(layer "F.Cu")
		(net "P3V3")
	)
	(segment
		(start 39.840916 -309.1815)
		(end 40.145208 -308.877208)
		(width 0.508)
		(layer "F.Cu")
		(net "P3V3")
	)
	(segment
		(start 15.92961 -361.277662)
		(end 15.992348 -361.3404)
		(width 0.508)
		(layer "F.Cu")
		(net "P3V3")
	)
	(segment
		(start 227.005896 -245.00205)
		(end 227.005896 -245.341902)
		(width 0.508)
		(layer "F.Cu")
		(net "P3V3")
	)
	(segment
		(start 19.61007 -340.810088)
		(end 18.034 -340.810088)
		(width 0.508)
		(layer "F.Cu")
		(net "P3V3")
	)
	(segment
		(start 70.2945 -148.59)
		(end 69.469 -148.59)
		(width 0.508)
		(layer "F.Cu")
		(net "P3V3")
	)
	(segment
		(start 19.4056 -160.454848)
		(end 20.358862 -161.40811)
		(width 0.508)
		(layer "F.Cu")
		(net "P3V3")
	)
	(segment
		(start 9.4742 -497.9797)
		(end 9.4742 -497.64696)
		(width 0.508)
		(layer "F.Cu")
		(net "P3V3")
	)
	(segment
		(start 91.6305 -29.718)
		(end 91.6305 -30.607)
		(width 0.508)
		(layer "F.Cu")
		(net "P3V3")
	)
	(segment
		(start 15.92961 -360.49839)
		(end 15.92961 -361.277662)
		(width 0.508)
		(layer "F.Cu")
		(net "P3V3")
	)
	(segment
		(start 49.5935 -145.669)
		(end 49.5935 -146.4818)
		(width 0.508)
		(layer "F.Cu")
		(net "P3V3")
	)
	(segment
		(start 70.2945 -360.553)
		(end 69.469 -360.553)
		(width 0.508)
		(layer "F.Cu")
		(net "P3V3")
	)
	(segment
		(start 70.2945 -363.601)
		(end 69.469 -363.601)
		(width 0.508)
		(layer "F.Cu")
		(net "P3V3")
	)
	(segment
		(start 49.5935 -144.526)
		(end 50.8635 -144.526)
		(width 0.508)
		(layer "F.Cu")
		(net "P3V3")
	)
	(segment
		(start 20.828 -60.88761)
		(end 21.698458 -60.88761)
		(width 0.508)
		(layer "F.Cu")
		(net "P3V3")
	)
	(segment
		(start 21.231606 -58.66511)
		(end 20.541488 -58.66511)
		(width 0.508)
		(layer "F.Cu")
		(net "P3V3")
	)
	(segment
		(start 22.25675 -164.43325)
		(end 23.172674 -164.43325)
		(width 0.4064)
		(layer "F.Cu")
		(net "P3V3")
	)
	(segment
		(start 74.041 -455.1045)
		(end 74.041 -456.311)
		(width 0.508)
		(layer "F.Cu")
		(net "P3V3")
	)
	(segment
		(start 214.9348 -188.0235)
		(end 214.9348 -188.7982)
		(width 0.508)
		(layer "F.Cu")
		(net "P3V3")
	)
	(segment
		(start 22.2758 -93.2053)
		(end 22.86 -93.7895)
		(width 0.508)
		(layer "F.Cu")
		(net "P3V3")
	)
	(segment
		(start 103.2002 -106.807)
		(end 104.2797 -106.807)
		(width 0.508)
		(layer "F.Cu")
		(net "P3V3")
	)
	(segment
		(start 87.3125 -116.586)
		(end 87.3125 -115.781074)
		(width 0.508)
		(layer "F.Cu")
		(net "P3V3")
	)
	(segment
		(start 226.751896 -347.03766)
		(end 226.773232 -347.016324)
		(width 0.508)
		(layer "F.Cu")
		(net "P3V3")
	)
	(segment
		(start 51.192176 -447.6115)
		(end 51.471576 -447.8909)
		(width 0.508)
		(layer "F.Cu")
		(net "P3V3")
	)
	(segment
		(start 102.1715 -302.768)
		(end 102.997 -302.768)
		(width 0.508)
		(layer "F.Cu")
		(net "P3V3")
	)
	(segment
		(start 11.18108 -495.94008)
		(end 12.202922 -494.918238)
		(width 1.016)
		(layer "F.Cu")
		(net "P3V3")
	)
	(segment
		(start 25.4 -236.22)
		(end 24.384 -236.22)
		(width 0.508)
		(layer "F.Cu")
		(net "P3V3")
	)
	(segment
		(start 227.389944 -62.189868)
		(end 228.966014 -62.189868)
		(width 0.508)
		(layer "F.Cu")
		(net "P3V3")
	)
	(segment
		(start 35.59175 -350.01454)
		(end 35.59175 -350.8502)
		(width 0.508)
		(layer "F.Cu")
		(net "P3V3")
	)
	(segment
		(start 227.468938 -243.389658)
		(end 227.372926 -243.389658)
		(width 0.508)
		(layer "F.Cu")
		(net "P3V3")
	)
	(segment
		(start 32.5755 -381.508)
		(end 32.5755 -382.651)
		(width 0.508)
		(layer "F.Cu")
		(net "P3V3")
	)
	(segment
		(start 40.513 -45.974)
		(end 32.4358 -45.974)
		(width 1.016)
		(layer "F.Cu")
		(net "P3V3")
	)
	(segment
		(start 224.520252 -348.68739)
		(end 224.337626 -348.870016)
		(width 0.508)
		(layer "F.Cu")
		(net "P3V3")
	)
	(segment
		(start 98.552 -441.0202)
		(end 97.282 -441.0202)
		(width 1.016)
		(layer "F.Cu")
		(net "P3V3")
	)
	(segment
		(start 43.688508 -451.653148)
		(end 43.387772 -451.352412)
		(width 0.508)
		(layer "F.Cu")
		(net "P3V3")
	)
	(segment
		(start 210.439 -452.628)
		(end 209.677 -453.39)
		(width 0.508)
		(layer "F.Cu")
		(net "P3V3")
	)
	(segment
		(start 48.3362 -232.029)
		(end 40.597074 -232.029)
		(width 1.016)
		(layer "F.Cu")
		(net "P3V3")
	)
	(segment
		(start 16.160242 -155.22448)
		(end 16.160242 -154.669998)
		(width 0.508)
		(layer "F.Cu")
		(net "P3V3")
	)
	(segment
		(start 234.5055 -145.484596)
		(end 234.086908 -145.903188)
		(width 0.508)
		(layer "F.Cu")
		(net "P3V3")
	)
	(segment
		(start 19.61007 -134.809992)
		(end 18.034 -134.809992)
		(width 0.508)
		(layer "F.Cu")
		(net "P3V3")
	)
	(segment
		(start 221.615 -370.586)
		(end 220.309186 -370.586)
		(width 0.508)
		(layer "F.Cu")
		(net "P3V3")
	)
	(segment
		(start 41.184576 -145.23339)
		(end 41.184576 -143.514318)
		(width 0.508)
		(layer "F.Cu")
		(net "P3V3")
	)
	(segment
		(start 99.5045 -290.195)
		(end 99.5045 -290.999672)
		(width 0.508)
		(layer "F.Cu")
		(net "P3V3")
	)
	(segment
		(start 224.663 -142.42161)
		(end 224.663 -143.2052)
		(width 0.508)
		(layer "F.Cu")
		(net "P3V3")
	)
	(segment
		(start 217.852498 -448.547998)
		(end 218.8845 -449.58)
		(width 0.508)
		(layer "F.Cu")
		(net "P3V3")
	)
	(segment
		(start 229.67696 -138.56335)
		(end 228.0285 -138.56335)
		(width 0.381)
		(layer "F.Cu")
		(net "P3V3")
	)
	(segment
		(start 19.5834 -469.8111)
		(end 20.2819 -469.8111)
		(width 0.508)
		(layer "F.Cu")
		(net "P3V3")
	)
	(segment
		(start 220.309186 -370.586)
		(end 168.148 -370.586)
		(width 1.016)
		(layer "F.Cu")
		(net "P3V3")
	)
	(segment
		(start 27.94 -373.38)
		(end 27.94 -374.2055)
		(width 0.508)
		(layer "F.Cu")
		(net "P3V3")
	)
	(segment
		(start 22.8346 -91.0336)
		(end 22.2758 -91.5924)
		(width 0.508)
		(layer "F.Cu")
		(net "P3V3")
	)
	(segment
		(start 28.546552 -490.583728)
		(end 28.79598 -490.833156)
		(width 1.016)
		(layer "F.Cu")
		(net "P3V3")
	)
	(segment
		(start 55.7403 -451.1548)
		(end 56.515 -451.1548)
		(width 0.508)
		(layer "F.Cu")
		(net "P3V3")
	)
	(segment
		(start 41.184576 -143.514318)
		(end 42.35323 -142.345664)
		(width 0.508)
		(layer "F.Cu")
		(net "P3V3")
	)
	(segment
		(start 75.438 -451.358)
		(end 75.438 -454.279)
		(width 0.508)
		(layer "F.Cu")
		(net "P3V3")
	)
	(segment
		(start 32.5755 -381.508)
		(end 32.5755 -380.9365)
		(width 0.3556)
		(layer "F.Cu")
		(net "P3V3")
	)
	(segment
		(start 16.265398 -258.230116)
		(end 16.26616 -258.229354)
		(width 0.508)
		(layer "F.Cu")
		(net "P3V3")
	)
	(segment
		(start 25.4 -30.226)
		(end 24.384 -30.226)
		(width 0.508)
		(layer "F.Cu")
		(net "P3V3")
	)
	(segment
		(start 45.078904 -352.263456)
		(end 44.68749 -351.872042)
		(width 0.508)
		(layer "F.Cu")
		(net "P3V3")
	)
	(segment
		(start 224.663 -452.20509)
		(end 224.480374 -452.387716)
		(width 0.508)
		(layer "F.Cu")
		(net "P3V3")
	)
	(segment
		(start 49.7205 -41.275)
		(end 50.4952 -41.275)
		(width 0.508)
		(layer "F.Cu")
		(net "P3V3")
	)
	(segment
		(start 44.677076 -345.375992)
		(end 44.677076 -344.563192)
		(width 0.508)
		(layer "F.Cu")
		(net "P3V3")
	)
	(segment
		(start 30.99435 -146.37385)
		(end 30.99435 -145.57375)
		(width 0.508)
		(layer "F.Cu")
		(net "P3V3")
	)
	(segment
		(start 90.4875 -87.418926)
		(end 90.489278 -87.420704)
		(width 0.508)
		(layer "F.Cu")
		(net "P3V3")
	)
	(segment
		(start 22.259798 -61.433202)
		(end 21.971 -61.722)
		(width 0.4064)
		(layer "F.Cu")
		(net "P3V3")
	)
	(segment
		(start 19.4945 -370.4844)
		(end 19.4945 -371.541548)
		(width 0.508)
		(layer "F.Cu")
		(net "P3V3")
	)
	(segment
		(start 72.009 -455.1045)
		(end 72.009 -456.311)
		(width 0.508)
		(layer "F.Cu")
		(net "P3V3")
	)
	(segment
		(start 234.5055 -246.634)
		(end 235.325158 -246.634)
		(width 0.508)
		(layer "F.Cu")
		(net "P3V3")
	)
	(segment
		(start 83.6295 -152.654)
		(end 84.455 -152.654)
		(width 0.508)
		(layer "F.Cu")
		(net "P3V3")
	)
	(segment
		(start 229.67696 -447.56324)
		(end 229.67696 -448.50304)
		(width 0.508)
		(layer "F.Cu")
		(net "P3V3")
	)
	(segment
		(start 71.1835 -437.388)
		(end 72.009 -437.388)
		(width 0.508)
		(layer "F.Cu")
		(net "P3V3")
	)
	(segment
		(start 70.2945 -145.542)
		(end 69.469 -145.542)
		(width 0.508)
		(layer "F.Cu")
		(net "P3V3")
	)
	(segment
		(start 32.5755 -380.9365)
		(end 33.054798 -380.457202)
		(width 0.3556)
		(layer "F.Cu")
		(net "P3V3")
	)
	(segment
		(start 39.116 -206.5528)
		(end 39.116 -206.1845)
		(width 0.508)
		(layer "F.Cu")
		(net "P3V3")
	)
	(segment
		(start 39.116 -309.1815)
		(end 39.840916 -309.1815)
		(width 0.508)
		(layer "F.Cu")
		(net "P3V3")
	)
	(segment
		(start 43.387772 -451.352412)
		(end 43.20032 -451.352412)
		(width 0.508)
		(layer "F.Cu")
		(net "P3V3")
	)
	(segment
		(start 74.422 -445.008)
		(end 75.438 -445.008)
		(width 0.508)
		(layer "F.Cu")
		(net "P3V3")
	)
	(segment
		(start 214.7824 -394.0175)
		(end 214.7824 -394.7922)
		(width 0.508)
		(layer "F.Cu")
		(net "P3V3")
	)
	(segment
		(start 24.384 -133.096)
		(end 24.638 -133.35)
		(width 0.508)
		(layer "F.Cu")
		(net "P3V3")
	)
	(segment
		(start 42.35323 -142.345664)
		(end 42.48023 -142.345664)
		(width 0.508)
		(layer "F.Cu")
		(net "P3V3")
	)
	(segment
		(start 89.3445 -225.012758)
		(end 89.355168 -225.00209)
		(width 0.508)
		(layer "F.Cu")
		(net "P3V3")
	)
	(segment
		(start 49.7205 -43.159934)
		(end 49.416208 -43.464226)
		(width 0.508)
		(layer "F.Cu")
		(net "P3V3")
	)
	(segment
		(start 96.3295 -319.3796)
		(end 96.33458 -319.37452)
		(width 0.508)
		(layer "F.Cu")
		(net "P3V3")
	)
	(segment
		(start 207.772 -452.628)
		(end 207.01 -453.39)
		(width 0.508)
		(layer "F.Cu")
		(net "P3V3")
	)
	(segment
		(start 58.293 -241.230658)
		(end 58.293 -240.4364)
		(width 0.508)
		(layer "F.Cu")
		(net "P3V3")
	)
	(segment
		(start 243.586 -413.3596)
		(end 243.586 -414.274)
		(width 0.508)
		(layer "F.Cu")
		(net "P3V3")
	)
	(segment
		(start 212.55482 -460.41818)
		(end 212.0265 -460.9465)
		(width 0.3556)
		(layer "F.Cu")
		(net "P3V3")
	)
	(segment
		(start 56.007 -17.145)
		(end 56.007 -11.3284)
		(width 1.016)
		(layer "F.Cu")
		(net "P3V3")
	)
	(segment
		(start 227.001832 -38.602412)
		(end 227.38715 -38.98773)
		(width 0.508)
		(layer "F.Cu")
		(net "P3V3")
	)
	(segment
		(start 43.3197 -412.1785)
		(end 40.5003 -412.1785)
		(width 1.016)
		(layer "F.Cu")
		(net "P3V3")
	)
	(segment
		(start 88.4555 -86.614)
		(end 88.4555 -87.403432)
		(width 0.508)
		(layer "F.Cu")
		(net "P3V3")
	)
	(segment
		(start 209.423 -44.2595)
		(end 209.423 -43.434)
		(width 0.508)
		(layer "F.Cu")
		(net "P3V3")
	)
	(segment
		(start 71.0311 -366.9665)
		(end 71.0311 -367.792)
		(width 0.508)
		(layer "F.Cu")
		(net "P3V3")
	)
	(segment
		(start 97.4725 -290.195)
		(end 97.4725 -290.994592)
		(width 0.508)
		(layer "F.Cu")
		(net "P3V3")
	)
	(segment
		(start 20.828 -61.909452)
		(end 20.828 -60.88761)
		(width 0.508)
		(layer "F.Cu")
		(net "P3V3")
	)
	(segment
		(start 228.283516 -140.38961)
		(end 227.468938 -140.38961)
		(width 0.508)
		(layer "F.Cu")
		(net "P3V3")
	)
	(segment
		(start 21.783548 -61.909452)
		(end 20.828 -61.909452)
		(width 0.508)
		(layer "F.Cu")
		(net "P3V3")
	)
	(segment
		(start 27.34056 -478.537778)
		(end 28.546552 -478.537778)
		(width 1.016)
		(layer "F.Cu")
		(net "P3V3")
	)
	(segment
		(start 23.9649 -467.3346)
		(end 23.656544 -467.026244)
		(width 0.508)
		(layer "F.Cu")
		(net "P3V3")
	)
	(segment
		(start 229.67696 -345.502992)
		(end 229.67696 -344.563192)
		(width 0.508)
		(layer "F.Cu")
		(net "P3V3")
	)
	(segment
		(start 227.221034 -346.5576)
		(end 227.231956 -346.5576)
		(width 0.508)
		(layer "F.Cu")
		(net "P3V3")
	)
	(segment
		(start 29.9466 -291.0967)
		(end 29.9466 -291.8968)
		(width 0.508)
		(layer "F.Cu")
		(net "P3V3")
	)
	(segment
		(start 28.45435 -390.04875)
		(end 27.6987 -390.8044)
		(width 0.508)
		(layer "F.Cu")
		(net "P3V3")
	)
	(segment
		(start 41.627298 -249.077988)
		(end 41.85412 -248.851166)
		(width 0.508)
		(layer "F.Cu")
		(net "P3V3")
	)
	(segment
		(start 221.615 -164.592)
		(end 220.4466 -164.592)
		(width 0.762)
		(layer "F.Cu")
		(net "P3V3")
	)
	(segment
		(start 69.977 -456.311)
		(end 69.977 -455.1045)
		(width 0.508)
		(layer "F.Cu")
		(net "P3V3")
	)
	(segment
		(start 89.3445 -225.806)
		(end 89.3445 -225.012758)
		(width 0.508)
		(layer "F.Cu")
		(net "P3V3")
	)
	(segment
		(start 70.2945 -143.51)
		(end 69.469 -143.51)
		(width 0.508)
		(layer "F.Cu")
		(net "P3V3")
	)
	(segment
		(start 234.5055 -41.771062)
		(end 235.292138 -41.771062)
		(width 0.508)
		(layer "F.Cu")
		(net "P3V3")
	)
	(segment
		(start 25.4 -30.226)
		(end 25.736804 -30.226)
		(width 0.762)
		(layer "F.Cu")
		(net "P3V3")
	)
	(segment
		(start 82.1055 -356.9716)
		(end 82.931 -356.9716)
		(width 0.508)
		(layer "F.Cu")
		(net "P3V3")
	)
	(segment
		(start 234.5055 -144.77111)
		(end 234.5055 -145.484596)
		(width 0.508)
		(layer "F.Cu")
		(net "P3V3")
	)
	(segment
		(start 24.638 -133.35)
		(end 25.4 -133.35)
		(width 0.508)
		(layer "F.Cu")
		(net "P3V3")
	)
	(segment
		(start 227.372926 -243.41582)
		(end 227.33762 -243.41582)
		(width 0.508)
		(layer "F.Cu")
		(net "P3V3")
	)
	(segment
		(start 91.6305 -30.607)
		(end 91.6305 -31.496)
		(width 0.508)
		(layer "F.Cu")
		(net "P3V3")
	)
	(segment
		(start 32.2326 -421.0685)
		(end 32.2326 -420.2938)
		(width 0.508)
		(layer "F.Cu")
		(net "P3V3")
	)
	(segment
		(start 221.615 -370.586)
		(end 222.631 -370.586)
		(width 0.508)
		(layer "F.Cu")
		(net "P3V3")
	)
	(segment
		(start 70.2945 -149.606)
		(end 69.469 -149.606)
		(width 0.508)
		(layer "F.Cu")
		(net "P3V3")
	)
	(segment
		(start 37.211 -151.003)
		(end 40.5384 -147.6756)
		(width 1.016)
		(layer "F.Cu")
		(net "P3V3")
	)
	(segment
		(start 21.017992 -370.433092)
		(end 21.017992 -369.607592)
		(width 0.508)
		(layer "F.Cu")
		(net "P3V3")
	)
	(segment
		(start 21.971 -61.722)
		(end 21.783548 -61.909452)
		(width 0.508)
		(layer "F.Cu")
		(net "P3V3")
	)
	(segment
		(start 16.27886 -360.14914)
		(end 15.92961 -360.49839)
		(width 0.508)
		(layer "F.Cu")
		(net "P3V3")
	)
	(segment
		(start 34.57575 -42.11955)
		(end 34.57575 -41.26865)
		(width 0.508)
		(layer "F.Cu")
		(net "P3V3")
	)
	(segment
		(start 78.105 -353.6315)
		(end 78.105 -352.806)
		(width 0.508)
		(layer "F.Cu")
		(net "P3V3")
	)
	(segment
		(start 194.243706 -497.778278)
		(end 194.243706 -496.063778)
		(width 0.508)
		(layer "F.Cu")
		(net "P3V3")
	)
	(segment
		(start 81.3054 -148.1836)
		(end 81.3054 -149.1488)
		(width 0.508)
		(layer "F.Cu")
		(net "P3V3")
	)
	(segment
		(start 29.707332 -26.255472)
		(end 46.853094 -26.255472)
		(width 1.016)
		(layer "F.Cu")
		(net "P3V3")
	)
	(segment
		(start 103.2002 -216.027)
		(end 104.2797 -216.027)
		(width 0.508)
		(layer "F.Cu")
		(net "P3V3")
	)
	(segment
		(start 228.7905 -243.389658)
		(end 228.256592 -243.389658)
		(width 0.508)
		(layer "F.Cu")
		(net "P3V3")
	)
	(segment
		(start 96.3295 -225.806)
		(end 96.3295 -225.022918)
		(width 0.508)
		(layer "F.Cu")
		(net "P3V3")
	)
	(segment
		(start 226.747832 -141.00556)
		(end 226.747832 -141.60246)
		(width 0.508)
		(layer "F.Cu")
		(net "P3V3")
	)
	(segment
		(start 44.677076 -36.630102)
		(end 44.677076 -35.918902)
		(width 0.508)
		(layer "F.Cu")
		(net "P3V3")
	)
	(segment
		(start 49.7205 -42.418)
		(end 49.7205 -43.159934)
		(width 0.508)
		(layer "F.Cu")
		(net "P3V3")
	)
	(segment
		(start 226.114102 -349.617284)
		(end 225.084894 -349.617284)
		(width 0.508)
		(layer "F.Cu")
		(net "P3V3")
	)
	(segment
		(start 224.918524 -247.359678)
		(end 226.036886 -247.359678)
		(width 0.508)
		(layer "F.Cu")
		(net "P3V3")
	)
	(segment
		(start 226.751896 -347.797628)
		(end 226.751896 -347.03766)
		(width 0.508)
		(layer "F.Cu")
		(net "P3V3")
	)
	(segment
		(start 87.3125 -446.786)
		(end 87.3125 -445.897)
		(width 0.508)
		(layer "F.Cu")
		(net "P3V3")
	)
	(segment
		(start 32.2072 -214.7697)
		(end 32.2072 -213.995)
		(width 0.508)
		(layer "F.Cu")
		(net "P3V3")
	)
	(segment
		(start 38.5445 -144.8435)
		(end 39.497 -145.796)
		(width 0.508)
		(layer "F.Cu")
		(net "P3V3")
	)
	(segment
		(start 71.33336 -445.1096)
		(end 73.0504 -445.1096)
		(width 0.3556)
		(layer "F.Cu")
		(net "P3V3")
	)
	(segment
		(start 226.747832 -141.60246)
		(end 226.946714 -141.801342)
		(width 0.508)
		(layer "F.Cu")
		(net "P3V3")
	)
	(segment
		(start 205.486 -197.358)
		(end 203.962 -198.882)
		(width 1.016)
		(layer "F.Cu")
		(net "P3V3")
	)
	(segment
		(start 32.678116 -249.871484)
		(end 38.095428 -249.871484)
		(width 1.016)
		(layer "F.Cu")
		(net "P3V3")
	)
	(segment
		(start 229.67696 -139.50315)
		(end 228.7905 -140.38961)
		(width 0.508)
		(layer "F.Cu")
		(net "P3V3")
	)
	(segment
		(start 226.505262 -450.850762)
		(end 226.9871 -451.3326)
		(width 0.508)
		(layer "F.Cu")
		(net "P3V3")
	)
	(segment
		(start 20.828 -164.9095)
		(end 21.7805 -164.9095)
		(width 0.508)
		(layer "F.Cu")
		(net "P3V3")
	)
	(segment
		(start 40.5003 -412.1785)
		(end 39.116 -412.1785)
		(width 0.508)
		(layer "F.Cu")
		(net "P3V3")
	)
	(segment
		(start 212.0265 -50.9905)
		(end 212.0265 -51.562)
		(width 0.3556)
		(layer "F.Cu")
		(net "P3V3")
	)
	(segment
		(start 78.0288 -310.896)
		(end 76.835 -310.896)
		(width 1.016)
		(layer "F.Cu")
		(net "P3V3")
	)
	(segment
		(start 216.6366 -137.3886)
		(end 215.265 -136.017)
		(width 1.016)
		(layer "F.Cu")
		(net "P3V3")
	)
	(segment
		(start 226.747832 -244.005608)
		(end 226.747832 -244.743986)
		(width 0.508)
		(layer "F.Cu")
		(net "P3V3")
	)
	(segment
		(start 17.123156 -160.454848)
		(end 19.4056 -160.454848)
		(width 0.508)
		(layer "F.Cu")
		(net "P3V3")
	)
	(segment
		(start 36.576 -61.341)
		(end 37.592 -61.341)
		(width 0.508)
		(layer "F.Cu")
		(net "P3V3")
	)
	(segment
		(start 54.483 -401.0152)
		(end 43.3197 -412.1785)
		(width 1.016)
		(layer "F.Cu")
		(net "P3V3")
	)
	(segment
		(start 108.966 -208.4705)
		(end 108.181394 -208.4705)
		(width 0.508)
		(layer "F.Cu")
		(net "P3V3")
	)
	(segment
		(start 32.4358 -45.974)
		(end 25.5016 -52.9082)
		(width 1.016)
		(layer "F.Cu")
		(net "P3V3")
	)
	(segment
		(start 206.0575 -196.7865)
		(end 205.486 -197.358)
		(width 0.508)
		(layer "F.Cu")
		(net "P3V3")
	)
	(segment
		(start 21.036534 -470.8271)
		(end 21.75256 -470.8271)
		(width 0.4064)
		(layer "F.Cu")
		(net "P3V3")
	)
	(segment
		(start 20.354798 -470.984072)
		(end 20.354798 -470.790778)
		(width 0.508)
		(layer "F.Cu")
		(net "P3V3")
	)
	(segment
		(start 42.39006 -268.189964)
		(end 43.96613 -268.189964)
		(width 0.508)
		(layer "F.Cu")
		(net "P3V3")
	)
	(segment
		(start 26.922476 -236.22)
		(end 25.4 -236.22)
		(width 0.508)
		(layer "F.Cu")
		(net "P3V3")
	)
	(segment
		(start 19.7485 -267.433044)
		(end 19.7485 -268.4145)
		(width 0.508)
		(layer "F.Cu")
		(net "P3V3")
	)
	(segment
		(start 89.3445 -446.786)
		(end 89.3445 -445.897)
		(width 0.508)
		(layer "F.Cu")
		(net "P3V3")
	)
	(segment
		(start 213.359746 -51.562254)
		(end 212.026754 -51.562254)
		(width 0.508)
		(layer "F.Cu")
		(net "P3V3")
	)
	(segment
		(start 23.172674 -370.433092)
		(end 21.843492 -370.433092)
		(width 0.381)
		(layer "F.Cu")
		(net "P3V3")
	)
	(segment
		(start 19.61007 -443.810136)
		(end 18.034 -443.810136)
		(width 0.508)
		(layer "F.Cu")
		(net "P3V3")
	)
	(segment
		(start 42.39006 -474.19006)
		(end 43.96613 -474.19006)
		(width 0.508)
		(layer "F.Cu")
		(net "P3V3")
	)
	(segment
		(start 22.86 -299.7835)
		(end 22.86 -299.4152)
		(width 0.508)
		(layer "F.Cu")
		(net "P3V3")
	)
	(segment
		(start 46.453044 -42.877994)
		(end 43.460924 -42.877994)
		(width 0.508)
		(layer "F.Cu")
		(net "P3V3")
	)
	(segment
		(start 36.576 -164.592)
		(end 37.592 -164.592)
		(width 0.508)
		(layer "F.Cu")
		(net "P3V3")
	)
	(segment
		(start 221.361 -473.456)
		(end 220.037406 -473.456)
		(width 0.508)
		(layer "F.Cu")
		(net "P3V3")
	)
	(segment
		(start 214.5284 -290.9951)
		(end 214.5284 -291.7698)
		(width 0.508)
		(layer "F.Cu")
		(net "P3V3")
	)
	(segment
		(start 21.971 -164.719)
		(end 22.25675 -164.43325)
		(width 0.4064)
		(layer "F.Cu")
		(net "P3V3")
	)
	(segment
		(start 25.4 -444.373)
		(end 25.9842 -444.373)
		(width 0.508)
		(layer "F.Cu")
		(net "P3V3")
	)
	(segment
		(start 18.68424 -467.295484)
		(end 18.319242 -467.660482)
		(width 0.508)
		(layer "F.Cu")
		(net "P3V3")
	)
	(segment
		(start 38.5445 -144.653)
		(end 38.5445 -144.8435)
		(width 0.508)
		(layer "F.Cu")
		(net "P3V3")
	)
	(segment
		(start 215.3539 -494.0808)
		(end 214.5538 -494.0808)
		(width 0.508)
		(layer "F.Cu")
		(net "P3V3")
	)
	(segment
		(start 47.039276 -43.464226)
		(end 46.453044 -42.877994)
		(width 0.508)
		(layer "F.Cu")
		(net "P3V3")
	)
	(segment
		(start 16.26616 -258.230878)
		(end 16.265398 -258.230116)
		(width 0.508)
		(layer "F.Cu")
		(net "P3V3")
	)
	(segment
		(start 227.231956 -346.5576)
		(end 227.400104 -346.389452)
		(width 0.508)
		(layer "F.Cu")
		(net "P3V3")
	)
	(segment
		(start 70.2945 -151.638)
		(end 69.469 -151.638)
		(width 0.508)
		(layer "F.Cu")
		(net "P3V3")
	)
	(segment
		(start 42.39006 -371.190012)
		(end 43.96613 -371.190012)
		(width 0.508)
		(layer "F.Cu")
		(net "P3V3")
	)
	(segment
		(start 71.628 -456.692)
		(end 70.358 -456.692)
		(width 0.508)
		(layer "F.Cu")
		(net "P3V3")
	)
	(segment
		(start 27.6987 -390.8044)
		(end 27.6987 -391.3124)
		(width 0.508)
		(layer "F.Cu")
		(net "P3V3")
	)
	(segment
		(start 214.376 -50.546)
		(end 213.359746 -51.562254)
		(width 0.508)
		(layer "F.Cu")
		(net "P3V3")
	)
	(segment
		(start 224.663 -451.4215)
		(end 224.663 -452.20509)
		(width 0.508)
		(layer "F.Cu")
		(net "P3V3")
	)
	(segment
		(start 77.216 -154.6225)
		(end 77.216 -155.448)
		(width 0.508)
		(layer "F.Cu")
		(net "P3V3")
	)
	(segment
		(start 48.3235 -351.028)
		(end 49.1236 -351.028)
		(width 0.508)
		(layer "F.Cu")
		(net "P3V3")
	)
	(segment
		(start 217.1446 -341.19693)
		(end 217.1446 -345.8718)
		(width 1.016)
		(layer "F.Cu")
		(net "P3V3")
	)
	(segment
		(start 74.6125 -455.1045)
		(end 74.041 -455.1045)
		(width 0.508)
		(layer "F.Cu")
		(net "P3V3")
	)
	(segment
		(start 88.4555 -87.403432)
		(end 88.457024 -87.404956)
		(width 0.508)
		(layer "F.Cu")
		(net "P3V3")
	)
	(segment
		(start 16.047466 -52.938934)
		(end 16.231362 -53.12283)
		(width 0.508)
		(layer "F.Cu")
		(net "P3V3")
	)
	(segment
		(start 20.354798 -470.984072)
		(end 20.879562 -470.984072)
		(width 0.4064)
		(layer "F.Cu")
		(net "P3V3")
	)
	(segment
		(start 26.875232 -29.087572)
		(end 29.707332 -26.255472)
		(width 1.016)
		(layer "F.Cu")
		(net "P3V3")
	)
	(segment
		(start 31.8262 -112.0267)
		(end 31.8262 -111.252)
		(width 0.508)
		(layer "F.Cu")
		(net "P3V3")
	)
	(segment
		(start 229.67696 -241.563398)
		(end 229.67696 -242.503198)
		(width 0.508)
		(layer "F.Cu")
		(net "P3V3")
	)
	(segment
		(start 97.4725 -86.614)
		(end 97.4725 -87.503)
		(width 0.508)
		(layer "F.Cu")
		(net "P3V3")
	)
	(segment
		(start 75.5904 -355.981)
		(end 75.5904 -357.3526)
		(width 0.3048)
		(layer "F.Cu")
		(net "P3V3")
	)
	(segment
		(start 98.3615 -116.586)
		(end 98.3615 -115.794282)
		(width 0.508)
		(layer "F.Cu")
		(net "P3V3")
	)
	(segment
		(start 43.946826 -35.817302)
		(end 43.028616 -35.817302)
		(width 0.381)
		(layer "F.Cu")
		(net "P3V3")
	)
	(segment
		(start 31.5341 -146.9136)
		(end 30.99435 -146.37385)
		(width 0.508)
		(layer "F.Cu")
		(net "P3V3")
	)
	(segment
		(start 25.564338 -480.314)
		(end 27.34056 -478.537778)
		(width 1.016)
		(layer "F.Cu")
		(net "P3V3")
	)
	(segment
		(start 19.61007 -237.81004)
		(end 18.034 -237.81004)
		(width 0.508)
		(layer "F.Cu")
		(net "P3V3")
	)
	(segment
		(start 45.140118 -451.653148)
		(end 43.688508 -451.653148)
		(width 0.508)
		(layer "F.Cu")
		(net "P3V3")
	)
	(segment
		(start 82.1055 -360.045)
		(end 82.931 -360.045)
		(width 0.508)
		(layer "F.Cu")
		(net "P3V3")
	)
	(segment
		(start 209.804 -446.151)
		(end 215.4555 -446.151)
		(width 1.016)
		(layer "F.Cu")
		(net "P3V3")
	)
	(segment
		(start 217.836242 -240.264442)
		(end 215.5698 -237.998)
		(width 1.016)
		(layer "F.Cu")
		(net "P3V3")
	)
	(segment
		(start 42.494454 -346.262452)
		(end 41.917366 -346.262452)
		(width 0.508)
		(layer "F.Cu")
		(net "P3V3")
	)
	(segment
		(start 87.3125 -225.806)
		(end 87.3125 -225.022918)
		(width 0.508)
		(layer "F.Cu")
		(net "P3V3")
	)
	(segment
		(start 234.5055 -452.628)
		(end 235.3056 -452.628)
		(width 0.508)
		(layer "F.Cu")
		(net "P3V3")
	)
	(segment
		(start 207.391 -299.7835)
		(end 206.3115 -299.7835)
		(width 0.508)
		(layer "F.Cu")
		(net "P3V3")
	)
	(segment
		(start 20.354798 -470.790778)
		(end 19.5834 -470.01938)
		(width 0.508)
		(layer "F.Cu")
		(net "P3V3")
	)
	(segment
		(start 40.513 -45.974)
		(end 37.084 -42.545)
		(width 1.016)
		(layer "F.Cu")
		(net "P3V3")
	)
	(segment
		(start 28.79598 -490.833156)
		(end 28.79598 -492.33328)
		(width 0.508)
		(layer "F.Cu")
		(net "P3V3")
	)
	(segment
		(start 68.2625 -437.388)
		(end 67.437 -437.388)
		(width 0.508)
		(layer "F.Cu")
		(net "P3V3")
	)
	(segment
		(start 98.3615 -319.380108)
		(end 98.372168 -319.36944)
		(width 0.508)
		(layer "F.Cu")
		(net "P3V3")
	)
	(segment
		(start 231.267 -439.7375)
		(end 231.267 -440.5884)
		(width 0.508)
		(layer "F.Cu")
		(net "P3V3")
	)
	(segment
		(start 87.3125 -319.377314)
		(end 87.31504 -319.374774)
		(width 0.508)
		(layer "F.Cu")
		(net "P3V3")
	)
	(segment
		(start 63.0809 -449.5546)
		(end 63.9826 -449.5546)
		(width 0.508)
		(layer "F.Cu")
		(net "P3V3")
	)
	(segment
		(start 14.224 -480.314)
		(end 14.224 -478.5995)
		(width 0.508)
		(layer "F.Cu")
		(net "P3V3")
	)
	(segment
		(start 15.204186 -52.938934)
		(end 16.047466 -52.938934)
		(width 0.508)
		(layer "F.Cu")
		(net "P3V3")
	)
	(segment
		(start 91.6305 -29.718)
		(end 91.6305 -28.5115)
		(width 0.3048)
		(layer "F.Cu")
		(net "P3V3")
	)
	(segment
		(start 226.747832 -244.743986)
		(end 227.005896 -245.00205)
		(width 0.508)
		(layer "F.Cu")
		(net "P3V3")
	)
	(segment
		(start 27.432 -132.715)
		(end 38.608 -121.539)
		(width 1.016)
		(layer "F.Cu")
		(net "P3V3")
	)
	(segment
		(start 166.878 -338.201)
		(end 214.14867 -338.201)
		(width 1.016)
		(layer "F.Cu")
		(net "P3V3")
	)
	(segment
		(start 32.258 -151.003)
		(end 37.211 -151.003)
		(width 1.016)
		(layer "F.Cu")
		(net "P3V3")
	)
	(segment
		(start 221.615 -63.754)
		(end 222.631 -63.754)
		(width 0.508)
		(layer "F.Cu")
		(net "P3V3")
	)
	(segment
		(start 52.6669 -245.231158)
		(end 52.6669 -246.031258)
		(width 0.508)
		(layer "F.Cu")
		(net "P3V3")
	)
	(segment
		(start 77.1144 -366.9665)
		(end 77.1144 -367.792)
		(width 0.508)
		(layer "F.Cu")
		(net "P3V3")
	)
	(segment
		(start 32.004 -374.2055)
		(end 32.004 -372.364)
		(width 0.508)
		(layer "F.Cu")
		(net "P3V3")
	)
	(segment
		(start 25.736804 -30.226)
		(end 26.875232 -29.087572)
		(width 0.762)
		(layer "F.Cu")
		(net "P3V3")
	)
	(segment
		(start 75.8063 -142.8115)
		(end 75.8063 -141.986)
		(width 0.508)
		(layer "F.Cu")
		(net "P3V3")
	)
	(segment
		(start 88.4555 -416.814)
		(end 88.4555 -417.60775)
		(width 0.508)
		(layer "F.Cu")
		(net "P3V3")
	)
	(segment
		(start 72.009 -456.311)
		(end 71.628 -456.692)
		(width 0.508)
		(layer "F.Cu")
		(net "P3V3")
	)
	(segment
		(start 207.391 -44.2595)
		(end 207.391 -43.434)
		(width 0.508)
		(layer "F.Cu")
		(net "P3V3")
	)
	(segment
		(start 18.31467 -463.126074)
		(end 19.598386 -461.842358)
		(width 0.508)
		(layer "F.Cu")
		(net "P3V3")
	)
	(segment
		(start 203.835 -300.609)
		(end 168.148 -300.609)
		(width 1.016)
		(layer "F.Cu")
		(net "P3V3")
	)
	(segment
		(start 214.376 -473.456)
		(end 208.026 -467.106)
		(width 1.016)
		(layer "F.Cu")
		(net "P3V3")
	)
	(segment
		(start 234.5055 -40.64)
		(end 235.292138 -40.64)
		(width 0.508)
		(layer "F.Cu")
		(net "P3V3")
	)
	(segment
		(start 80.264 -154.6225)
		(end 80.264 -155.448)
		(width 0.508)
		(layer "F.Cu")
		(net "P3V3")
	)
	(segment
		(start 20.16125 -399.08734)
		(end 20.43811 -398.81048)
		(width 0.508)
		(layer "F.Cu")
		(net "P3V3")
	)
	(segment
		(start 43.028616 -344.563192)
		(end 44.677076 -344.563192)
		(width 0.381)
		(layer "F.Cu")
		(net "P3V3")
	)
	(segment
		(start 212.55482 -50.46218)
		(end 212.0265 -50.9905)
		(width 0.3556)
		(layer "F.Cu")
		(net "P3V3")
	)
	(segment
		(start 74.168 -154.6225)
		(end 74.168 -155.448)
		(width 0.508)
		(layer "F.Cu")
		(net "P3V3")
	)
	(segment
		(start 234.086908 -145.903188)
		(end 228.454204 -145.903188)
		(width 0.508)
		(layer "F.Cu")
		(net "P3V3")
	)
	(segment
		(start 82.1055 -362.1278)
		(end 82.931 -362.1278)
		(width 0.508)
		(layer "F.Cu")
		(net "P3V3")
	)
	(segment
		(start 41.917366 -346.262452)
		(end 41.672764 -346.507054)
		(width 0.508)
		(layer "F.Cu")
		(net "P3V3")
	)
	(segment
		(start 70.2945 -146.558)
		(end 69.469 -146.558)
		(width 0.508)
		(layer "F.Cu")
		(net "P3V3")
	)
	(segment
		(start 96.3295 -225.022918)
		(end 96.33458 -225.017838)
		(width 0.508)
		(layer "F.Cu")
		(net "P3V3")
	)
	(segment
		(start 87.3125 -320.167)
		(end 87.3125 -319.377314)
		(width 0.508)
		(layer "F.Cu")
		(net "P3V3")
	)
	(segment
		(start 229.017576 -37.389562)
		(end 228.510592 -37.389562)
		(width 0.508)
		(layer "F.Cu")
		(net "P3V3")
	)
	(segment
		(start 25.6032 -256.9464)
		(end 32.678116 -249.871484)
		(width 1.016)
		(layer "F.Cu")
		(net "P3V3")
	)
	(segment
		(start 21.7805 -164.9095)
		(end 21.971 -164.719)
		(width 0.508)
		(layer "F.Cu")
		(net "P3V3")
	)
	(segment
		(start 78.232 -154.6225)
		(end 78.232 -155.448)
		(width 0.508)
		(layer "F.Cu")
		(net "P3V3")
	)
	(segment
		(start 42.494454 -346.262452)
		(end 43.282108 -346.262452)
		(width 0.508)
		(layer "F.Cu")
		(net "P3V3")
	)
	(segment
		(start 227.001832 -38.005512)
		(end 227.001832 -38.602412)
		(width 0.508)
		(layer "F.Cu")
		(net "P3V3")
	)
	(segment
		(start 41.654476 -38.426644)
		(end 41.654476 -37.967158)
		(width 0.508)
		(layer "F.Cu")
		(net "P3V3")
	)
	(segment
		(start 28.546552 -478.537778)
		(end 28.546552 -490.583728)
		(width 1.016)
		(layer "F.Cu")
		(net "P3V3")
	)
	(segment
		(start 217.86469 -140.58011)
		(end 216.6366 -139.35202)
		(width 1.016)
		(layer "F.Cu")
		(net "P3V3")
	)
	(segment
		(start 228.281992 -346.389452)
		(end 228.7905 -346.389452)
		(width 0.508)
		(layer "F.Cu")
		(net "P3V3")
	)
	(segment
		(start 43.790616 -346.262452)
		(end 44.677076 -345.375992)
		(width 0.508)
		(layer "F.Cu")
		(net "P3V3")
	)
	(segment
		(start 46.228 -242.8875)
		(end 45.212 -242.8875)
		(width 0.508)
		(layer "F.Cu")
		(net "P3V3")
	)
	(segment
		(start 101.092 -104.2035)
		(end 101.981 -104.2035)
		(width 0.508)
		(layer "F.Cu")
		(net "P3V3")
	)
	(segment
		(start 20.541488 -161.665158)
		(end 20.358862 -161.482532)
		(width 0.508)
		(layer "F.Cu")
		(net "P3V3")
	)
	(segment
		(start 38.241478 -35.4965)
		(end 38.241478 -36.284916)
		(width 0.508)
		(layer "F.Cu")
		(net "P3V3")
	)
	(segment
		(start 209.677 -453.39)
		(end 208.915 -452.628)
		(width 0.508)
		(layer "F.Cu")
		(net "P3V3")
	)
	(segment
		(start 226.90709 -348.323154)
		(end 226.90709 -347.952822)
		(width 0.508)
		(layer "F.Cu")
		(net "P3V3")
	)
	(segment
		(start 79.396336 -148.467064)
		(end 78.1812 -148.467064)
		(width 0.3048)
		(layer "F.Cu")
		(net "P3V3")
	)
	(segment
		(start 73.66 -456.692)
		(end 72.39 -456.692)
		(width 0.508)
		(layer "F.Cu")
		(net "P3V3")
	)
	(segment
		(start 38.5445 -144.653)
		(end 38.5445 -144.145254)
		(width 0.3556)
		(layer "F.Cu")
		(net "P3V3")
	)
	(segment
		(start 224.663 -246.205248)
		(end 224.480374 -246.387874)
		(width 0.508)
		(layer "F.Cu")
		(net "P3V3")
	)
	(segment
		(start 23.656544 -466.695028)
		(end 23.123144 -466.161628)
		(width 0.508)
		(layer "F.Cu")
		(net "P3V3")
	)
	(segment
		(start 227.389944 -268.189964)
		(end 228.966014 -268.189964)
		(width 0.508)
		(layer "F.Cu")
		(net "P3V3")
	)
	(segment
		(start 20.541488 -367.665)
		(end 20.358862 -367.482374)
		(width 0.508)
		(layer "F.Cu")
		(net "P3V3")
	)
	(segment
		(start 35.0012 -42.545)
		(end 34.57575 -42.11955)
		(width 0.508)
		(layer "F.Cu")
		(net "P3V3")
	)
	(segment
		(start 70.2945 -361.569)
		(end 69.469 -361.569)
		(width 0.508)
		(layer "F.Cu")
		(net "P3V3")
	)
	(segment
		(start 43.419268 -454.835768)
		(end 45.73905 -454.835768)
		(width 0.508)
		(layer "F.Cu")
		(net "P3V3")
	)
	(segment
		(start 224.520252 -347.9038)
		(end 224.520252 -348.68739)
		(width 0.508)
		(layer "F.Cu")
		(net "P3V3")
	)
	(segment
		(start 20.16125 -401.35175)
		(end 20.16125 -399.08734)
		(width 0.508)
		(layer "F.Cu")
		(net "P3V3")
	)
	(segment
		(start 41.021 -207.264)
		(end 46.355 -212.598)
		(width 1.016)
		(layer "F.Cu")
		(net "P3V3")
	)
	(segment
		(start 99.5045 -290.999672)
		(end 99.506532 -291.001704)
		(width 0.508)
		(layer "F.Cu")
		(net "P3V3")
	)
	(segment
		(start 43.282108 -346.262452)
		(end 43.790616 -346.262452)
		(width 0.508)
		(layer "F.Cu")
		(net "P3V3")
	)
	(segment
		(start 227.372926 -243.389658)
		(end 227.372926 -243.41582)
		(width 0.508)
		(layer "F.Cu")
		(net "P3V3")
	)
	(segment
		(start 228.510592 -37.389562)
		(end 227.696014 -37.389562)
		(width 0.508)
		(layer "F.Cu")
		(net "P3V3")
	)
	(segment
		(start 88.4555 -417.60775)
		(end 88.457278 -417.609528)
		(width 0.508)
		(layer "F.Cu")
		(net "P3V3")
	)
	(segment
		(start 227.468938 -449.3895)
		(end 227.141278 -449.3895)
		(width 0.508)
		(layer "F.Cu")
		(net "P3V3")
	)
	(segment
		(start 49.7205 -247.396)
		(end 50.5206 -247.396)
		(width 0.508)
		(layer "F.Cu")
		(net "P3V3")
	)
	(segment
		(start 32.5755 -387.0325)
		(end 30.80004 -388.80796)
		(width 1.016)
		(layer "F.Cu")
		(net "P3V3")
	)
	(segment
		(start 234.499912 -453.776588)
		(end 234.5055 -453.771)
		(width 0.508)
		(layer "F.Cu")
		(net "P3V3")
	)
	(segment
		(start 16.204438 -361.55249)
		(end 15.992348 -361.3404)
		(width 0.508)
		(layer "F.Cu")
		(net "P3V3")
	)
	(segment
		(start 212.0265 -463.11439)
		(end 212.0265 -461.518)
		(width 0.508)
		(layer "F.Cu")
		(net "P3V3")
	)
	(segment
		(start 50.850292 -447.6115)
		(end 49.429924 -449.031868)
		(width 0.508)
		(layer "F.Cu")
		(net "P3V3")
	)
	(segment
		(start 214.376 -48.26)
		(end 214.376 -50.546)
		(width 0.508)
		(layer "F.Cu")
		(net "P3V3")
	)
	(segment
		(start 204.6605 -299.7835)
		(end 203.835 -300.609)
		(width 1.016)
		(layer "F.Cu")
		(net "P3V3")
	)
	(segment
		(start 51.562 -138.7475)
		(end 52.451 -138.7475)
		(width 0.508)
		(layer "F.Cu")
		(net "P3V3")
	)
	(segment
		(start 98.3615 -225.028506)
		(end 98.372168 -225.017838)
		(width 0.508)
		(layer "F.Cu")
		(net "P3V3")
	)
	(segment
		(start 20.749006 -264.271506)
		(end 20.749006 -264.0584)
		(width 0.508)
		(layer "F.Cu")
		(net "P3V3")
	)
	(segment
		(start 226.773232 -347.016324)
		(end 226.773232 -347.005402)
		(width 0.508)
		(layer "F.Cu")
		(net "P3V3")
	)
	(segment
		(start 12.202922 -482.335078)
		(end 14.224 -480.314)
		(width 1.016)
		(layer "F.Cu")
		(net "P3V3")
	)
	(segment
		(start 234.5055 -143.637)
		(end 235.29671 -143.637)
		(width 0.508)
		(layer "F.Cu")
		(net "P3V3")
	)
	(segment
		(start 39.497 -145.796)
		(end 40.32504 -145.796)
		(width 0.508)
		(layer "F.Cu")
		(net "P3V3")
	)
	(segment
		(start 42.39006 -62.189868)
		(end 43.96613 -62.189868)
		(width 0.508)
		(layer "F.Cu")
		(net "P3V3")
	)
	(segment
		(start 28.79598 -492.33328)
		(end 30.2133 -493.7506)
		(width 0.508)
		(layer "F.Cu")
		(net "P3V3")
	)
	(segment
		(start 234.499912 -454.097898)
		(end 234.499912 -453.776588)
		(width 0.508)
		(layer "F.Cu")
		(net "P3V3")
	)
	(segment
		(start 49.429924 -449.43776)
		(end 51.078384 -449.43776)
		(width 0.381)
		(layer "F.Cu")
		(net "P3V3")
	)
	(segment
		(start 12.202922 -494.918238)
		(end 12.202922 -482.335078)
		(width 1.016)
		(layer "F.Cu")
		(net "P3V3")
	)
	(segment
		(start 26.035 -157.226)
		(end 32.258 -151.003)
		(width 1.016)
		(layer "F.Cu")
		(net "P3V3")
	)
	(segment
		(start 218.8845 -243.580158)
		(end 217.836242 -243.580158)
		(width 0.508)
		(layer "F.Cu")
		(net "P3V3")
	)
	(segment
		(start 39.175944 -250.952)
		(end 41.1988 -250.952)
		(width 1.016)
		(layer "F.Cu")
		(net "P3V3")
	)
	(segment
		(start 234.5055 -247.771158)
		(end 235.325158 -247.771158)
		(width 0.508)
		(layer "F.Cu")
		(net "P3V3")
	)
	(segment
		(start 38.608 -121.539)
		(end 43.307 -121.539)
		(width 1.016)
		(layer "F.Cu")
		(net "P3V3")
	)
	(segment
		(start 70.2945 -356.489)
		(end 69.469 -356.489)
		(width 0.508)
		(layer "F.Cu")
		(net "P3V3")
	)
	(segment
		(start 20.879562 -470.984072)
		(end 21.036534 -470.8271)
		(width 0.4064)
		(layer "F.Cu")
		(net "P3V3")
	)
	(segment
		(start 50.850292 -447.6115)
		(end 51.192176 -447.6115)
		(width 0.508)
		(layer "F.Cu")
		(net "P3V3")
	)
	(segment
		(start 39.02075 -103.09225)
		(end 39.02075 -103.73995)
		(width 0.508)
		(layer "F.Cu")
		(net "P3V3")
	)
	(segment
		(start 49.7205 -42.418)
		(end 50.4952 -42.418)
		(width 0.508)
		(layer "F.Cu")
		(net "P3V3")
	)
	(segment
		(start 51.943 -8.1915)
		(end 52.8701 -8.1915)
		(width 0.508)
		(layer "F.Cu")
		(net "P3V3")
	)
	(segment
		(start 234.5055 -350.770952)
		(end 235.2802 -350.770952)
		(width 0.508)
		(layer "F.Cu")
		(net "P3V3")
	)
	(segment
		(start 75.950064 -357.712264)
		(end 75.950064 -359.0798)
		(width 0.3048)
		(layer "F.Cu")
		(net "P3V3")
	)
	(segment
		(start 72.136 -154.6225)
		(end 72.136 -155.448)
		(width 0.508)
		(layer "F.Cu")
		(net "P3V3")
	)
	(segment
		(start 51.562 -136.8425)
		(end 52.451 -136.8425)
		(width 0.508)
		(layer "F.Cu")
		(net "P3V3")
	)
	(segment
		(start 77.0128 -107.3404)
		(end 78.1304 -107.3404)
		(width 1.016)
		(layer "F.Cu")
		(net "P3V3")
	)
	(segment
		(start 76.0984 -366.9665)
		(end 76.0984 -367.792)
		(width 0.508)
		(layer "F.Cu")
		(net "P3V3")
	)
	(segment
		(start 108.966 -435.2925)
		(end 108.077 -435.2925)
		(width 0.508)
		(layer "F.Cu")
		(net "P3V3")
	)
	(segment
		(start 36.406074 -236.22)
		(end 26.922476 -236.22)
		(width 1.016)
		(layer "F.Cu")
		(net "P3V3")
	)
	(segment
		(start 215.4555 -446.151)
		(end 217.852498 -448.547998)
		(width 1.016)
		(layer "F.Cu")
		(net "P3V3")
	)
	(segment
		(start 214.3887 -84.8995)
		(end 214.3887 -85.6742)
		(width 0.508)
		(layer "F.Cu")
		(net "P3V3")
	)
	(segment
		(start 208.915 -452.628)
		(end 207.772 -452.628)
		(width 0.508)
		(layer "F.Cu")
		(net "P3V3")
	)
	(segment
		(start 220.037406 -473.456)
		(end 214.376 -473.456)
		(width 1.016)
		(layer "F.Cu")
		(net "P3V3")
	)
	(segment
		(start 38.5445 -144.145254)
		(end 38.33876 -143.939514)
		(width 0.3556)
		(layer "F.Cu")
		(net "P3V3")
	)
	(segment
		(start 40.765984 -248.925842)
		(end 40.765984 -248.157746)
		(width 0.508)
		(layer "F.Cu")
		(net "P3V3")
	)
	(segment
		(start 23.172674 -267.433044)
		(end 21.970492 -267.433044)
		(width 0.381)
		(layer "F.Cu")
		(net "P3V3")
	)
	(segment
		(start 15.204186 -53.820314)
		(end 15.204186 -52.938934)
		(width 0.508)
		(layer "F.Cu")
		(net "P3V3")
	)
	(segment
		(start 39.243 -137.4775)
		(end 40.0685 -137.4775)
		(width 0.508)
		(layer "F.Cu")
		(net "P3V3")
	)
	(segment
		(start 20.541488 -58.66511)
		(end 20.358862 -58.482484)
		(width 0.508)
		(layer "F.Cu")
		(net "P3V3")
	)
	(segment
		(start 234.5055 -453.771)
		(end 235.3056 -453.771)
		(width 0.508)
		(layer "F.Cu")
		(net "P3V3")
	)
	(segment
		(start 54.483 -370.586)
		(end 54.483 -401.0152)
		(width 1.016)
		(layer "F.Cu")
		(net "P3V3")
	)
	(segment
		(start 49.4665 -453.644)
		(end 50.2666 -453.644)
		(width 0.508)
		(layer "F.Cu")
		(net "P3V3")
	)
	(segment
		(start 42.105072 -37.516562)
		(end 42.493692 -37.516562)
		(width 0.508)
		(layer "F.Cu")
		(net "P3V3")
	)
	(segment
		(start 78.2066 -216.6874)
		(end 77.089 -216.6874)
		(width 1.016)
		(layer "F.Cu")
		(net "P3V3")
	)
	(segment
		(start 41.654476 -37.967158)
		(end 42.105072 -37.516562)
		(width 0.508)
		(layer "F.Cu")
		(net "P3V3")
	)
	(segment
		(start 89.3445 -116.586)
		(end 89.3445 -115.781074)
		(width 0.508)
		(layer "F.Cu")
		(net "P3V3")
	)
	(segment
		(start 45.9105 -140.589)
		(end 46.863 -140.589)
		(width 0.508)
		(layer "F.Cu")
		(net "P3V3")
	)
	(segment
		(start 227.38715 -38.98773)
		(end 227.38715 -39.299896)
		(width 0.508)
		(layer "F.Cu")
		(net "P3V3")
	)
	(segment
		(start 65.416938 -97.79)
		(end 74.422 -97.79)
		(width 1.016)
		(layer "F.Cu")
		(net "P3V3")
	)
	(segment
		(start 194.243706 -491.753906)
		(end 193.4972 -491.0074)
		(width 1.016)
		(layer "F.Cu")
		(net "P3V3")
	)
	(segment
		(start 221.615 -267.589)
		(end 222.631 -267.589)
		(width 0.508)
		(layer "F.Cu")
		(net "P3V3")
	)
	(segment
		(start 227.363782 -140.38961)
		(end 226.747832 -141.00556)
		(width 0.508)
		(layer "F.Cu")
		(net "P3V3")
	)
	(segment
		(start 96.3295 -320.167)
		(end 96.3295 -319.3796)
		(width 0.508)
		(layer "F.Cu")
		(net "P3V3")
	)
	(segment
		(start 99.5045 -86.614)
		(end 99.5045 -87.503)
		(width 0.508)
		(layer "F.Cu")
		(net "P3V3")
	)
	(segment
		(start 72.39 -456.692)
		(end 72.009 -456.311)
		(width 0.508)
		(layer "F.Cu")
		(net "P3V3")
	)
	(segment
		(start 45.9105 -139.844272)
		(end 46.054772 -139.7)
		(width 0.3556)
		(layer "F.Cu")
		(net "P3V3")
	)
	(segment
		(start 224.480374 -246.921528)
		(end 224.918524 -247.359678)
		(width 0.508)
		(layer "F.Cu")
		(net "P3V3")
	)
	(segment
		(start 38.407086 -342.341708)
		(end 37.580824 -342.341708)
		(width 0.508)
		(layer "F.Cu")
		(net "P3V3")
	)
	(segment
		(start 97.8535 -196.62394)
		(end 97.850452 -196.626988)
		(width 0.508)
		(layer "F.Cu")
		(net "P3V3")
	)
	(segment
		(start 227.468938 -243.389658)
		(end 228.256592 -243.389658)
		(width 0.508)
		(layer "F.Cu")
		(net "P3V3")
	)
	(segment
		(start 73.80732 -142.8115)
		(end 73.80732 -141.986)
		(width 0.508)
		(layer "F.Cu")
		(net "P3V3")
	)
	(segment
		(start 228.281992 -346.389452)
		(end 227.494338 -346.389452)
		(width 0.508)
		(layer "F.Cu")
		(net "P3V3")
	)
	(segment
		(start 29.69514 -388.80796)
		(end 28.45435 -390.04875)
		(width 1.016)
		(layer "F.Cu")
		(net "P3V3")
	)
	(segment
		(start 44.048426 -35.918902)
		(end 43.946826 -35.817302)
		(width 0.381)
		(layer "F.Cu")
		(net "P3V3")
	)
	(segment
		(start 80.645 -142.8115)
		(end 80.645 -141.986)
		(width 0.508)
		(layer "F.Cu")
		(net "P3V3")
	)
	(segment
		(start 229.67696 -138.56335)
		(end 229.67696 -139.50315)
		(width 0.508)
		(layer "F.Cu")
		(net "P3V3")
	)
	(segment
		(start 205.486 -441.833)
		(end 209.804 -446.151)
		(width 1.016)
		(layer "F.Cu")
		(net "P3V3")
	)
	(segment
		(start 207.391 -93.7895)
		(end 206.5909 -93.7895)
		(width 0.508)
		(layer "F.Cu")
		(net "P3V3")
	)
	(segment
		(start 84.5185 -146.9644)
		(end 85.344 -146.9644)
		(width 0.508)
		(layer "F.Cu")
		(net "P3V3")
	)
	(segment
		(start 38.095428 -249.871484)
		(end 39.175944 -250.952)
		(width 1.016)
		(layer "F.Cu")
		(net "P3V3")
	)
	(segment
		(start 21.646642 -163.887658)
		(end 20.828 -163.887658)
		(width 0.508)
		(layer "F.Cu")
		(net "P3V3")
	)
	(segment
		(start 87.3125 -225.022918)
		(end 87.31758 -225.017838)
		(width 0.508)
		(layer "F.Cu")
		(net "P3V3")
	)
	(segment
		(start 21.970492 -267.433044)
		(end 21.144992 -267.433044)
		(width 0.508)
		(layer "F.Cu")
		(net "P3V3")
	)
	(segment
		(start 38.33876 -143.939514)
		(end 38.33876 -143.0655)
		(width 0.3556)
		(layer "F.Cu")
		(net "P3V3")
	)
	(segment
		(start 31.9278 -13.8176)
		(end 31.9278 -13.0429)
		(width 0.508)
		(layer "F.Cu")
		(net "P3V3")
	)
	(segment
		(start 18.93062 -466.4202)
		(end 18.68424 -466.66658)
		(width 0.508)
		(layer "F.Cu")
		(net "P3V3")
	)
	(segment
		(start 48.3235 -351.776538)
		(end 47.836582 -352.263456)
		(width 0.508)
		(layer "F.Cu")
		(net "P3V3")
	)
	(segment
		(start 215.5698 -237.998)
		(end 168.91 -237.998)
		(width 1.016)
		(layer "F.Cu")
		(net "P3V3")
	)
	(segment
		(start 95.8215 -195.834)
		(end 95.8215 -196.723)
		(width 0.508)
		(layer "F.Cu")
		(net "P3V3")
	)
	(segment
		(start 89.3445 -115.781074)
		(end 89.339166 -115.77574)
		(width 0.508)
		(layer "F.Cu")
		(net "P3V3")
	)
	(segment
		(start 29.03093 -85.107018)
		(end 29.03093 -85.9282)
		(width 0.508)
		(layer "F.Cu")
		(net "P3V3")
	)
	(segment
		(start 233.730546 -454.867264)
		(end 234.499912 -454.097898)
		(width 0.508)
		(layer "F.Cu")
		(net "P3V3")
	)
	(segment
		(start 193.4972 -491.0074)
		(end 185.0898 -491.0074)
		(width 1.016)
		(layer "F.Cu")
		(net "P3V3")
	)
	(segment
		(start 56.3372 -96.4692)
		(end 57.3024 -95.504)
		(width 1.016)
		(layer "F.Cu")
		(net "P3V3")
	)
	(segment
		(start 74.041 -456.311)
		(end 73.66 -456.692)
		(width 0.508)
		(layer "F.Cu")
		(net "P3V3")
	)
	(segment
		(start 224.480374 -246.387874)
		(end 224.480374 -246.921528)
		(width 0.508)
		(layer "F.Cu")
		(net "P3V3")
	)
	(segment
		(start 203.962 -198.882)
		(end 203.962 -203.073)
		(width 1.016)
		(layer "F.Cu")
		(net "P3V3")
	)
	(segment
		(start 212.55482 -459.975458)
		(end 212.55482 -460.41818)
		(width 0.3556)
		(layer "F.Cu")
		(net "P3V3")
	)
	(segment
		(start 226.773232 -347.005402)
		(end 227.221034 -346.5576)
		(width 0.508)
		(layer "F.Cu")
		(net "P3V3")
	)
	(segment
		(start 39.8272 -207.264)
		(end 39.116 -206.5528)
		(width 0.508)
		(layer "F.Cu")
		(net "P3V3")
	)
	(segment
		(start 91.059 -27.94)
		(end 91.059 -26.5811)
		(width 0.3048)
		(layer "F.Cu")
		(net "P3V3")
	)
	(segment
		(start 78.1558 -437.4134)
		(end 76.6572 -437.4134)
		(width 1.016)
		(layer "F.Cu")
		(net "P3V3")
	)
	(segment
		(start 62.8142 -199.1868)
		(end 74.549 -187.452)
		(width 1.016)
		(layer "F.Cu")
		(net "P3V3")
	)
	(segment
		(start 73.0504 -366.9665)
		(end 73.0504 -367.792)
		(width 0.508)
		(layer "F.Cu")
		(net "P3V3")
	)
	(segment
		(start 91.6305 -28.5115)
		(end 91.059 -27.94)
		(width 0.3048)
		(layer "F.Cu")
		(net "P3V3")
	)
	(segment
		(start 82.1055 -363.1438)
		(end 82.931 -363.1438)
		(width 0.508)
		(layer "F.Cu")
		(net "P3V3")
	)
	(segment
		(start 218.8845 -140.58011)
		(end 217.86469 -140.58011)
		(width 0.508)
		(layer "F.Cu")
		(net "P3V3")
	)
	(segment
		(start 45.9105 -140.589)
		(end 45.9105 -139.844272)
		(width 0.3556)
		(layer "F.Cu")
		(net "P3V3")
	)
	(segment
		(start 211.455 -44.2595)
		(end 211.455 -43.434)
		(width 0.508)
		(layer "F.Cu")
		(net "P3V3")
	)
	(segment
		(start 205.486 -437.769)
		(end 205.486 -441.833)
		(width 1.016)
		(layer "F.Cu")
		(net "P3V3")
	)
	(segment
		(start 37.084 -42.545)
		(end 35.0012 -42.545)
		(width 1.016)
		(layer "F.Cu")
		(net "P3V3")
	)
	(segment
		(start 44.1452 -96.4692)
		(end 56.3372 -96.4692)
		(width 1.016)
		(layer "F.Cu")
		(net "P3V3")
	)
	(segment
		(start 43.282108 -37.516562)
		(end 43.790616 -37.516562)
		(width 0.508)
		(layer "F.Cu")
		(net "P3V3")
	)
	(segment
		(start 25.9842 -444.373)
		(end 26.416 -443.9412)
		(width 0.508)
		(layer "F.Cu")
		(net "P3V3")
	)
	(segment
		(start 212.979 -452.628)
		(end 210.439 -452.628)
		(width 0.508)
		(layer "F.Cu")
		(net "P3V3")
	)
	(segment
		(start 24.7015 -464.82)
		(end 25.4762 -464.82)
		(width 0.508)
		(layer "F.Cu")
		(net "P3V3")
	)
	(segment
		(start 48.34382 -232.03662)
		(end 48.3362 -232.029)
		(width 1.016)
		(layer "F.Cu")
		(net "P3V3")
	)
	(segment
		(start 22.2758 -91.5924)
		(end 22.2758 -93.2053)
		(width 0.508)
		(layer "F.Cu")
		(net "P3V3")
	)
	(segment
		(start 88.519 -18.2245)
		(end 87.503 -18.2245)
		(width 0.508)
		(layer "F.Cu")
		(net "P3V3")
	)
	(segment
		(start 98.3615 -115.794282)
		(end 98.361246 -115.794028)
		(width 0.508)
		(layer "F.Cu")
		(net "P3V3")
	)
	(segment
		(start 234.5055 -349.631)
		(end 235.2802 -349.631)
		(width 0.508)
		(layer "F.Cu")
		(net "P3V3")
	)
	(segment
		(start 19.61007 -31.809944)
		(end 18.034 -31.809944)
		(width 0.508)
		(layer "F.Cu")
		(net "P3V3")
	)
	(segment
		(start 225.1075 -41.67759)
		(end 224.924874 -41.860216)
		(width 0.508)
		(layer "F.Cu")
		(net "P3V3")
	)
	(segment
		(start 20.828 -163.887658)
		(end 20.828 -164.9095)
		(width 0.508)
		(layer "F.Cu")
		(net "P3V3")
	)
	(segment
		(start 98.3615 -225.806)
		(end 98.3615 -225.028506)
		(width 0.508)
		(layer "F.Cu")
		(net "P3V3")
	)
	(segment
		(start 24.698198 -463.78241)
		(end 25.472898 -463.78241)
		(width 0.508)
		(layer "F.Cu")
		(net "P3V3")
	)
	(segment
		(start 225.1075 -40.894)
		(end 225.1075 -41.67759)
		(width 0.508)
		(layer "F.Cu")
		(net "P3V3")
	)
	(segment
		(start 225.084894 -349.617284)
		(end 224.337626 -348.870016)
		(width 0.508)
		(layer "F.Cu")
		(net "P3V3")
	)
	(segment
		(start 227.389944 -371.190012)
		(end 228.966014 -371.190012)
		(width 0.508)
		(layer "F.Cu")
		(net "P3V3")
	)
	(segment
		(start 81.3054 -148.1836)
		(end 79.6798 -148.1836)
		(width 0.3048)
		(layer "F.Cu")
		(net "P3V3")
	)
	(segment
		(start 229.67696 -241.563398)
		(end 228.0285 -241.563398)
		(width 0.381)
		(layer "F.Cu")
		(net "P3V3")
	)
	(segment
		(start 22.86 -196.7865)
		(end 22.0726 -196.7865)
		(width 0.508)
		(layer "F.Cu")
		(net "P3V3")
	)
	(segment
		(start 44.68749 -351.872042)
		(end 43.465496 -351.872042)
		(width 0.508)
		(layer "F.Cu")
		(net "P3V3")
	)
	(segment
		(start 16.204438 -362.137452)
		(end 16.204438 -361.55249)
		(width 0.508)
		(layer "F.Cu")
		(net "P3V3")
	)
	(segment
		(start 21.231606 -161.665158)
		(end 20.541488 -161.665158)
		(width 0.508)
		(layer "F.Cu")
		(net "P3V3")
	)
	(segment
		(start 73.0504 -445.1096)
		(end 73.152 -445.008)
		(width 0.3556)
		(layer "F.Cu")
		(net "P3V3")
	)
	(segment
		(start 229.67696 -448.50304)
		(end 228.7905 -449.3895)
		(width 0.508)
		(layer "F.Cu")
		(net "P3V3")
	)
	(segment
		(start 221.615 -267.589)
		(end 220.21419 -267.589)
		(width 0.508)
		(layer "F.Cu")
		(net "P3V3")
	)
	(segment
		(start 49.4665 -454.787)
		(end 50.2666 -454.787)
		(width 0.508)
		(layer "F.Cu")
		(net "P3V3")
	)
	(segment
		(start 33.054798 -380.457202)
		(end 33.054798 -379.975364)
		(width 0.3556)
		(layer "F.Cu")
		(net "P3V3")
	)
	(segment
		(start 44.677076 -35.918902)
		(end 44.048426 -35.918902)
		(width 0.381)
		(layer "F.Cu")
		(net "P3V3")
	)
	(segment
		(start 97.8535 -195.834)
		(end 97.8535 -196.62394)
		(width 0.508)
		(layer "F.Cu")
		(net "P3V3")
	)
	(segment
		(start 82.1055 -365.1758)
		(end 82.931 -365.1758)
		(width 0.508)
		(layer "F.Cu")
		(net "P3V3")
	)
	(segment
		(start 101.7905 -213.487)
		(end 102.616 -213.487)
		(width 0.508)
		(layer "F.Cu")
		(net "P3V3")
	)
	(segment
		(start 49.429924 -449.031868)
		(end 49.429924 -449.43776)
		(width 0.508)
		(layer "F.Cu")
		(net "P3V3")
	)
	(segment
		(start 51.562 -134.9375)
		(end 52.451 -134.9375)
		(width 0.508)
		(layer "F.Cu")
		(net "P3V3")
	)
	(segment
		(start 46.228 -242.8875)
		(end 47.60976 -242.8875)
		(width 0.381)
		(layer "F.Cu")
		(net "P3V3")
	)
	(segment
		(start 46.355 -212.598)
		(end 74.168 -212.598)
		(width 1.016)
		(layer "F.Cu")
		(net "P3V3")
	)
	(segment
		(start 26.797 -133.35)
		(end 27.432 -132.715)
		(width 0.508)
		(layer "F.Cu")
		(net "P3V3")
	)
	(segment
		(start 75.5904 -357.3526)
		(end 75.950064 -357.712264)
		(width 0.3048)
		(layer "F.Cu")
		(net "P3V3")
	)
	(segment
		(start 215.265 -136.017)
		(end 168.402 -136.017)
		(width 1.016)
		(layer "F.Cu")
		(net "P3V3")
	)
	(segment
		(start 41.672764 -346.507054)
		(end 41.672764 -347.491558)
		(width 0.508)
		(layer "F.Cu")
		(net "P3V3")
	)
	(segment
		(start 36.576 -267.589)
		(end 37.592 -267.589)
		(width 0.508)
		(layer "F.Cu")
		(net "P3V3")
	)
	(segment
		(start 54.5338 -199.1868)
		(end 62.8142 -199.1868)
		(width 1.016)
		(layer "F.Cu")
		(net "P3V3")
	)
	(segment
		(start 221.615 -164.592)
		(end 222.631 -164.592)
		(width 0.508)
		(layer "F.Cu")
		(net "P3V3")
	)
	(segment
		(start 63.130938 -95.504)
		(end 65.416938 -97.79)
		(width 1.016)
		(layer "F.Cu")
		(net "P3V3")
	)
	(segment
		(start 36.576 -370.332)
		(end 37.592 -370.332)
		(width 0.508)
		(layer "F.Cu")
		(net "P3V3")
	)
	(segment
		(start 220.21419 -267.589)
		(end 167.64 -267.589)
		(width 1.016)
		(layer "F.Cu")
		(net "P3V3")
	)
	(segment
		(start 29.95803 -188.129418)
		(end 29.95803 -188.9252)
		(width 0.508)
		(layer "F.Cu")
		(net "P3V3")
	)
	(segment
		(start 197.0786 -209.9564)
		(end 168.148 -209.9564)
		(width 1.016)
		(layer "F.Cu")
		(net "P3V3")
	)
	(segment
		(start 21.144992 -267.433044)
		(end 19.7485 -267.433044)
		(width 0.508)
		(layer "F.Cu")
		(net "P3V3")
	)
	(segment
		(start 39.8272 -207.264)
		(end 41.021 -207.264)
		(width 1.016)
		(layer "F.Cu")
		(net "P3V3")
	)
	(segment
		(start 16.26616 -259.13969)
		(end 16.26616 -258.230878)
		(width 0.508)
		(layer "F.Cu")
		(net "P3V3")
	)
	(segment
		(start 194.243706 -496.063778)
		(end 194.243706 -491.753906)
		(width 1.016)
		(layer "F.Cu")
		(net "P3V3")
	)
	(segment
		(start 83.6295 -150.622)
		(end 84.455 -150.622)
		(width 0.508)
		(layer "F.Cu")
		(net "P3V3")
	)
	(segment
		(start 29.972 -373.38)
		(end 29.972 -374.2055)
		(width 0.508)
		(layer "F.Cu")
		(net "P3V3")
	)
	(segment
		(start 209.677 -453.39)
		(end 209.677 -454.2155)
		(width 0.508)
		(layer "F.Cu")
		(net "P3V3")
	)
	(segment
		(start 216.6366 -139.35202)
		(end 216.6366 -137.3886)
		(width 1.016)
		(layer "F.Cu")
		(net "P3V3")
	)
	(segment
		(start 234.5055 -144.77111)
		(end 235.29671 -144.77111)
		(width 0.508)
		(layer "F.Cu")
		(net "P3V3")
	)
	(segment
		(start 89.3445 -320.167)
		(end 89.3445 -319.37452)
		(width 0.508)
		(layer "F.Cu")
		(net "P3V3")
	)
	(segment
		(start 229.93096 -35.563302)
		(end 229.904036 -35.563302)
		(width 0.381)
		(layer "F.Cu")
		(net "P3V3")
	)
	(segment
		(start 43.790616 -37.516562)
		(end 44.677076 -36.630102)
		(width 0.508)
		(layer "F.Cu")
		(net "P3V3")
	)
	(segment
		(start 32.2961 -147.6756)
		(end 31.5341 -146.9136)
		(width 1.016)
		(layer "F.Cu")
		(net "P3V3")
	)
	(segment
		(start 227.389944 -474.19006)
		(end 228.966014 -474.19006)
		(width 0.508)
		(layer "F.Cu")
		(net "P3V3")
	)
	(segment
		(start 108.966 -437.3245)
		(end 108.17987 -437.3245)
		(width 0.508)
		(layer "F.Cu")
		(net "P3V3")
	)
	(segment
		(start 226.946714 -141.801342)
		(end 226.946714 -142.343632)
		(width 0.508)
		(layer "F.Cu")
		(net "P3V3")
	)
	(segment
		(start 229.904036 -36.503102)
		(end 229.017576 -37.389562)
		(width 0.508)
		(layer "F.Cu")
		(net "P3V3")
	)
	(segment
		(start 18.21815 -463.126074)
		(end 18.31467 -463.126074)
		(width 0.508)
		(layer "F.Cu")
		(net "P3V3")
	)
	(segment
		(start 23.172674 -61.433202)
		(end 22.259798 -61.433202)
		(width 0.4064)
		(layer "F.Cu")
		(net "P3V3")
	)
	(segment
		(start 228.7905 -140.38961)
		(end 228.283516 -140.38961)
		(width 0.508)
		(layer "F.Cu")
		(net "P3V3")
	)
	(segment
		(start 80.137 -353.6315)
		(end 80.137 -352.806)
		(width 0.508)
		(layer "F.Cu")
		(net "P3V3")
	)
	(segment
		(start 42.39006 -165.189916)
		(end 43.96613 -165.189916)
		(width 0.508)
		(layer "F.Cu")
		(net "P3V3")
	)
	(segment
		(start 228.2952 -449.3895)
		(end 227.468938 -449.3895)
		(width 0.508)
		(layer "F.Cu")
		(net "P3V3")
	)
	(segment
		(start 90.932 -16.256)
		(end 90.932 -17.0815)
		(width 0.508)
		(layer "F.Cu")
		(net "P3V3")
	)
	(segment
		(start 74.0664 -366.9665)
		(end 74.0664 -367.792)
		(width 0.508)
		(layer "F.Cu")
		(net "P3V3")
	)
	(segment
		(start 213.741 -454.2155)
		(end 213.741 -453.39)
		(width 0.508)
		(layer "F.Cu")
		(net "P3V3")
	)
	(segment
		(start 46.054772 -139.7)
		(end 46.054772 -138.975338)
		(width 0.3556)
		(layer "F.Cu")
		(net "P3V3")
	)
	(segment
		(start 227.141278 -449.3895)
		(end 226.505262 -450.025516)
		(width 0.508)
		(layer "F.Cu")
		(net "P3V3")
	)
	(segment
		(start 40.88765 -145.23339)
		(end 41.184576 -145.23339)
		(width 0.508)
		(layer "F.Cu")
		(net "P3V3")
	)
	(segment
		(start 21.231606 -367.665)
		(end 20.541488 -367.665)
		(width 0.508)
		(layer "F.Cu")
		(net "P3V3")
	)
	(segment
		(start 48.3235 -351.028)
		(end 48.3235 -351.776538)
		(width 0.508)
		(layer "F.Cu")
		(net "P3V3")
	)
	(segment
		(start 21.843492 -370.433092)
		(end 21.017992 -370.433092)
		(width 0.508)
		(layer "F.Cu")
		(net "P3V3")
	)
	(segment
		(start 56.007 -11.3284)
		(end 52.8701 -8.1915)
		(width 1.016)
		(layer "F.Cu")
		(net "P3V3")
	)
	(segment
		(start 226.90709 -347.952822)
		(end 226.751896 -347.797628)
		(width 0.508)
		(layer "F.Cu")
		(net "P3V3")
	)
	(segment
		(start 45.212 -242.8875)
		(end 45.212 -243.84)
		(width 0.508)
		(layer "F.Cu")
		(net "P3V3")
	)
	(segment
		(start 221.361 -473.456)
		(end 222.504 -473.456)
		(width 0.508)
		(layer "F.Cu")
		(net "P3V3")
	)
	(segment
		(start 75.5904 -355.981)
		(end 76.5556 -355.981)
		(width 0.508)
		(layer "F.Cu")
		(net "P3V3")
	)
	(segment
		(start 49.7205 -248.539)
		(end 50.5206 -248.539)
		(width 0.508)
		(layer "F.Cu")
		(net "P3V3")
	)
	(segment
		(start 39.02075 -103.73995)
		(end 39.9288 -104.648)
		(width 0.508)
		(layer "F.Cu")
		(net "P3V3")
	)
	(segment
		(start 19.5834 -470.01938)
		(end 19.5834 -469.8111)
		(width 0.508)
		(layer "F.Cu")
		(net "P3V3")
	)
	(segment
		(start 96.3295 -116.586)
		(end 96.3295 -115.7986)
		(width 0.508)
		(layer "F.Cu")
		(net "P3V3")
	)
	(segment
		(start 227.468938 -140.38961)
		(end 227.363782 -140.38961)
		(width 0.508)
		(layer "F.Cu")
		(net "P3V3")
	)
	(segment
		(start 38.1508 -413.1437)
		(end 39.116 -412.1785)
		(width 0.508)
		(layer "F.Cu")
		(net "P3V3")
	)
	(segment
		(start 16.26616 -258.229354)
		(end 16.26616 -257.309874)
		(width 0.508)
		(layer "F.Cu")
		(net "P3V3")
	)
	(segment
		(start 90.4875 -416.814)
		(end 90.4875 -417.60648)
		(width 0.508)
		(layer "F.Cu")
		(net "P3V3")
	)
	(segment
		(start 30.80004 -388.80796)
		(end 29.69514 -388.80796)
		(width 1.016)
		(layer "F.Cu")
		(net "P3V3")
	)
	(segment
		(start 15.317724 -53.933852)
		(end 15.204186 -53.820314)
		(width 0.508)
		(layer "F.Cu")
		(net "P3V3")
	)
	(segment
		(start 87.3125 -115.781074)
		(end 87.307166 -115.77574)
		(width 0.508)
		(layer "F.Cu")
		(net "P3V3")
	)
	(segment
		(start 243.586 -424.6245)
		(end 243.586 -425.45)
		(width 0.508)
		(layer "F.Cu")
		(net "P3V3")
	)
	(segment
		(start 228.0285 -344.563192)
		(end 229.67696 -344.563192)
		(width 0.381)
		(layer "F.Cu")
		(net "P3V3")
	)
	(segment
		(start 79.6798 -148.1836)
		(end 79.396336 -148.467064)
		(width 0.3048)
		(layer "F.Cu")
		(net "P3V3")
	)
	(segment
		(start 227.696014 -37.389562)
		(end 227.617782 -37.389562)
		(width 0.508)
		(layer "F.Cu")
		(net "P3V3")
	)
	(segment
		(start 32.5755 -382.651)
		(end 32.5755 -387.0325)
		(width 1.016)
		(layer "F.Cu")
		(net "P3V3")
	)
	(segment
		(start 217.836242 -243.580158)
		(end 217.836242 -240.264442)
		(width 1.016)
		(layer "F.Cu")
		(net "P3V3")
	)
	(segment
		(start 23.5458 -91.0336)
		(end 22.8346 -91.0336)
		(width 0.508)
		(layer "F.Cu")
		(net "P3V3")
	)
	(segment
		(start 21.4249 -466.4202)
		(end 18.93062 -466.4202)
		(width 0.508)
		(layer "F.Cu")
		(net "P3V3")
	)
	(segment
		(start 25.4 -339.09)
		(end 24.384 -339.09)
		(width 0.508)
		(layer "F.Cu")
		(net "P3V3")
	)
	(segment
		(start 74.4474 -352.2345)
		(end 74.4474 -351.409)
		(width 0.508)
		(layer "F.Cu")
		(net "P3V3")
	)
	(segment
		(start 38.1508 -413.512)
		(end 38.1508 -413.1437)
		(width 0.508)
		(layer "F.Cu")
		(net "P3V3")
	)
	(segment
		(start 36.576 -473.456)
		(end 37.592 -473.456)
		(width 0.508)
		(layer "F.Cu")
		(net "P3V3")
	)
	(segment
		(start 224.924874 -42.372026)
		(end 225.314764 -42.761916)
		(width 0.508)
		(layer "F.Cu")
		(net "P3V3")
	)
	(segment
		(start 108.966 -308.6735)
		(end 108.077 -308.6735)
		(width 0.508)
		(layer "F.Cu")
		(net "P3V3")
	)
	(segment
		(start 220.4466 -164.592)
		(end 198.755 -164.592)
		(width 1.016)
		(layer "F.Cu")
		(net "P3V3")
	)
	(segment
		(start 206.3115 -299.7835)
		(end 204.6605 -299.7835)
		(width 1.016)
		(layer "F.Cu")
		(net "P3V3")
	)
	(segment
		(start 47.836582 -352.263456)
		(end 45.078904 -352.263456)
		(width 0.508)
		(layer "F.Cu")
		(net "P3V3")
	)
	(segment
		(start 213.741 -453.39)
		(end 212.979 -452.628)
		(width 0.508)
		(layer "F.Cu")
		(net "P3V3")
	)
	(segment
		(start 227.33762 -243.41582)
		(end 226.747832 -244.005608)
		(width 0.508)
		(layer "F.Cu")
		(net "P3V3")
	)
	(segment
		(start 227.400104 -346.389452)
		(end 227.494338 -346.389452)
		(width 0.508)
		(layer "F.Cu")
		(net "P3V3")
	)
	(segment
		(start 79.1464 -366.9665)
		(end 79.1464 -367.792)
		(width 0.508)
		(layer "F.Cu")
		(net "P3V3")
	)
	(segment
		(start 220.208094 -40.490394)
		(end 220.208094 -41.284906)
		(width 0.508)
		(layer "F.Cu")
		(net "P3V3")
	)
	(segment
		(start 108.17987 -437.3245)
		(end 108.173266 -437.317896)
		(width 0.508)
		(layer "F.Cu")
		(net "P3V3")
	)
	(segment
		(start 214.14867 -338.201)
		(end 217.1446 -341.19693)
		(width 1.016)
		(layer "F.Cu")
		(net "P3V3")
	)
	(via
		(at 20.4724 -469.6206)
		(size 0.508)
		(drill 0.254)
		(layers "F.Cu" "B.Cu")
		(net "P3V3")
	)
	(via
		(at 69.469 -145.542)
		(size 0.508)
		(drill 0.254)
		(layers "F.Cu" "B.Cu")
		(net "P3V3")
	)
	(via
		(at 82.931 -365.1758)
		(size 0.508)
		(drill 0.254)
		(layers "F.Cu" "B.Cu")
		(net "P3V3")
	)
	(via
		(at 21.646642 -163.887658)
		(size 0.508)
		(drill 0.254)
		(layers "F.Cu" "B.Cu")
		(net "P3V3")
	)
	(via
		(at 74.803 -318.516)
		(size 0.508)
		(drill 0.254)
		(layers "F.Cu" "B.Cu")
		(net "P3V3")
	)
	(via
		(at 243.586 -420.878)
		(size 0.508)
		(drill 0.254)
		(layers "F.Cu" "B.Cu")
		(net "P3V3")
	)
	(via
		(at 26.416 -443.9412)
		(size 0.508)
		(drill 0.254)
		(layers "F.Cu" "B.Cu")
		(net "P3V3")
	)
	(via
		(at 82.931 -359.029)
		(size 0.508)
		(drill 0.254)
		(layers "F.Cu" "B.Cu")
		(net "P3V3")
	)
	(via
		(at 32.5755 -382.651)
		(size 0.508)
		(drill 0.254)
		(layers "F.Cu" "B.Cu")
		(net "P3V3")
	)
	(via
		(at 20.749006 -264.0584)
		(size 0.508)
		(drill 0.254)
		(layers "F.Cu" "B.Cu")
		(net "P3V3")
	)
	(via
		(at 96.33458 -225.017838)
		(size 0.508)
		(drill 0.254)
		(layers "F.Cu" "B.Cu")
		(net "P3V3")
	)
	(via
		(at 49.1236 -351.028)
		(size 0.508)
		(drill 0.254)
		(layers "F.Cu" "B.Cu")
		(net "P3V3")
	)
	(via
		(at 45.73905 -454.835768)
		(size 0.508)
		(drill 0.254)
		(layers "F.Cu" "B.Cu")
		(net "P3V3")
	)
	(via
		(at 90.486738 -417.607242)
		(size 0.508)
		(drill 0.254)
		(layers "F.Cu" "B.Cu")
		(net "P3V3")
	)
	(via
		(at 95.8215 -196.723)
		(size 0.508)
		(drill 0.254)
		(layers "F.Cu" "B.Cu")
		(net "P3V3")
	)
	(via
		(at 80.264 -155.448)
		(size 0.508)
		(drill 0.254)
		(layers "F.Cu" "B.Cu")
		(net "P3V3")
	)
	(via
		(at 87.3125 -445.897)
		(size 0.508)
		(drill 0.254)
		(layers "F.Cu" "B.Cu")
		(net "P3V3")
	)
	(via
		(at 77.089 -216.6874)
		(size 0.508)
		(drill 0.254)
		(layers "F.Cu" "B.Cu")
		(net "P3V3")
	)
	(via
		(at 75.438 -451.358)
		(size 0.508)
		(drill 0.254)
		(layers "F.Cu" "B.Cu")
		(net "P3V3")
	)
	(via
		(at 24.384 -133.096)
		(size 0.508)
		(drill 0.254)
		(layers "F.Cu" "B.Cu")
		(net "P3V3")
	)
	(via
		(at 214.7824 -394.7922)
		(size 0.508)
		(drill 0.254)
		(layers "F.Cu" "B.Cu")
		(net "P3V3")
	)
	(via
		(at 27.94 -373.38)
		(size 0.508)
		(drill 0.254)
		(layers "F.Cu" "B.Cu")
		(net "P3V3")
	)
	(via
		(at 161.0868 -397.6878)
		(size 0.508)
		(drill 0.254)
		(layers "F.Cu" "B.Cu")
		(net "P3V3")
	)
	(via
		(at 224.337626 -348.870016)
		(size 0.508)
		(drill 0.254)
		(layers "F.Cu" "B.Cu")
		(net "P3V3")
	)
	(via
		(at 235.3056 -453.771)
		(size 0.508)
		(drill 0.254)
		(layers "F.Cu" "B.Cu")
		(net "P3V3")
	)
	(via
		(at 108.176314 -206.4385)
		(size 0.508)
		(drill 0.254)
		(layers "F.Cu" "B.Cu")
		(net "P3V3")
	)
	(via
		(at 24.3586 -153.797)
		(size 0.508)
		(drill 0.254)
		(layers "F.Cu" "B.Cu")
		(net "P3V3")
	)
	(via
		(at 192.786 -423.291)
		(size 0.508)
		(drill 0.254)
		(layers "F.Cu" "B.Cu")
		(net "P3V3")
	)
	(via
		(at 69.469 -360.553)
		(size 0.508)
		(drill 0.254)
		(layers "F.Cu" "B.Cu")
		(net "P3V3")
	)
	(via
		(at 166.878 -338.201)
		(size 0.508)
		(drill 0.254)
		(layers "F.Cu" "B.Cu")
		(net "P3V3")
	)
	(via
		(at 162.4838 -397.6878)
		(size 0.508)
		(drill 0.254)
		(layers "F.Cu" "B.Cu")
		(net "P3V3")
	)
	(via
		(at 50.8635 -145.3134)
		(size 0.508)
		(drill 0.254)
		(layers "F.Cu" "B.Cu")
		(net "P3V3")
	)
	(via
		(at 21.017992 -369.607592)
		(size 0.508)
		(drill 0.254)
		(layers "F.Cu" "B.Cu")
		(net "P3V3")
	)
	(via
		(at 16.265398 -258.230116)
		(size 0.508)
		(drill 0.254)
		(layers "F.Cu" "B.Cu")
		(net "P3V3")
	)
	(via
		(at 42.494454 -346.262452)
		(size 0.508)
		(drill 0.254)
		(layers "F.Cu" "B.Cu")
		(net "P3V3")
	)
	(via
		(at 168.402 -136.017)
		(size 0.508)
		(drill 0.254)
		(layers "F.Cu" "B.Cu")
		(net "P3V3")
	)
	(via
		(at 108.17606 -208.465166)
		(size 0.508)
		(drill 0.254)
		(layers "F.Cu" "B.Cu")
		(net "P3V3")
	)
	(via
		(at 69.469 -363.601)
		(size 0.508)
		(drill 0.254)
		(layers "F.Cu" "B.Cu")
		(net "P3V3")
	)
	(via
		(at 45.212 -243.84)
		(size 0.508)
		(drill 0.254)
		(layers "F.Cu" "B.Cu")
		(net "P3V3")
	)
	(via
		(at 32.004 -372.364)
		(size 0.508)
		(drill 0.254)
		(layers "F.Cu" "B.Cu")
		(net "P3V3")
	)
	(via
		(at 96.266 -440.944)
		(size 0.508)
		(drill 0.254)
		(layers "F.Cu" "B.Cu")
		(net "P3V3")
	)
	(via
		(at 167.64 -267.589)
		(size 0.508)
		(drill 0.254)
		(layers "F.Cu" "B.Cu")
		(net "P3V3")
	)
	(via
		(at 82.931 -363.1438)
		(size 0.508)
		(drill 0.254)
		(layers "F.Cu" "B.Cu")
		(net "P3V3")
	)
	(via
		(at 23.5458 -91.0336)
		(size 0.508)
		(drill 0.254)
		(layers "F.Cu" "B.Cu")
		(net "P3V3")
	)
	(via
		(at 89.3445 -445.897)
		(size 0.508)
		(drill 0.254)
		(layers "F.Cu" "B.Cu")
		(net "P3V3")
	)
	(via
		(at 74.295 -245.237)
		(size 0.508)
		(drill 0.254)
		(layers "F.Cu" "B.Cu")
		(net "P3V3")
	)
	(via
		(at 25.3746 -360.5784)
		(size 0.508)
		(drill 0.254)
		(layers "F.Cu" "B.Cu")
		(net "P3V3")
	)
	(via
		(at 74.168 -212.598)
		(size 0.508)
		(drill 0.254)
		(layers "F.Cu" "B.Cu")
		(net "P3V3")
	)
	(via
		(at 211.074 -412.75)
		(size 0.7112)
		(drill 0.3556)
		(layers "F.Cu" "B.Cu")
		(net "P3V3")
	)
	(via
		(at 227.468938 -243.389658)
		(size 0.508)
		(drill 0.254)
		(layers "F.Cu" "B.Cu")
		(net "P3V3")
	)
	(via
		(at 46.853094 -26.255472)
		(size 0.508)
		(drill 0.254)
		(layers "F.Cu" "B.Cu")
		(net "P3V3")
	)
	(via
		(at 89.355168 -225.00209)
		(size 0.508)
		(drill 0.254)
		(layers "F.Cu" "B.Cu")
		(net "P3V3")
	)
	(via
		(at 78.232 -155.448)
		(size 0.508)
		(drill 0.254)
		(layers "F.Cu" "B.Cu")
		(net "P3V3")
	)
	(via
		(at 104.2797 -106.807)
		(size 0.508)
		(drill 0.254)
		(layers "F.Cu" "B.Cu")
		(net "P3V3")
	)
	(via
		(at 97.850452 -196.626988)
		(size 0.508)
		(drill 0.254)
		(layers "F.Cu" "B.Cu")
		(net "P3V3")
	)
	(via
		(at 20.43811 -398.81048)
		(size 0.508)
		(drill 0.254)
		(layers "F.Cu" "B.Cu")
		(net "P3V3")
	)
	(via
		(at 228.966014 -474.19006)
		(size 0.508)
		(drill 0.254)
		(layers "F.Cu" "B.Cu")
		(net "P3V3")
	)
	(via
		(at 19.598386 -461.842358)
		(size 0.508)
		(drill 0.254)
		(layers "F.Cu" "B.Cu")
		(net "P3V3")
	)
	(via
		(at 221.869 -412.877)
		(size 0.7112)
		(drill 0.3556)
		(layers "F.Cu" "B.Cu")
		(net "P3V3")
	)
	(via
		(at 76.708 -445.008)
		(size 0.508)
		(drill 0.254)
		(layers "F.Cu" "B.Cu")
		(net "P3V3")
	)
	(via
		(at 235.29671 -144.77111)
		(size 0.508)
		(drill 0.254)
		(layers "F.Cu" "B.Cu")
		(net "P3V3")
	)
	(via
		(at 102.87 -73.406)
		(size 0.508)
		(drill 0.254)
		(layers "F.Cu" "B.Cu")
		(net "P3V3")
	)
	(via
		(at 18.034 -237.81004)
		(size 0.508)
		(drill 0.254)
		(layers "F.Cu" "B.Cu")
		(net "P3V3")
	)
	(via
		(at 52.6669 -246.031258)
		(size 0.508)
		(drill 0.254)
		(layers "F.Cu" "B.Cu")
		(net "P3V3")
	)
	(via
		(at 71.0311 -367.792)
		(size 0.508)
		(drill 0.254)
		(layers "F.Cu" "B.Cu")
		(net "P3V3")
	)
	(via
		(at 224.480374 -452.387716)
		(size 0.508)
		(drill 0.254)
		(layers "F.Cu" "B.Cu")
		(net "P3V3")
	)
	(via
		(at 50.5206 -248.539)
		(size 0.508)
		(drill 0.254)
		(layers "F.Cu" "B.Cu")
		(net "P3V3")
	)
	(via
		(at 161.0868 -396.5448)
		(size 0.508)
		(drill 0.254)
		(layers "F.Cu" "B.Cu")
		(net "P3V3")
	)
	(via
		(at 42.493692 -37.516562)
		(size 0.508)
		(drill 0.254)
		(layers "F.Cu" "B.Cu")
		(net "P3V3")
	)
	(via
		(at 41.1988 -250.952)
		(size 0.508)
		(drill 0.254)
		(layers "F.Cu" "B.Cu")
		(net "P3V3")
	)
	(via
		(at 206.756 -411.861)
		(size 0.508)
		(drill 0.254)
		(layers "F.Cu" "B.Cu")
		(net "P3V3")
	)
	(via
		(at 209.423 -43.434)
		(size 0.508)
		(drill 0.254)
		(layers "F.Cu" "B.Cu")
		(net "P3V3")
	)
	(via
		(at 96.33458 -319.37452)
		(size 0.508)
		(drill 0.254)
		(layers "F.Cu" "B.Cu")
		(net "P3V3")
	)
	(via
		(at 84.455 -152.654)
		(size 0.508)
		(drill 0.254)
		(layers "F.Cu" "B.Cu")
		(net "P3V3")
	)
	(via
		(at 37.592 -267.589)
		(size 0.508)
		(drill 0.254)
		(layers "F.Cu" "B.Cu")
		(net "P3V3")
	)
	(via
		(at 73.80732 -141.986)
		(size 0.508)
		(drill 0.254)
		(layers "F.Cu" "B.Cu")
		(net "P3V3")
	)
	(via
		(at 165.5318 -396.5448)
		(size 0.508)
		(drill 0.254)
		(layers "F.Cu" "B.Cu")
		(net "P3V3")
	)
	(via
		(at 89.3445 -319.37452)
		(size 0.508)
		(drill 0.254)
		(layers "F.Cu" "B.Cu")
		(net "P3V3")
	)
	(via
		(at 40.5384 -147.6756)
		(size 0.508)
		(drill 0.254)
		(layers "F.Cu" "B.Cu")
		(net "P3V3")
	)
	(via
		(at 74.676 -282.321)
		(size 0.508)
		(drill 0.254)
		(layers "F.Cu" "B.Cu")
		(net "P3V3")
	)
	(via
		(at 37.580824 -342.341708)
		(size 0.508)
		(drill 0.254)
		(layers "F.Cu" "B.Cu")
		(net "P3V3")
	)
	(via
		(at 235.29671 -143.637)
		(size 0.508)
		(drill 0.254)
		(layers "F.Cu" "B.Cu")
		(net "P3V3")
	)
	(via
		(at 50.4952 -41.275)
		(size 0.508)
		(drill 0.254)
		(layers "F.Cu" "B.Cu")
		(net "P3V3")
	)
	(via
		(at 52.451 -138.7475)
		(size 0.508)
		(drill 0.254)
		(layers "F.Cu" "B.Cu")
		(net "P3V3")
	)
	(via
		(at 69.469 -146.558)
		(size 0.508)
		(drill 0.254)
		(layers "F.Cu" "B.Cu")
		(net "P3V3")
	)
	(via
		(at 19.7485 -268.4145)
		(size 0.508)
		(drill 0.254)
		(layers "F.Cu" "B.Cu")
		(net "P3V3")
	)
	(via
		(at 25.4 -361.442)
		(size 0.508)
		(drill 0.254)
		(layers "F.Cu" "B.Cu")
		(net "P3V3")
	)
	(via
		(at 99.5045 -87.503)
		(size 0.508)
		(drill 0.254)
		(layers "F.Cu" "B.Cu")
		(net "P3V3")
	)
	(via
		(at 22.479 -299.0342)
		(size 0.508)
		(drill 0.254)
		(layers "F.Cu" "B.Cu")
		(net "P3V3")
	)
	(via
		(at 244.221 -412.623)
		(size 0.7112)
		(drill 0.3556)
		(layers "F.Cu" "B.Cu")
		(net "P3V3")
	)
	(via
		(at 74.4474 -351.409)
		(size 0.508)
		(drill 0.254)
		(layers "F.Cu" "B.Cu")
		(net "P3V3")
	)
	(via
		(at 76.6572 -437.4134)
		(size 0.508)
		(drill 0.254)
		(layers "F.Cu" "B.Cu")
		(net "P3V3")
	)
	(via
		(at 191.389 -422.148)
		(size 0.508)
		(drill 0.254)
		(layers "F.Cu" "B.Cu")
		(net "P3V3")
	)
	(via
		(at 235.292138 -41.771062)
		(size 0.508)
		(drill 0.254)
		(layers "F.Cu" "B.Cu")
		(net "P3V3")
	)
	(via
		(at 97.282 -441.0202)
		(size 0.508)
		(drill 0.254)
		(layers "F.Cu" "B.Cu")
		(net "P3V3")
	)
	(via
		(at 137.708386 -397.773398)
		(size 0.508)
		(drill 0.254)
		(layers "F.Cu" "B.Cu")
		(net "P3V3")
	)
	(via
		(at 193.8528 -431.4444)
		(size 0.7112)
		(drill 0.3556)
		(layers "F.Cu" "B.Cu")
		(net "P3V3")
	)
	(via
		(at 76.0984 -367.792)
		(size 0.508)
		(drill 0.254)
		(layers "F.Cu" "B.Cu")
		(net "P3V3")
	)
	(via
		(at 222.631 -267.589)
		(size 0.508)
		(drill 0.254)
		(layers "F.Cu" "B.Cu")
		(net "P3V3")
	)
	(via
		(at 44.1452 -96.4692)
		(size 0.508)
		(drill 0.254)
		(layers "F.Cu" "B.Cu")
		(net "P3V3")
	)
	(via
		(at 50.4952 -42.418)
		(size 0.508)
		(drill 0.254)
		(layers "F.Cu" "B.Cu")
		(net "P3V3")
	)
	(via
		(at 231.267 -440.5884)
		(size 0.508)
		(drill 0.254)
		(layers "F.Cu" "B.Cu")
		(net "P3V3")
	)
	(via
		(at 63.9826 -449.5546)
		(size 0.508)
		(drill 0.254)
		(layers "F.Cu" "B.Cu")
		(net "P3V3")
	)
	(via
		(at 51.637946 -447.8909)
		(size 0.508)
		(drill 0.254)
		(layers "F.Cu" "B.Cu")
		(net "P3V3")
	)
	(via
		(at 227.696014 -37.389562)
		(size 0.508)
		(drill 0.254)
		(layers "F.Cu" "B.Cu")
		(net "P3V3")
	)
	(via
		(at 43.96613 -371.190012)
		(size 0.508)
		(drill 0.254)
		(layers "F.Cu" "B.Cu")
		(net "P3V3")
	)
	(via
		(at 19.4945 -371.541548)
		(size 0.508)
		(drill 0.254)
		(layers "F.Cu" "B.Cu")
		(net "P3V3")
	)
	(via
		(at 216.154 -413.258)
		(size 0.7112)
		(drill 0.3556)
		(layers "F.Cu" "B.Cu")
		(net "P3V3")
	)
	(via
		(at 220.208094 -41.284906)
		(size 0.508)
		(drill 0.254)
		(layers "F.Cu" "B.Cu")
		(net "P3V3")
	)
	(via
		(at 85.344 -146.9644)
		(size 0.508)
		(drill 0.254)
		(layers "F.Cu" "B.Cu")
		(net "P3V3")
	)
	(via
		(at 214.3887 -85.6742)
		(size 0.508)
		(drill 0.254)
		(layers "F.Cu" "B.Cu")
		(net "P3V3")
	)
	(via
		(at 75.8063 -141.986)
		(size 0.508)
		(drill 0.254)
		(layers "F.Cu" "B.Cu")
		(net "P3V3")
	)
	(via
		(at 237.109 -412.75)
		(size 0.7112)
		(drill 0.3556)
		(layers "F.Cu" "B.Cu")
		(net "P3V3")
	)
	(via
		(at 40.145208 -308.877208)
		(size 0.508)
		(drill 0.254)
		(layers "F.Cu" "B.Cu")
		(net "P3V3")
	)
	(via
		(at 74.168 -155.448)
		(size 0.508)
		(drill 0.254)
		(layers "F.Cu" "B.Cu")
		(net "P3V3")
	)
	(via
		(at 87.503 -18.2245)
		(size 0.508)
		(drill 0.254)
		(layers "F.Cu" "B.Cu")
		(net "P3V3")
	)
	(via
		(at 25.4762 -464.82)
		(size 0.508)
		(drill 0.254)
		(layers "F.Cu" "B.Cu")
		(net "P3V3")
	)
	(via
		(at 58.293 -240.4364)
		(size 0.508)
		(drill 0.254)
		(layers "F.Cu" "B.Cu")
		(net "P3V3")
	)
	(via
		(at 22.0726 -196.7865)
		(size 0.508)
		(drill 0.254)
		(layers "F.Cu" "B.Cu")
		(net "P3V3")
	)
	(via
		(at 24.384 -30.226)
		(size 0.508)
		(drill 0.254)
		(layers "F.Cu" "B.Cu")
		(net "P3V3")
	)
	(via
		(at 228.966014 -62.189868)
		(size 0.508)
		(drill 0.254)
		(layers "F.Cu" "B.Cu")
		(net "P3V3")
	)
	(via
		(at 77.216 -155.448)
		(size 0.508)
		(drill 0.254)
		(layers "F.Cu" "B.Cu")
		(net "P3V3")
	)
	(via
		(at 83.312 -350.901)
		(size 0.508)
		(drill 0.254)
		(layers "F.Cu" "B.Cu")
		(net "P3V3")
	)
	(via
		(at 45.140118 -451.653148)
		(size 0.508)
		(drill 0.254)
		(layers "F.Cu" "B.Cu")
		(net "P3V3")
	)
	(via
		(at 69.469 -151.638)
		(size 0.508)
		(drill 0.254)
		(layers "F.Cu" "B.Cu")
		(net "P3V3")
	)
	(via
		(at 195.834 -423.291)
		(size 0.508)
		(drill 0.254)
		(layers "F.Cu" "B.Cu")
		(net "P3V3")
	)
	(via
		(at 205.359 -414.147)
		(size 0.508)
		(drill 0.254)
		(layers "F.Cu" "B.Cu")
		(net "P3V3")
	)
	(via
		(at 77.5208 -231.902)
		(size 0.508)
		(drill 0.254)
		(layers "F.Cu" "B.Cu")
		(net "P3V3")
	)
	(via
		(at 164.1348 -396.5448)
		(size 0.508)
		(drill 0.254)
		(layers "F.Cu" "B.Cu")
		(net "P3V3")
	)
	(via
		(at 15.317724 -53.933852)
		(size 0.508)
		(drill 0.254)
		(layers "F.Cu" "B.Cu")
		(net "P3V3")
	)
	(via
		(at 18.319242 -467.660482)
		(size 0.508)
		(drill 0.254)
		(layers "F.Cu" "B.Cu")
		(net "P3V3")
	)
	(via
		(at 40.0685 -137.4775)
		(size 0.508)
		(drill 0.254)
		(layers "F.Cu" "B.Cu")
		(net "P3V3")
	)
	(via
		(at 137.708386 -396.376398)
		(size 0.508)
		(drill 0.254)
		(layers "F.Cu" "B.Cu")
		(net "P3V3")
	)
	(via
		(at 87.307166 -115.77574)
		(size 0.508)
		(drill 0.254)
		(layers "F.Cu" "B.Cu")
		(net "P3V3")
	)
	(via
		(at 222.504 -473.456)
		(size 0.508)
		(drill 0.254)
		(layers "F.Cu" "B.Cu")
		(net "P3V3")
	)
	(via
		(at 168.148 -370.586)
		(size 0.508)
		(drill 0.254)
		(layers "F.Cu" "B.Cu")
		(net "P3V3")
	)
	(via
		(at 139.105386 -396.376398)
		(size 0.508)
		(drill 0.254)
		(layers "F.Cu" "B.Cu")
		(net "P3V3")
	)
	(via
		(at 211.455 -43.434)
		(size 0.508)
		(drill 0.254)
		(layers "F.Cu" "B.Cu")
		(net "P3V3")
	)
	(via
		(at 37.592 -164.592)
		(size 0.508)
		(drill 0.254)
		(layers "F.Cu" "B.Cu")
		(net "P3V3")
	)
	(via
		(at 40.513 -45.974)
		(size 0.508)
		(drill 0.254)
		(layers "F.Cu" "B.Cu")
		(net "P3V3")
	)
	(via
		(at 88.457278 -417.609528)
		(size 0.508)
		(drill 0.254)
		(layers "F.Cu" "B.Cu")
		(net "P3V3")
	)
	(via
		(at 74.9808 -231.902)
		(size 0.508)
		(drill 0.254)
		(layers "F.Cu" "B.Cu")
		(net "P3V3")
	)
	(via
		(at 25.5016 -52.9082)
		(size 0.508)
		(drill 0.254)
		(layers "F.Cu" "B.Cu")
		(net "P3V3")
	)
	(via
		(at 32.2072 -213.995)
		(size 0.508)
		(drill 0.254)
		(layers "F.Cu" "B.Cu")
		(net "P3V3")
	)
	(via
		(at 52.451 -136.8425)
		(size 0.508)
		(drill 0.254)
		(layers "F.Cu" "B.Cu")
		(net "P3V3")
	)
	(via
		(at 206.756 -413.004)
		(size 0.508)
		(drill 0.254)
		(layers "F.Cu" "B.Cu")
		(net "P3V3")
	)
	(via
		(at 191.389 -423.291)
		(size 0.508)
		(drill 0.254)
		(layers "F.Cu" "B.Cu")
		(net "P3V3")
	)
	(via
		(at 98.372168 -319.36944)
		(size 0.508)
		(drill 0.254)
		(layers "F.Cu" "B.Cu")
		(net "P3V3")
	)
	(via
		(at 168.148 -209.9564)
		(size 0.508)
		(drill 0.254)
		(layers "F.Cu" "B.Cu")
		(net "P3V3")
	)
	(via
		(at 25.2222 -363.5248)
		(size 0.508)
		(drill 0.254)
		(layers "F.Cu" "B.Cu")
		(net "P3V3")
	)
	(via
		(at 29.972 -373.38)
		(size 0.508)
		(drill 0.254)
		(layers "F.Cu" "B.Cu")
		(net "P3V3")
	)
	(via
		(at 243.586 -425.45)
		(size 0.508)
		(drill 0.254)
		(layers "F.Cu" "B.Cu")
		(net "P3V3")
	)
	(via
		(at 20.358862 -58.482484)
		(size 0.508)
		(drill 0.254)
		(layers "F.Cu" "B.Cu")
		(net "P3V3")
	)
	(via
		(at 24.384 -236.22)
		(size 0.508)
		(drill 0.254)
		(layers "F.Cu" "B.Cu")
		(net "P3V3")
	)
	(via
		(at 31.9278 -13.8176)
		(size 0.508)
		(drill 0.254)
		(layers "F.Cu" "B.Cu")
		(net "P3V3")
	)
	(via
		(at 56.007 -17.145)
		(size 0.508)
		(drill 0.254)
		(layers "F.Cu" "B.Cu")
		(net "P3V3")
	)
	(via
		(at 77.0128 -107.3404)
		(size 0.508)
		(drill 0.254)
		(layers "F.Cu" "B.Cu")
		(net "P3V3")
	)
	(via
		(at 212.0265 -463.11439)
		(size 0.508)
		(drill 0.254)
		(layers "F.Cu" "B.Cu")
		(net "P3V3")
	)
	(via
		(at 72.136 -155.448)
		(size 0.508)
		(drill 0.254)
		(layers "F.Cu" "B.Cu")
		(net "P3V3")
	)
	(via
		(at 108.077 -435.2925)
		(size 0.508)
		(drill 0.254)
		(layers "F.Cu" "B.Cu")
		(net "P3V3")
	)
	(via
		(at 228.966014 -165.189916)
		(size 0.508)
		(drill 0.254)
		(layers "F.Cu" "B.Cu")
		(net "P3V3")
	)
	(via
		(at 222.631 -164.592)
		(size 0.508)
		(drill 0.254)
		(layers "F.Cu" "B.Cu")
		(net "P3V3")
	)
	(via
		(at 29.03093 -85.9282)
		(size 0.508)
		(drill 0.254)
		(layers "F.Cu" "B.Cu")
		(net "P3V3")
	)
	(via
		(at 43.307 -121.539)
		(size 0.508)
		(drill 0.254)
		(layers "F.Cu" "B.Cu")
		(net "P3V3")
	)
	(via
		(at 74.0664 -367.792)
		(size 0.508)
		(drill 0.254)
		(layers "F.Cu" "B.Cu")
		(net "P3V3")
	)
	(via
		(at 79.1464 -367.792)
		(size 0.508)
		(drill 0.254)
		(layers "F.Cu" "B.Cu")
		(net "P3V3")
	)
	(via
		(at 206.756 -414.147)
		(size 0.508)
		(drill 0.254)
		(layers "F.Cu" "B.Cu")
		(net "P3V3")
	)
	(via
		(at 83.312 -348.996)
		(size 0.508)
		(drill 0.254)
		(layers "F.Cu" "B.Cu")
		(net "P3V3")
	)
	(via
		(at 82.931 -356.9716)
		(size 0.508)
		(drill 0.254)
		(layers "F.Cu" "B.Cu")
		(net "P3V3")
	)
	(via
		(at 25.472898 -463.78241)
		(size 0.508)
		(drill 0.254)
		(layers "F.Cu" "B.Cu")
		(net "P3V3")
	)
	(via
		(at 56.515 -451.1548)
		(size 0.508)
		(drill 0.254)
		(layers "F.Cu" "B.Cu")
		(net "P3V3")
	)
	(via
		(at 50.2666 -454.787)
		(size 0.508)
		(drill 0.254)
		(layers "F.Cu" "B.Cu")
		(net "P3V3")
	)
	(via
		(at 74.549 -187.452)
		(size 0.508)
		(drill 0.254)
		(layers "F.Cu" "B.Cu")
		(net "P3V3")
	)
	(via
		(at 39.497 -145.796)
		(size 0.508)
		(drill 0.254)
		(layers "F.Cu" "B.Cu")
		(net "P3V3")
	)
	(via
		(at 206.5909 -93.7895)
		(size 0.508)
		(drill 0.254)
		(layers "F.Cu" "B.Cu")
		(net "P3V3")
	)
	(via
		(at 15.992348 -361.3404)
		(size 0.508)
		(drill 0.254)
		(layers "F.Cu" "B.Cu")
		(net "P3V3")
	)
	(via
		(at 139.105386 -397.773398)
		(size 0.508)
		(drill 0.254)
		(layers "F.Cu" "B.Cu")
		(net "P3V3")
	)
	(via
		(at 29.9466 -291.8968)
		(size 0.508)
		(drill 0.254)
		(layers "F.Cu" "B.Cu")
		(net "P3V3")
	)
	(via
		(at 20.358862 -367.482374)
		(size 0.508)
		(drill 0.254)
		(layers "F.Cu" "B.Cu")
		(net "P3V3")
	)
	(via
		(at 108.173266 -437.317896)
		(size 0.508)
		(drill 0.254)
		(layers "F.Cu" "B.Cu")
		(net "P3V3")
	)
	(via
		(at 90.489278 -87.420704)
		(size 0.508)
		(drill 0.254)
		(layers "F.Cu" "B.Cu")
		(net "P3V3")
	)
	(via
		(at 50.5206 -247.396)
		(size 0.508)
		(drill 0.254)
		(layers "F.Cu" "B.Cu")
		(net "P3V3")
	)
	(via
		(at 80.645 -141.986)
		(size 0.508)
		(drill 0.254)
		(layers "F.Cu" "B.Cu")
		(net "P3V3")
	)
	(via
		(at 229.489 -413.385)
		(size 0.7112)
		(drill 0.3556)
		(layers "F.Cu" "B.Cu")
		(net "P3V3")
	)
	(via
		(at 91.6305 -31.496)
		(size 0.508)
		(drill 0.254)
		(layers "F.Cu" "B.Cu")
		(net "P3V3")
	)
	(via
		(at 27.6987 -391.3124)
		(size 0.508)
		(drill 0.254)
		(layers "F.Cu" "B.Cu")
		(net "P3V3")
	)
	(via
		(at 205.359 -411.861)
		(size 0.508)
		(drill 0.254)
		(layers "F.Cu" "B.Cu")
		(net "P3V3")
	)
	(via
		(at 75.184 -155.448)
		(size 0.508)
		(drill 0.254)
		(layers "F.Cu" "B.Cu")
		(net "P3V3")
	)
	(via
		(at 83.185 -347.599)
		(size 0.508)
		(drill 0.254)
		(layers "F.Cu" "B.Cu")
		(net "P3V3")
	)
	(via
		(at 43.96613 -268.189964)
		(size 0.508)
		(drill 0.254)
		(layers "F.Cu" "B.Cu")
		(net "P3V3")
	)
	(via
		(at 99.506532 -291.001704)
		(size 0.508)
		(drill 0.254)
		(layers "F.Cu" "B.Cu")
		(net "P3V3")
	)
	(via
		(at 97.028 -24.892)
		(size 0.508)
		(drill 0.254)
		(layers "F.Cu" "B.Cu")
		(net "P3V3")
	)
	(via
		(at 208.026 -467.106)
		(size 0.508)
		(drill 0.254)
		(layers "F.Cu" "B.Cu")
		(net "P3V3")
	)
	(via
		(at 76.835 -310.896)
		(size 0.508)
		(drill 0.254)
		(layers "F.Cu" "B.Cu")
		(net "P3V3")
	)
	(via
		(at 31.8262 -111.252)
		(size 0.508)
		(drill 0.254)
		(layers "F.Cu" "B.Cu")
		(net "P3V3")
	)
	(via
		(at 69.469 -149.606)
		(size 0.508)
		(drill 0.254)
		(layers "F.Cu" "B.Cu")
		(net "P3V3")
	)
	(via
		(at 102.997 -70.485)
		(size 0.508)
		(drill 0.254)
		(layers "F.Cu" "B.Cu")
		(net "P3V3")
	)
	(via
		(at 37.592 -370.332)
		(size 0.508)
		(drill 0.254)
		(layers "F.Cu" "B.Cu")
		(net "P3V3")
	)
	(via
		(at 227.494338 -346.389452)
		(size 0.508)
		(drill 0.254)
		(layers "F.Cu" "B.Cu")
		(net "P3V3")
	)
	(via
		(at 48.34382 -232.03662)
		(size 0.508)
		(drill 0.254)
		(layers "F.Cu" "B.Cu")
		(net "P3V3")
	)
	(via
		(at 77.5208 -229.362)
		(size 0.508)
		(drill 0.254)
		(layers "F.Cu" "B.Cu")
		(net "P3V3")
	)
	(via
		(at 18.034 -31.809944)
		(size 0.508)
		(drill 0.254)
		(layers "F.Cu" "B.Cu")
		(net "P3V3")
	)
	(via
		(at 108.077 -308.6735)
		(size 0.508)
		(drill 0.254)
		(layers "F.Cu" "B.Cu")
		(net "P3V3")
	)
	(via
		(at 73.0504 -367.792)
		(size 0.508)
		(drill 0.254)
		(layers "F.Cu" "B.Cu")
		(net "P3V3")
	)
	(via
		(at 98.372168 -225.017838)
		(size 0.508)
		(drill 0.254)
		(layers "F.Cu" "B.Cu")
		(net "P3V3")
	)
	(via
		(at 23.123144 -466.161628)
		(size 0.508)
		(drill 0.254)
		(layers "F.Cu" "B.Cu")
		(net "P3V3")
	)
	(via
		(at 217.852752 -346.579952)
		(size 0.508)
		(drill 0.254)
		(layers "F.Cu" "B.Cu")
		(net "P3V3")
	)
	(via
		(at 74.93 -316.23)
		(size 0.508)
		(drill 0.254)
		(layers "F.Cu" "B.Cu")
		(net "P3V3")
	)
	(via
		(at 168.91 -237.998)
		(size 0.508)
		(drill 0.254)
		(layers "F.Cu" "B.Cu")
		(net "P3V3")
	)
	(via
		(at 46.863 -140.589)
		(size 0.508)
		(drill 0.254)
		(layers "F.Cu" "B.Cu")
		(net "P3V3")
	)
	(via
		(at 222.631 -63.754)
		(size 0.508)
		(drill 0.254)
		(layers "F.Cu" "B.Cu")
		(net "P3V3")
	)
	(via
		(at 164.1348 -397.6878)
		(size 0.508)
		(drill 0.254)
		(layers "F.Cu" "B.Cu")
		(net "P3V3")
	)
	(via
		(at 206.502 -402.7805)
		(size 0.508)
		(drill 0.254)
		(layers "F.Cu" "B.Cu")
		(net "P3V3")
	)
	(via
		(at 81.3054 -149.1488)
		(size 0.508)
		(drill 0.254)
		(layers "F.Cu" "B.Cu")
		(net "P3V3")
	)
	(via
		(at 101.981 -104.2035)
		(size 0.508)
		(drill 0.254)
		(layers "F.Cu" "B.Cu")
		(net "P3V3")
	)
	(via
		(at 165.5318 -397.6878)
		(size 0.508)
		(drill 0.254)
		(layers "F.Cu" "B.Cu")
		(net "P3V3")
	)
	(via
		(at 61.87186 -451.994778)
		(size 0.7112)
		(drill 0.3556)
		(layers "F.Cu" "B.Cu")
		(net "P3V3")
	)
	(via
		(at 29.95803 -188.9252)
		(size 0.508)
		(drill 0.254)
		(layers "F.Cu" "B.Cu")
		(net "P3V3")
	)
	(via
		(at 97.474278 -290.99637)
		(size 0.508)
		(drill 0.254)
		(layers "F.Cu" "B.Cu")
		(net "P3V3")
	)
	(via
		(at 217.836242 -243.580158)
		(size 0.508)
		(drill 0.254)
		(layers "F.Cu" "B.Cu")
		(net "P3V3")
	)
	(via
		(at 227.468938 -140.38961)
		(size 0.508)
		(drill 0.254)
		(layers "F.Cu" "B.Cu")
		(net "P3V3")
	)
	(via
		(at 87.31758 -225.017838)
		(size 0.508)
		(drill 0.254)
		(layers "F.Cu" "B.Cu")
		(net "P3V3")
	)
	(via
		(at 103.7082 -314.325)
		(size 0.508)
		(drill 0.254)
		(layers "F.Cu" "B.Cu")
		(net "P3V3")
	)
	(via
		(at 49.5935 -146.4818)
		(size 0.508)
		(drill 0.254)
		(layers "F.Cu" "B.Cu")
		(net "P3V3")
	)
	(via
		(at 235.3056 -452.628)
		(size 0.508)
		(drill 0.254)
		(layers "F.Cu" "B.Cu")
		(net "P3V3")
	)
	(via
		(at 88.457024 -87.404956)
		(size 0.508)
		(drill 0.254)
		(layers "F.Cu" "B.Cu")
		(net "P3V3")
	)
	(via
		(at 82.931 -362.1278)
		(size 0.508)
		(drill 0.254)
		(layers "F.Cu" "B.Cu")
		(net "P3V3")
	)
	(via
		(at 214.5538 -494.0808)
		(size 0.508)
		(drill 0.254)
		(layers "F.Cu" "B.Cu")
		(net "P3V3")
	)
	(via
		(at 24.384 -339.09)
		(size 0.508)
		(drill 0.254)
		(layers "F.Cu" "B.Cu")
		(net "P3V3")
	)
	(via
		(at 78.105 -352.806)
		(size 0.508)
		(drill 0.254)
		(layers "F.Cu" "B.Cu")
		(net "P3V3")
	)
	(via
		(at 207.391 -43.434)
		(size 0.508)
		(drill 0.254)
		(layers "F.Cu" "B.Cu")
		(net "P3V3")
	)
	(via
		(at 74.9808 -229.362)
		(size 0.508)
		(drill 0.254)
		(layers "F.Cu" "B.Cu")
		(net "P3V3")
	)
	(via
		(at 69.469 -358.521)
		(size 0.508)
		(drill 0.254)
		(layers "F.Cu" "B.Cu")
		(net "P3V3")
	)
	(via
		(at 224.924874 -41.860216)
		(size 0.508)
		(drill 0.254)
		(layers "F.Cu" "B.Cu")
		(net "P3V3")
	)
	(via
		(at 228.966014 -268.189964)
		(size 0.508)
		(drill 0.254)
		(layers "F.Cu" "B.Cu")
		(net "P3V3")
	)
	(via
		(at 52.8701 -8.1915)
		(size 0.508)
		(drill 0.254)
		(layers "F.Cu" "B.Cu")
		(net "P3V3")
	)
	(via
		(at 185.0898 -491.0074)
		(size 0.508)
		(drill 0.254)
		(layers "F.Cu" "B.Cu")
		(net "P3V3")
	)
	(via
		(at 72.3646 -351.409)
		(size 0.508)
		(drill 0.254)
		(layers "F.Cu" "B.Cu")
		(net "P3V3")
	)
	(via
		(at 162.4838 -396.5448)
		(size 0.508)
		(drill 0.254)
		(layers "F.Cu" "B.Cu")
		(net "P3V3")
	)
	(via
		(at 214.376 -48.26)
		(size 0.508)
		(drill 0.254)
		(layers "F.Cu" "B.Cu")
		(net "P3V3")
	)
	(via
		(at 32.8041 -318.0207)
		(size 0.508)
		(drill 0.254)
		(layers "F.Cu" "B.Cu")
		(net "P3V3")
	)
	(via
		(at 235.2802 -350.770952)
		(size 0.508)
		(drill 0.254)
		(layers "F.Cu" "B.Cu")
		(net "P3V3")
	)
	(via
		(at 168.148 -300.609)
		(size 0.508)
		(drill 0.254)
		(layers "F.Cu" "B.Cu")
		(net "P3V3")
	)
	(via
		(at 69.469 -143.51)
		(size 0.508)
		(drill 0.254)
		(layers "F.Cu" "B.Cu")
		(net "P3V3")
	)
	(via
		(at 18.034 -443.810136)
		(size 0.508)
		(drill 0.254)
		(layers "F.Cu" "B.Cu")
		(net "P3V3")
	)
	(via
		(at 49.1236 -349.885)
		(size 0.508)
		(drill 0.254)
		(layers "F.Cu" "B.Cu")
		(net "P3V3")
	)
	(via
		(at 98.361246 -115.794028)
		(size 0.508)
		(drill 0.254)
		(layers "F.Cu" "B.Cu")
		(net "P3V3")
	)
	(via
		(at 38.1508 -413.512)
		(size 0.508)
		(drill 0.254)
		(layers "F.Cu" "B.Cu")
		(net "P3V3")
	)
	(via
		(at 77.1144 -367.792)
		(size 0.508)
		(drill 0.254)
		(layers "F.Cu" "B.Cu")
		(net "P3V3")
	)
	(via
		(at 37.592 -473.456)
		(size 0.508)
		(drill 0.254)
		(layers "F.Cu" "B.Cu")
		(net "P3V3")
	)
	(via
		(at 102.616 -213.487)
		(size 0.508)
		(drill 0.254)
		(layers "F.Cu" "B.Cu")
		(net "P3V3")
	)
	(via
		(at 214.5284 -291.7698)
		(size 0.508)
		(drill 0.254)
		(layers "F.Cu" "B.Cu")
		(net "P3V3")
	)
	(via
		(at 89.339166 -115.77574)
		(size 0.508)
		(drill 0.254)
		(layers "F.Cu" "B.Cu")
		(net "P3V3")
	)
	(via
		(at 52.451 -134.9375)
		(size 0.508)
		(drill 0.254)
		(layers "F.Cu" "B.Cu")
		(net "P3V3")
	)
	(via
		(at 207.01 -453.39)
		(size 0.508)
		(drill 0.254)
		(layers "F.Cu" "B.Cu")
		(net "P3V3")
	)
	(via
		(at 85.344 -144.92732)
		(size 0.508)
		(drill 0.254)
		(layers "F.Cu" "B.Cu")
		(net "P3V3")
	)
	(via
		(at 69.469 -148.59)
		(size 0.508)
		(drill 0.254)
		(layers "F.Cu" "B.Cu")
		(net "P3V3")
	)
	(via
		(at 74.803 -103.632)
		(size 0.508)
		(drill 0.254)
		(layers "F.Cu" "B.Cu")
		(net "P3V3")
	)
	(via
		(at 222.631 -370.586)
		(size 0.508)
		(drill 0.254)
		(layers "F.Cu" "B.Cu")
		(net "P3V3")
	)
	(via
		(at 108.077 -310.7055)
		(size 0.508)
		(drill 0.254)
		(layers "F.Cu" "B.Cu")
		(net "P3V3")
	)
	(via
		(at 90.932 -16.256)
		(size 0.508)
		(drill 0.254)
		(layers "F.Cu" "B.Cu")
		(net "P3V3")
	)
	(via
		(at 54.483 -370.586)
		(size 0.508)
		(drill 0.254)
		(layers "F.Cu" "B.Cu")
		(net "P3V3")
	)
	(via
		(at 18.034 -340.810088)
		(size 0.508)
		(drill 0.254)
		(layers "F.Cu" "B.Cu")
		(net "P3V3")
	)
	(via
		(at 235.292138 -40.64)
		(size 0.508)
		(drill 0.254)
		(layers "F.Cu" "B.Cu")
		(net "P3V3")
	)
	(via
		(at 72.009 -437.388)
		(size 0.508)
		(drill 0.254)
		(layers "F.Cu" "B.Cu")
		(net "P3V3")
	)
	(via
		(at 194.437 -423.291)
		(size 0.508)
		(drill 0.254)
		(layers "F.Cu" "B.Cu")
		(net "P3V3")
	)
	(via
		(at 15.856204 -154.36596)
		(size 0.508)
		(drill 0.254)
		(layers "F.Cu" "B.Cu")
		(net "P3V3")
	)
	(via
		(at 54.5338 -199.1868)
		(size 0.508)
		(drill 0.254)
		(layers "F.Cu" "B.Cu")
		(net "P3V3")
	)
	(via
		(at 69.469 -356.489)
		(size 0.508)
		(drill 0.254)
		(layers "F.Cu" "B.Cu")
		(net "P3V3")
	)
	(via
		(at 192.786 -422.148)
		(size 0.508)
		(drill 0.254)
		(layers "F.Cu" "B.Cu")
		(net "P3V3")
	)
	(via
		(at 104.2797 -216.027)
		(size 0.508)
		(drill 0.254)
		(layers "F.Cu" "B.Cu")
		(net "P3V3")
	)
	(via
		(at 38.241478 -36.284916)
		(size 0.508)
		(drill 0.254)
		(layers "F.Cu" "B.Cu")
		(net "P3V3")
	)
	(via
		(at 76.5556 -355.981)
		(size 0.508)
		(drill 0.254)
		(layers "F.Cu" "B.Cu")
		(net "P3V3")
	)
	(via
		(at 96.331532 -115.796568)
		(size 0.508)
		(drill 0.254)
		(layers "F.Cu" "B.Cu")
		(net "P3V3")
	)
	(via
		(at 205.359 -413.004)
		(size 0.508)
		(drill 0.254)
		(layers "F.Cu" "B.Cu")
		(net "P3V3")
	)
	(via
		(at 39.9288 -104.648)
		(size 0.508)
		(drill 0.254)
		(layers "F.Cu" "B.Cu")
		(net "P3V3")
	)
	(via
		(at 87.31504 -319.374774)
		(size 0.508)
		(drill 0.254)
		(layers "F.Cu" "B.Cu")
		(net "P3V3")
	)
	(via
		(at 35.59175 -350.8502)
		(size 0.508)
		(drill 0.254)
		(layers "F.Cu" "B.Cu")
		(net "P3V3")
	)
	(via
		(at 69.469 -361.569)
		(size 0.508)
		(drill 0.254)
		(layers "F.Cu" "B.Cu")
		(net "P3V3")
	)
	(via
		(at 235.325158 -247.771158)
		(size 0.508)
		(drill 0.254)
		(layers "F.Cu" "B.Cu")
		(net "P3V3")
	)
	(via
		(at 43.96613 -62.189868)
		(size 0.508)
		(drill 0.254)
		(layers "F.Cu" "B.Cu")
		(net "P3V3")
	)
	(via
		(at 235.2802 -349.631)
		(size 0.508)
		(drill 0.254)
		(layers "F.Cu" "B.Cu")
		(net "P3V3")
	)
	(via
		(at 97.4725 -87.503)
		(size 0.508)
		(drill 0.254)
		(layers "F.Cu" "B.Cu")
		(net "P3V3")
	)
	(via
		(at 28.540964 -478.53219)
		(size 0.508)
		(drill 0.254)
		(layers "F.Cu" "B.Cu")
		(net "P3V3")
	)
	(via
		(at 32.2326 -420.2938)
		(size 0.508)
		(drill 0.254)
		(layers "F.Cu" "B.Cu")
		(net "P3V3")
	)
	(via
		(at 82.931 -360.045)
		(size 0.508)
		(drill 0.254)
		(layers "F.Cu" "B.Cu")
		(net "P3V3")
	)
	(via
		(at 228.966014 -371.190012)
		(size 0.508)
		(drill 0.254)
		(layers "F.Cu" "B.Cu")
		(net "P3V3")
	)
	(via
		(at 194.437 -422.148)
		(size 0.508)
		(drill 0.254)
		(layers "F.Cu" "B.Cu")
		(net "P3V3")
	)
	(via
		(at 40.91813 -249.077988)
		(size 0.508)
		(drill 0.254)
		(layers "F.Cu" "B.Cu")
		(net "P3V3")
	)
	(via
		(at 20.358862 -161.482532)
		(size 0.508)
		(drill 0.254)
		(layers "F.Cu" "B.Cu")
		(net "P3V3")
	)
	(via
		(at 24.511 -256.8448)
		(size 0.508)
		(drill 0.254)
		(layers "F.Cu" "B.Cu")
		(net "P3V3")
	)
	(via
		(at 198.755 -164.592)
		(size 0.508)
		(drill 0.254)
		(layers "F.Cu" "B.Cu")
		(net "P3V3")
	)
	(via
		(at 39.8272 -207.264)
		(size 0.508)
		(drill 0.254)
		(layers "F.Cu" "B.Cu")
		(net "P3V3")
	)
	(via
		(at 74.422 -97.79)
		(size 0.508)
		(drill 0.254)
		(layers "F.Cu" "B.Cu")
		(net "P3V3")
	)
	(via
		(at 93.726 -74.676)
		(size 0.508)
		(drill 0.254)
		(layers "F.Cu" "B.Cu")
		(net "P3V3")
	)
	(via
		(at 227.468938 -449.3895)
		(size 0.508)
		(drill 0.254)
		(layers "F.Cu" "B.Cu")
		(net "P3V3")
	)
	(via
		(at 18.034 -134.809992)
		(size 0.508)
		(drill 0.254)
		(layers "F.Cu" "B.Cu")
		(net "P3V3")
	)
	(via
		(at 50.2666 -453.644)
		(size 0.508)
		(drill 0.254)
		(layers "F.Cu" "B.Cu")
		(net "P3V3")
	)
	(via
		(at 75.438 -445.008)
		(size 0.508)
		(drill 0.254)
		(layers "F.Cu" "B.Cu")
		(net "P3V3")
	)
	(via
		(at 43.96613 -165.189916)
		(size 0.508)
		(drill 0.254)
		(layers "F.Cu" "B.Cu")
		(net "P3V3")
	)
	(via
		(at 214.9348 -188.7982)
		(size 0.508)
		(drill 0.254)
		(layers "F.Cu" "B.Cu")
		(net "P3V3")
	)
	(via
		(at 84.455 -150.622)
		(size 0.508)
		(drill 0.254)
		(layers "F.Cu" "B.Cu")
		(net "P3V3")
	)
	(via
		(at 80.137 -352.806)
		(size 0.508)
		(drill 0.254)
		(layers "F.Cu" "B.Cu")
		(net "P3V3")
	)
	(via
		(at 102.997 -302.768)
		(size 0.508)
		(drill 0.254)
		(layers "F.Cu" "B.Cu")
		(net "P3V3")
	)
	(via
		(at 235.325158 -246.634)
		(size 0.508)
		(drill 0.254)
		(layers "F.Cu" "B.Cu")
		(net "P3V3")
	)
	(via
		(at 21.698458 -60.88761)
		(size 0.508)
		(drill 0.254)
		(layers "F.Cu" "B.Cu")
		(net "P3V3")
	)
	(via
		(at 43.96613 -474.19006)
		(size 0.508)
		(drill 0.254)
		(layers "F.Cu" "B.Cu")
		(net "P3V3")
	)
	(via
		(at 224.480374 -246.387874)
		(size 0.508)
		(drill 0.254)
		(layers "F.Cu" "B.Cu")
		(net "P3V3")
	)
	(via
		(at 37.592 -61.341)
		(size 0.508)
		(drill 0.254)
		(layers "F.Cu" "B.Cu")
		(net "P3V3")
	)
	(via
		(at 217.86469 -140.58011)
		(size 0.508)
		(drill 0.254)
		(layers "F.Cu" "B.Cu")
		(net "P3V3")
	)
	(via
		(at 224.480374 -143.387826)
		(size 0.508)
		(drill 0.254)
		(layers "F.Cu" "B.Cu")
		(net "P3V3")
	)
	(via
		(at 67.437 -437.388)
		(size 0.508)
		(drill 0.254)
		(layers "F.Cu" "B.Cu")
		(net "P3V3")
	)
	(via
		(at 195.834 -422.148)
		(size 0.508)
		(drill 0.254)
		(layers "F.Cu" "B.Cu")
		(net "P3V3")
	)
	(via
		(at 243.586 -414.274)
		(size 0.508)
		(drill 0.254)
		(layers "F.Cu" "B.Cu")
		(net "P3V3")
	)
	(via
		(at 168.021 -165.227)
		(size 0.508)
		(drill 0.254)
		(layers "F.Cu" "B.Cu")
		(net "P3V3")
	)
	(segment
		(start 222.631 -164.592)
		(end 228.368098 -164.592)
		(width 0.508)
		(layer "B.Cu")
		(net "P3V3")
	)
	(segment
		(start 25.472898 -463.78241)
		(end 25.472898 -464.816698)
		(width 1.016)
		(layer "B.Cu")
		(net "P3V3")
	)
	(segment
		(start 22.805898 -465.04987)
		(end 19.598386 -461.842358)
		(width 1.016)
		(layer "B.Cu")
		(net "P3V3")
	)
	(segment
		(start 207.01 -454.66)
		(end 207.01 -453.39)
		(width 1.016)
		(layer "B.Cu")
		(net "P3V3")
	)
	(segment
		(start 212.0265 -459.6765)
		(end 207.01 -454.66)
		(width 1.016)
		(layer "B.Cu")
		(net "P3V3")
	)
	(segment
		(start 23.123144 -466.018118)
		(end 22.805898 -465.700872)
		(width 1.016)
		(layer "B.Cu")
		(net "P3V3")
	)
	(segment
		(start 20.358862 -365.706914)
		(end 15.992348 -361.3404)
		(width 1.016)
		(layer "B.Cu")
		(net "P3V3")
	)
	(segment
		(start 210.840574 -464.300316)
		(end 210.831684 -464.300316)
		(width 1.016)
		(layer "B.Cu")
		(net "P3V3")
	)
	(segment
		(start 228.36505 -267.589)
		(end 222.631 -267.589)
		(width 0.508)
		(layer "B.Cu")
		(net "P3V3")
	)
	(segment
		(start 23.123144 -466.161628)
		(end 23.123144 -466.018118)
		(width 1.016)
		(layer "B.Cu")
		(net "P3V3")
	)
	(segment
		(start 18.22069 -468.05469)
		(end 18.22069 -467.759034)
		(width 1.016)
		(layer "B.Cu")
		(net "P3V3")
	)
	(segment
		(start 50.682652 -5.673852)
		(end 52.8701 -7.8613)
		(width 1.016)
		(layer "B.Cu")
		(net "P3V3")
	)
	(segment
		(start 35.2552 -13.8176)
		(end 37.5412 -11.5316)
		(width 1.016)
		(layer "B.Cu")
		(net "P3V3")
	)
	(segment
		(start 231.267 -440.5884)
		(end 231.267 -440.944)
		(width 1.016)
		(layer "B.Cu")
		(net "P3V3")
	)
	(segment
		(start 18.319242 -467.660482)
		(end 18.873724 -467.106)
		(width 1.016)
		(layer "B.Cu")
		(net "P3V3")
	)
	(segment
		(start 229.489 -442.722)
		(end 227.203 -442.722)
		(width 1.016)
		(layer "B.Cu")
		(net "P3V3")
	)
	(segment
		(start 185.0898 -491.0074)
		(end 185.0898 -490.0422)
		(width 1.016)
		(layer "B.Cu")
		(net "P3V3")
	)
	(segment
		(start 36.449 -415.2138)
		(end 36.449 -417.1442)
		(width 1.016)
		(layer "B.Cu")
		(net "P3V3")
	)
	(segment
		(start 218.059 -451.866)
		(end 218.059 -457.08189)
		(width 1.016)
		(layer "B.Cu")
		(net "P3V3")
	)
	(segment
		(start 15.494 -449.5546)
		(end 17.8816 -451.9422)
		(width 1.016)
		(layer "B.Cu")
		(net "P3V3")
	)
	(segment
		(start 52.8701 -7.8613)
		(end 52.8701 -8.1915)
		(width 1.016)
		(layer "B.Cu")
		(net "P3V3")
	)
	(segment
		(start 19.7866 -469.6206)
		(end 18.22069 -468.05469)
		(width 1.016)
		(layer "B.Cu")
		(net "P3V3")
	)
	(segment
		(start 37.5412 -9.455912)
		(end 41.32326 -5.673852)
		(width 1.016)
		(layer "B.Cu")
		(net "P3V3")
	)
	(segment
		(start 185.0898 -490.0422)
		(end 208.026 -467.106)
		(width 1.016)
		(layer "B.Cu")
		(net "P3V3")
	)
	(segment
		(start 17.653 -442.595)
		(end 16.51 -442.595)
		(width 1.016)
		(layer "B.Cu")
		(net "P3V3")
	)
	(segment
		(start 36.449 -417.1442)
		(end 33.2994 -420.2938)
		(width 1.016)
		(layer "B.Cu")
		(net "P3V3")
	)
	(segment
		(start 227.203 -442.722)
		(end 218.059 -451.866)
		(width 1.016)
		(layer "B.Cu")
		(net "P3V3")
	)
	(segment
		(start 228.362002 -370.586)
		(end 228.966014 -371.190012)
		(width 0.508)
		(layer "B.Cu")
		(net "P3V3")
	)
	(segment
		(start 222.631 -370.586)
		(end 228.362002 -370.586)
		(width 0.508)
		(layer "B.Cu")
		(net "P3V3")
	)
	(segment
		(start 218.059 -457.08189)
		(end 212.0265 -463.11439)
		(width 1.016)
		(layer "B.Cu")
		(net "P3V3")
	)
	(segment
		(start 195.834 -442.214)
		(end 207.01 -453.39)
		(width 1.016)
		(layer "B.Cu")
		(net "P3V3")
	)
	(segment
		(start 22.805898 -465.700872)
		(end 22.805898 -465.04987)
		(width 1.016)
		(layer "B.Cu")
		(net "P3V3")
	)
	(segment
		(start 22.178772 -467.106)
		(end 23.123144 -466.161628)
		(width 1.016)
		(layer "B.Cu")
		(net "P3V3")
	)
	(segment
		(start 231.267 -440.944)
		(end 229.489 -442.722)
		(width 1.016)
		(layer "B.Cu")
		(net "P3V3")
	)
	(segment
		(start 17.8816 -451.9422)
		(end 20.2438 -451.9422)
		(width 1.016)
		(layer "B.Cu")
		(net "P3V3")
	)
	(segment
		(start 31.9278 -13.8176)
		(end 35.2552 -13.8176)
		(width 1.016)
		(layer "B.Cu")
		(net "P3V3")
	)
	(segment
		(start 222.504 -473.456)
		(end 228.231954 -473.456)
		(width 0.508)
		(layer "B.Cu")
		(net "P3V3")
	)
	(segment
		(start 20.358862 -367.482374)
		(end 20.358862 -365.706914)
		(width 1.016)
		(layer "B.Cu")
		(net "P3V3")
	)
	(segment
		(start 212.0265 -463.11439)
		(end 210.840574 -464.300316)
		(width 1.016)
		(layer "B.Cu")
		(net "P3V3")
	)
	(segment
		(start 33.2994 -420.2938)
		(end 32.2326 -420.2938)
		(width 1.016)
		(layer "B.Cu")
		(net "P3V3")
	)
	(segment
		(start 32.004 -372.364)
		(end 32.004 -375.793)
		(width 1.016)
		(layer "B.Cu")
		(net "P3V3")
	)
	(segment
		(start 228.231954 -473.456)
		(end 228.966014 -474.19006)
		(width 0.508)
		(layer "B.Cu")
		(net "P3V3")
	)
	(segment
		(start 210.831684 -464.300316)
		(end 208.026 -467.106)
		(width 1.016)
		(layer "B.Cu")
		(net "P3V3")
	)
	(segment
		(start 15.494 -443.611)
		(end 15.494 -449.5546)
		(width 1.016)
		(layer "B.Cu")
		(net "P3V3")
	)
	(segment
		(start 32.004 -375.793)
		(end 32.5755 -376.3645)
		(width 1.016)
		(layer "B.Cu")
		(net "P3V3")
	)
	(segment
		(start 16.51 -442.595)
		(end 15.494 -443.611)
		(width 1.016)
		(layer "B.Cu")
		(net "P3V3")
	)
	(segment
		(start 212.0265 -463.11439)
		(end 212.0265 -459.6765)
		(width 1.016)
		(layer "B.Cu")
		(net "P3V3")
	)
	(segment
		(start 25.472898 -464.816698)
		(end 25.4762 -464.82)
		(width 1.016)
		(layer "B.Cu")
		(net "P3V3")
	)
	(segment
		(start 41.32326 -5.673852)
		(end 50.682652 -5.673852)
		(width 1.016)
		(layer "B.Cu")
		(net "P3V3")
	)
	(segment
		(start 195.834 -423.291)
		(end 195.834 -442.214)
		(width 1.016)
		(layer "B.Cu")
		(net "P3V3")
	)
	(segment
		(start 20.2438 -451.9422)
		(end 26.4922 -458.1906)
		(width 1.016)
		(layer "B.Cu")
		(net "P3V3")
	)
	(segment
		(start 228.966014 -268.189964)
		(end 228.36505 -267.589)
		(width 0.508)
		(layer "B.Cu")
		(net "P3V3")
	)
	(segment
		(start 18.22069 -467.759034)
		(end 18.319242 -467.660482)
		(width 1.016)
		(layer "B.Cu")
		(net "P3V3")
	)
	(segment
		(start 228.368098 -164.592)
		(end 228.966014 -165.189916)
		(width 0.508)
		(layer "B.Cu")
		(net "P3V3")
	)
	(segment
		(start 20.4724 -469.6206)
		(end 19.7866 -469.6206)
		(width 1.016)
		(layer "B.Cu")
		(net "P3V3")
	)
	(segment
		(start 26.4922 -462.763108)
		(end 25.472898 -463.78241)
		(width 1.016)
		(layer "B.Cu")
		(net "P3V3")
	)
	(segment
		(start 38.1508 -413.512)
		(end 36.449 -415.2138)
		(width 1.016)
		(layer "B.Cu")
		(net "P3V3")
	)
	(segment
		(start 26.4922 -458.1906)
		(end 26.4922 -462.763108)
		(width 1.016)
		(layer "B.Cu")
		(net "P3V3")
	)
	(segment
		(start 37.5412 -11.5316)
		(end 37.5412 -9.455912)
		(width 1.016)
		(layer "B.Cu")
		(net "P3V3")
	)
	(segment
		(start 32.5755 -376.3645)
		(end 32.5755 -382.651)
		(width 1.016)
		(layer "B.Cu")
		(net "P3V3")
	)
	(segment
		(start 18.873724 -467.106)
		(end 22.178772 -467.106)
		(width 1.016)
		(layer "B.Cu")
		(net "P3V3")
	)
	(segment
		(start 228.431852 -346.389452)
		(end 231.6734 -349.631)
		(width 1.016)
		(layer "In2.Cu")
		(net "P3V3")
	)
	(segment
		(start 46.99 -471.551)
		(end 46.99 -472.51112)
		(width 1.016)
		(layer "In2.Cu")
		(net "P3V3")
	)
	(segment
		(start 232.1306 -143.637)
		(end 228.88321 -140.38961)
		(width 1.016)
		(layer "In2.Cu")
		(net "P3V3")
	)
	(segment
		(start 229.789482 -61.3664)
		(end 228.966014 -62.189868)
		(width 1.016)
		(layer "In2.Cu")
		(net "P3V3")
	)
	(segment
		(start 21.463 -470.6112)
		(end 21.463 -473.837)
		(width 1.016)
		(layer "In2.Cu")
		(net "P3V3")
	)
	(segment
		(start 205.867 -93.0656)
		(end 205.867 -90.9574)
		(width 1.016)
		(layer "In2.Cu")
		(net "P3V3")
	)
	(segment
		(start 222.640144 -452.387716)
		(end 220.353128 -450.1007)
		(width 1.016)
		(layer "In2.Cu")
		(net "P3V3")
	)
	(segment
		(start 217.86469 -140.58011)
		(end 219.19311 -140.58011)
		(width 1.016)
		(layer "In2.Cu")
		(net "P3V3")
	)
	(segment
		(start 225.0186 -473.456)
		(end 222.504 -473.456)
		(width 1.016)
		(layer "In2.Cu")
		(net "P3V3")
	)
	(segment
		(start 29.812234 -478.568766)
		(end 34.925 -473.456)
		(width 1.016)
		(layer "In2.Cu")
		(net "P3V3")
	)
	(segment
		(start 231.989884 -42.510964)
		(end 231.989884 -60.316364)
		(width 1.016)
		(layer "In2.Cu")
		(net "P3V3")
	)
	(segment
		(start 220.353128 -450.1007)
		(end 209.3087 -450.1007)
		(width 1.016)
		(layer "In2.Cu")
		(net "P3V3")
	)
	(segment
		(start 224.480374 -245.546626)
		(end 226.637342 -243.389658)
		(width 1.016)
		(layer "In2.Cu")
		(net "P3V3")
	)
	(segment
		(start 218.0336 -83.2866)
		(end 223.371156 -83.2866)
		(width 1.016)
		(layer "In2.Cu")
		(net "P3V3")
	)
	(segment
		(start 25.5016 -52.9082)
		(end 25.5016 -53.499004)
		(width 1.016)
		(layer "In2.Cu")
		(net "P3V3")
	)
	(segment
		(start 18.034 -31.809944)
		(end 19.617944 -30.226)
		(width 0.508)
		(layer "In2.Cu")
		(net "P3V3")
	)
	(segment
		(start 16.265398 -259.574792)
		(end 20.749006 -264.0584)
		(width 1.016)
		(layer "In2.Cu")
		(net "P3V3")
	)
	(segment
		(start 26.416 -443.9412)
		(end 26.2382 -444.119)
		(width 0.508)
		(layer "In2.Cu")
		(net "P3V3")
	)
	(segment
		(start 52.324 -466.217)
		(end 46.99 -471.551)
		(width 1.016)
		(layer "In2.Cu")
		(net "P3V3")
	)
	(segment
		(start 219.80906 -346.579952)
		(end 217.852752 -346.579952)
		(width 1.016)
		(layer "In2.Cu")
		(net "P3V3")
	)
	(segment
		(start 225.737166 -492.920782)
		(end 225.737166 -474.174566)
		(width 1.016)
		(layer "In2.Cu")
		(net "P3V3")
	)
	(segment
		(start 228.88321 -140.38961)
		(end 227.468938 -140.38961)
		(width 1.016)
		(layer "In2.Cu")
		(net "P3V3")
	)
	(segment
		(start 168.656 -164.592)
		(end 168.021 -165.227)
		(width 1.016)
		(layer "In2.Cu")
		(net "P3V3")
	)
	(segment
		(start 215.646 -85.6742)
		(end 218.0336 -83.2866)
		(width 1.016)
		(layer "In2.Cu")
		(net "P3V3")
	)
	(segment
		(start 232.8418 -452.628)
		(end 229.6033 -449.3895)
		(width 1.016)
		(layer "In2.Cu")
		(net "P3V3")
	)
	(segment
		(start 227.494338 -346.389452)
		(end 228.431852 -346.389452)
		(width 1.016)
		(layer "In2.Cu")
		(net "P3V3")
	)
	(segment
		(start 224.9424 -267.589)
		(end 225.7806 -268.4272)
		(width 1.016)
		(layer "In2.Cu")
		(net "P3V3")
	)
	(segment
		(start 220.643958 -246.387874)
		(end 217.836242 -243.580158)
		(width 1.016)
		(layer "In2.Cu")
		(net "P3V3")
	)
	(segment
		(start 46.99 -472.51112)
		(end 45.31106 -474.19006)
		(width 1.016)
		(layer "In2.Cu")
		(net "P3V3")
	)
	(segment
		(start 18.080736 -443.7634)
		(end 18.034 -443.810136)
		(width 0.508)
		(layer "In2.Cu")
		(net "P3V3")
	)
	(segment
		(start 214.7824 -394.7922)
		(end 214.7824 -395.1986)
		(width 1.016)
		(layer "In2.Cu")
		(net "P3V3")
	)
	(segment
		(start 243.586 -414.274)
		(end 243.586 -420.878)
		(width 0.508)
		(layer "In2.Cu")
		(net "P3V3")
	)
	(segment
		(start 214.5538 -494.0808)
		(end 224.577148 -494.0808)
		(width 1.016)
		(layer "In2.Cu")
		(net "P3V3")
	)
	(segment
		(start 224.480374 -451.966838)
		(end 227.057712 -449.3895)
		(width 1.016)
		(layer "In2.Cu")
		(net "P3V3")
	)
	(segment
		(start 18.034 -237.81004)
		(end 19.62404 -236.22)
		(width 0.508)
		(layer "In2.Cu")
		(net "P3V3")
	)
	(segment
		(start 21.698458 -60.88761)
		(end 21.698458 -59.478164)
		(width 1.016)
		(layer "In2.Cu")
		(net "P3V3")
	)
	(segment
		(start 20.4724 -469.6206)
		(end 21.463 -470.6112)
		(width 1.016)
		(layer "In2.Cu")
		(net "P3V3")
	)
	(segment
		(start 17.597882 -161.482532)
		(end 15.856204 -159.740854)
		(width 1.016)
		(layer "In2.Cu")
		(net "P3V3")
	)
	(segment
		(start 40.3352 -474.726)
		(end 43.43019 -474.726)
		(width 1.016)
		(layer "In2.Cu")
		(net "P3V3")
	)
	(segment
		(start 225.737166 -474.174566)
		(end 225.0186 -473.456)
		(width 1.016)
		(layer "In2.Cu")
		(net "P3V3")
	)
	(segment
		(start 20.749006 -264.0584)
		(end 21.892006 -262.9154)
		(width 1.016)
		(layer "In2.Cu")
		(net "P3V3")
	)
	(segment
		(start 222.099124 -348.870016)
		(end 219.80906 -346.579952)
		(width 1.016)
		(layer "In2.Cu")
		(net "P3V3")
	)
	(segment
		(start 45.31106 -474.19006)
		(end 43.96613 -474.19006)
		(width 1.016)
		(layer "In2.Cu")
		(net "P3V3")
	)
	(segment
		(start 226.020884 -80.636872)
		(end 226.020884 -65.134998)
		(width 1.016)
		(layer "In2.Cu")
		(net "P3V3")
	)
	(segment
		(start 37.592 -473.456)
		(end 39.0652 -473.456)
		(width 1.016)
		(layer "In2.Cu")
		(net "P3V3")
	)
	(segment
		(start 221.9452 -293.0652)
		(end 215.8238 -293.0652)
		(width 1.016)
		(layer "In2.Cu")
		(net "P3V3")
	)
	(segment
		(start 19.7485 -265.058906)
		(end 20.749006 -264.0584)
		(width 1.016)
		(layer "In2.Cu")
		(net "P3V3")
	)
	(segment
		(start 222.000826 -143.387826)
		(end 224.480374 -143.387826)
		(width 1.016)
		(layer "In2.Cu")
		(net "P3V3")
	)
	(segment
		(start 15.317724 -53.933852)
		(end 16.687546 -52.56403)
		(width 1.016)
		(layer "In2.Cu")
		(net "P3V3")
	)
	(segment
		(start 21.698458 -59.478164)
		(end 20.702778 -58.482484)
		(width 1.016)
		(layer "In2.Cu")
		(net "P3V3")
	)
	(segment
		(start 108.173266 -435.388766)
		(end 108.077 -435.2925)
		(width 1.016)
		(layer "In2.Cu")
		(net "P3V3")
	)
	(segment
		(start 235.3056 -452.628)
		(end 235.3056 -453.771)
		(width 1.016)
		(layer "In2.Cu")
		(net "P3V3")
	)
	(segment
		(start 222.631 -164.592)
		(end 224.8662 -164.592)
		(width 1.016)
		(layer "In2.Cu")
		(net "P3V3")
	)
	(segment
		(start 26.194766 -478.568766)
		(end 28.540964 -478.568766)
		(width 1.016)
		(layer "In2.Cu")
		(net "P3V3")
	)
	(segment
		(start 223.371156 -83.2866)
		(end 226.020884 -80.636872)
		(width 1.016)
		(layer "In2.Cu")
		(net "P3V3")
	)
	(segment
		(start 43.43019 -474.726)
		(end 43.96613 -474.19006)
		(width 1.016)
		(layer "In2.Cu")
		(net "P3V3")
	)
	(segment
		(start 15.856204 -159.740854)
		(end 15.856204 -154.36596)
		(width 1.016)
		(layer "In2.Cu")
		(net "P3V3")
	)
	(segment
		(start 227.494338 -346.389452)
		(end 225.81489 -346.389452)
		(width 1.016)
		(layer "In2.Cu")
		(net "P3V3")
	)
	(segment
		(start 235.325158 -246.634)
		(end 232.1052 -246.634)
		(width 1.016)
		(layer "In2.Cu")
		(net "P3V3")
	)
	(segment
		(start 225.7806 -289.2298)
		(end 221.9452 -293.0652)
		(width 1.016)
		(layer "In2.Cu")
		(net "P3V3")
	)
	(segment
		(start 207.01 -452.3994)
		(end 207.01 -453.39)
		(width 1.016)
		(layer "In2.Cu")
		(net "P3V3")
	)
	(segment
		(start 219.19311 -140.58011)
		(end 222.000826 -143.387826)
		(width 1.016)
		(layer "In2.Cu")
		(net "P3V3")
	)
	(segment
		(start 214.7824 -395.1986)
		(end 207.2005 -402.7805)
		(width 1.016)
		(layer "In2.Cu")
		(net "P3V3")
	)
	(segment
		(start 224.480374 -246.387874)
		(end 224.480374 -245.546626)
		(width 1.016)
		(layer "In2.Cu")
		(net "P3V3")
	)
	(segment
		(start 21.6154 -443.7634)
		(end 18.080736 -443.7634)
		(width 0.508)
		(layer "In2.Cu")
		(net "P3V3")
	)
	(segment
		(start 222.631 -267.589)
		(end 224.9424 -267.589)
		(width 1.016)
		(layer "In2.Cu")
		(net "P3V3")
	)
	(segment
		(start 20.358862 -161.482532)
		(end 20.639532 -161.482532)
		(width 1.016)
		(layer "In2.Cu")
		(net "P3V3")
	)
	(segment
		(start 214.3887 -85.6742)
		(end 215.646 -85.6742)
		(width 1.016)
		(layer "In2.Cu")
		(net "P3V3")
	)
	(segment
		(start 209.3087 -450.1007)
		(end 207.01 -452.3994)
		(width 1.016)
		(layer "In2.Cu")
		(net "P3V3")
	)
	(segment
		(start 39.8272 -207.9498)
		(end 33.782 -213.995)
		(width 1.016)
		(layer "In2.Cu")
		(net "P3V3")
	)
	(segment
		(start 235.29671 -144.77111)
		(end 235.29671 -143.637)
		(width 1.016)
		(layer "In2.Cu")
		(net "P3V3")
	)
	(segment
		(start 21.892006 -259.463794)
		(end 24.511 -256.8448)
		(width 1.016)
		(layer "In2.Cu")
		(net "P3V3")
	)
	(segment
		(start 230.939848 -61.3664)
		(end 229.789482 -61.3664)
		(width 1.016)
		(layer "In2.Cu")
		(net "P3V3")
	)
	(segment
		(start 21.646642 -162.489642)
		(end 21.646642 -163.887658)
		(width 1.016)
		(layer "In2.Cu")
		(net "P3V3")
	)
	(segment
		(start 224.337626 -347.866716)
		(end 224.337626 -348.870016)
		(width 1.016)
		(layer "In2.Cu")
		(net "P3V3")
	)
	(segment
		(start 224.337626 -348.870016)
		(end 222.099124 -348.870016)
		(width 1.016)
		(layer "In2.Cu")
		(net "P3V3")
	)
	(segment
		(start 224.480374 -143.387826)
		(end 224.480374 -142.422626)
		(width 1.016)
		(layer "In2.Cu")
		(net "P3V3")
	)
	(segment
		(start 20.358862 -157.796738)
		(end 24.3586 -153.797)
		(width 1.016)
		(layer "In2.Cu")
		(net "P3V3")
	)
	(segment
		(start 39.8272 -207.264)
		(end 39.8272 -207.9498)
		(width 1.016)
		(layer "In2.Cu")
		(net "P3V3")
	)
	(segment
		(start 16.687546 -52.56403)
		(end 25.15743 -52.56403)
		(width 1.016)
		(layer "In2.Cu")
		(net "P3V3")
	)
	(segment
		(start 205.867 -90.9574)
		(end 211.1502 -85.6742)
		(width 1.016)
		(layer "In2.Cu")
		(net "P3V3")
	)
	(segment
		(start 52.324 -454.152)
		(end 52.324 -466.217)
		(width 1.016)
		(layer "In2.Cu")
		(net "P3V3")
	)
	(segment
		(start 108.077 -435.2925)
		(end 108.077 -417.449)
		(width 1.016)
		(layer "In2.Cu")
		(net "P3V3")
	)
	(segment
		(start 28.540964 -478.53219)
		(end 28.540964 -478.568766)
		(width 1.016)
		(layer "In2.Cu")
		(net "P3V3")
	)
	(segment
		(start 33.782 -213.995)
		(end 32.2072 -213.995)
		(width 1.016)
		(layer "In2.Cu")
		(net "P3V3")
	)
	(segment
		(start 235.3056 -452.628)
		(end 232.8418 -452.628)
		(width 1.016)
		(layer "In2.Cu")
		(net "P3V3")
	)
	(segment
		(start 34.925 -473.456)
		(end 37.592 -473.456)
		(width 1.016)
		(layer "In2.Cu")
		(net "P3V3")
	)
	(segment
		(start 19.62404 -236.22)
		(end 24.384 -236.22)
		(width 0.508)
		(layer "In2.Cu")
		(net "P3V3")
	)
	(segment
		(start 20.358862 -161.482532)
		(end 20.358862 -157.796738)
		(width 1.016)
		(layer "In2.Cu")
		(net "P3V3")
	)
	(segment
		(start 206.5909 -93.7895)
		(end 205.867 -93.0656)
		(width 1.016)
		(layer "In2.Cu")
		(net "P3V3")
	)
	(segment
		(start 198.755 -164.592)
		(end 168.656 -164.592)
		(width 1.016)
		(layer "In2.Cu")
		(net "P3V3")
	)
	(segment
		(start 19.7485 -268.4145)
		(end 19.7485 -265.058906)
		(width 1.016)
		(layer "In2.Cu")
		(net "P3V3")
	)
	(segment
		(start 226.020884 -65.134998)
		(end 228.966014 -62.189868)
		(width 1.016)
		(layer "In2.Cu")
		(net "P3V3")
	)
	(segment
		(start 226.2124 -165.9382)
		(end 226.2124 -185.3184)
		(width 1.016)
		(layer "In2.Cu")
		(net "P3V3")
	)
	(segment
		(start 108.173266 -437.317896)
		(end 108.173266 -435.388766)
		(width 1.016)
		(layer "In2.Cu")
		(net "P3V3")
	)
	(segment
		(start 20.358862 -161.482532)
		(end 17.597882 -161.482532)
		(width 1.016)
		(layer "In2.Cu")
		(net "P3V3")
	)
	(segment
		(start 221.4372 -190.0936)
		(end 216.2302 -190.0936)
		(width 1.016)
		(layer "In2.Cu")
		(net "P3V3")
	)
	(segment
		(start 21.971 -444.119)
		(end 21.6154 -443.7634)
		(width 0.508)
		(layer "In2.Cu")
		(net "P3V3")
	)
	(segment
		(start 28.540964 -478.568766)
		(end 29.812234 -478.568766)
		(width 1.016)
		(layer "In2.Cu")
		(net "P3V3")
	)
	(segment
		(start 207.2005 -402.7805)
		(end 206.502 -402.7805)
		(width 1.016)
		(layer "In2.Cu")
		(net "P3V3")
	)
	(segment
		(start 211.1502 -85.6742)
		(end 214.3887 -85.6742)
		(width 1.016)
		(layer "In2.Cu")
		(net "P3V3")
	)
	(segment
		(start 235.2802 -349.631)
		(end 235.2802 -350.770952)
		(width 1.016)
		(layer "In2.Cu")
		(net "P3V3")
	)
	(segment
		(start 224.480374 -246.387874)
		(end 220.643958 -246.387874)
		(width 1.016)
		(layer "In2.Cu")
		(net "P3V3")
	)
	(segment
		(start 20.639532 -161.482532)
		(end 21.646642 -162.489642)
		(width 1.016)
		(layer "In2.Cu")
		(net "P3V3")
	)
	(segment
		(start 16.265398 -258.230116)
		(end 16.265398 -259.574792)
		(width 1.016)
		(layer "In2.Cu")
		(net "P3V3")
	)
	(segment
		(start 21.892006 -262.9154)
		(end 21.892006 -259.463794)
		(width 1.016)
		(layer "In2.Cu")
		(net "P3V3")
	)
	(segment
		(start 23.848568 -55.152036)
		(end 23.257764 -55.152036)
		(width 1.016)
		(layer "In2.Cu")
		(net "P3V3")
	)
	(segment
		(start 25.5016 -53.499004)
		(end 23.848568 -55.152036)
		(width 1.016)
		(layer "In2.Cu")
		(net "P3V3")
	)
	(segment
		(start 228.860858 -243.389658)
		(end 227.468938 -243.389658)
		(width 1.016)
		(layer "In2.Cu")
		(net "P3V3")
	)
	(segment
		(start 26.2382 -444.119)
		(end 21.971 -444.119)
		(width 0.508)
		(layer "In2.Cu")
		(net "P3V3")
	)
	(segment
		(start 227.057712 -449.3895)
		(end 227.468938 -449.3895)
		(width 1.016)
		(layer "In2.Cu")
		(net "P3V3")
	)
	(segment
		(start 229.6033 -449.3895)
		(end 227.468938 -449.3895)
		(width 1.016)
		(layer "In2.Cu")
		(net "P3V3")
	)
	(segment
		(start 21.463 -473.837)
		(end 26.194766 -478.568766)
		(width 1.016)
		(layer "In2.Cu")
		(net "P3V3")
	)
	(segment
		(start 19.747992 -133.096)
		(end 24.384 -133.096)
		(width 0.508)
		(layer "In2.Cu")
		(net "P3V3")
	)
	(segment
		(start 20.702778 -58.482484)
		(end 20.358862 -58.482484)
		(width 1.016)
		(layer "In2.Cu")
		(net "P3V3")
	)
	(segment
		(start 235.325158 -247.771158)
		(end 235.325158 -246.634)
		(width 1.016)
		(layer "In2.Cu")
		(net "P3V3")
	)
	(segment
		(start 226.2124 -185.3184)
		(end 221.4372 -190.0936)
		(width 1.016)
		(layer "In2.Cu")
		(net "P3V3")
	)
	(segment
		(start 224.8662 -164.592)
		(end 226.2124 -165.9382)
		(width 1.016)
		(layer "In2.Cu")
		(net "P3V3")
	)
	(segment
		(start 216.2302 -190.0936)
		(end 214.9348 -188.7982)
		(width 1.016)
		(layer "In2.Cu")
		(net "P3V3")
	)
	(segment
		(start 23.257764 -55.152036)
		(end 20.358862 -58.050938)
		(width 1.016)
		(layer "In2.Cu")
		(net "P3V3")
	)
	(segment
		(start 225.81489 -346.389452)
		(end 224.337626 -347.866716)
		(width 1.016)
		(layer "In2.Cu")
		(net "P3V3")
	)
	(segment
		(start 215.8238 -293.0652)
		(end 214.5284 -291.7698)
		(width 1.016)
		(layer "In2.Cu")
		(net "P3V3")
	)
	(segment
		(start 232.1052 -246.634)
		(end 228.860858 -243.389658)
		(width 1.016)
		(layer "In2.Cu")
		(net "P3V3")
	)
	(segment
		(start 226.637342 -243.389658)
		(end 227.468938 -243.389658)
		(width 1.016)
		(layer "In2.Cu")
		(net "P3V3")
	)
	(segment
		(start 231.6734 -349.631)
		(end 235.2802 -349.631)
		(width 1.016)
		(layer "In2.Cu")
		(net "P3V3")
	)
	(segment
		(start 224.577148 -494.0808)
		(end 225.737166 -492.920782)
		(width 1.016)
		(layer "In2.Cu")
		(net "P3V3")
	)
	(segment
		(start 231.989884 -60.316364)
		(end 230.939848 -61.3664)
		(width 1.016)
		(layer "In2.Cu")
		(net "P3V3")
	)
	(segment
		(start 25.15743 -52.56403)
		(end 25.5016 -52.9082)
		(width 1.016)
		(layer "In2.Cu")
		(net "P3V3")
	)
	(segment
		(start 235.29671 -143.637)
		(end 232.1306 -143.637)
		(width 1.016)
		(layer "In2.Cu")
		(net "P3V3")
	)
	(segment
		(start 224.480374 -142.422626)
		(end 226.51339 -140.38961)
		(width 1.016)
		(layer "In2.Cu")
		(net "P3V3")
	)
	(segment
		(start 225.7806 -268.4272)
		(end 225.7806 -289.2298)
		(width 1.016)
		(layer "In2.Cu")
		(net "P3V3")
	)
	(segment
		(start 243.586 -420.878)
		(end 243.586 -425.45)
		(width 0.508)
		(layer "In2.Cu")
		(net "P3V3")
	)
	(segment
		(start 224.480374 -452.387716)
		(end 224.480374 -451.966838)
		(width 1.016)
		(layer "In2.Cu")
		(net "P3V3")
	)
	(segment
		(start 18.034 -134.809992)
		(end 19.747992 -133.096)
		(width 0.508)
		(layer "In2.Cu")
		(net "P3V3")
	)
	(segment
		(start 224.480374 -452.387716)
		(end 222.640144 -452.387716)
		(width 1.016)
		(layer "In2.Cu")
		(net "P3V3")
	)
	(segment
		(start 226.51339 -140.38961)
		(end 227.468938 -140.38961)
		(width 1.016)
		(layer "In2.Cu")
		(net "P3V3")
	)
	(segment
		(start 39.0652 -473.456)
		(end 40.3352 -474.726)
		(width 1.016)
		(layer "In2.Cu")
		(net "P3V3")
	)
	(segment
		(start 230.7082 -41.22928)
		(end 231.989884 -42.510964)
		(width 1.016)
		(layer "In2.Cu")
		(net "P3V3")
	)
	(segment
		(start 20.358862 -58.050938)
		(end 20.358862 -58.482484)
		(width 1.016)
		(layer "In2.Cu")
		(net "P3V3")
	)
	(segment
		(start 19.617944 -30.226)
		(end 24.384 -30.226)
		(width 0.508)
		(layer "In2.Cu")
		(net "P3V3")
	)
	(segment
		(start 39.9288 -104.648)
		(end 33.3248 -111.252)
		(width 1.016)
		(layer "In5.Cu")
		(net "P3V3")
	)
	(segment
		(start 30.570424 -85.9282)
		(end 29.03093 -85.9282)
		(width 1.016)
		(layer "In5.Cu")
		(net "P3V3")
	)
	(segment
		(start 41.3258 -288.0614)
		(end 42.6466 -286.7406)
		(width 1.016)
		(layer "In5.Cu")
		(net "P3V3")
	)
	(segment
		(start 27.0256 -391.3124)
		(end 27.6987 -391.3124)
		(width 1.016)
		(layer "In5.Cu")
		(net "P3V3")
	)
	(segment
		(start 31.5214 -288.0614)
		(end 41.3258 -288.0614)
		(width 1.016)
		(layer "In5.Cu")
		(net "P3V3")
	)
	(segment
		(start 22.0726 -196.7865)
		(end 22.5425 -196.7865)
		(width 1.016)
		(layer "In5.Cu")
		(net "P3V3")
	)
	(segment
		(start 22.8092 -299.0342)
		(end 22.479 -299.0342)
		(width 1.016)
		(layer "In5.Cu")
		(net "P3V3")
	)
	(segment
		(start 27.178 -188.9252)
		(end 29.95803 -188.9252)
		(width 1.016)
		(layer "In5.Cu")
		(net "P3V3")
	)
	(segment
		(start 21.7424 -396.5956)
		(end 27.0256 -391.3124)
		(width 1.016)
		(layer "In5.Cu")
		(net "P3V3")
	)
	(segment
		(start 226.481132 -62.189868)
		(end 228.966014 -62.189868)
		(width 1.016)
		(layer "In5.Cu")
		(net "P3V3")
	)
	(segment
		(start 44.1452 -96.4692)
		(end 34.6964 -87.0204)
		(width 1.016)
		(layer "In5.Cu")
		(net "P3V3")
	)
	(segment
		(start 20.43811 -398.81048)
		(end 21.7424 -397.50619)
		(width 1.016)
		(layer "In5.Cu")
		(net "P3V3")
	)
	(segment
		(start 37.5158 -191.4906)
		(end 31.2674 -191.4906)
		(width 1.016)
		(layer "In5.Cu")
		(net "P3V3")
	)
	(segment
		(start 23.5712 -192.532)
		(end 27.178 -188.9252)
		(width 1.016)
		(layer "In5.Cu")
		(net "P3V3")
	)
	(segment
		(start 29.9466 -289.6362)
		(end 31.5214 -288.0614)
		(width 1.016)
		(layer "In5.Cu")
		(net "P3V3")
	)
	(segment
		(start 224.917 -63.754)
		(end 226.481132 -62.189868)
		(width 1.016)
		(layer "In5.Cu")
		(net "P3V3")
	)
	(segment
		(start 24.464772 -464.82)
		(end 25.4762 -464.82)
		(width 1.016)
		(layer "In5.Cu")
		(net "P3V3")
	)
	(segment
		(start 23.123144 -466.161628)
		(end 24.464772 -464.82)
		(width 1.016)
		(layer "In5.Cu")
		(net "P3V3")
	)
	(segment
		(start 23.5458 -91.0336)
		(end 28.6512 -85.9282)
		(width 1.016)
		(layer "In5.Cu")
		(net "P3V3")
	)
	(segment
		(start 45.212 -199.1868)
		(end 37.5158 -191.4906)
		(width 1.016)
		(layer "In5.Cu")
		(net "P3V3")
	)
	(segment
		(start 34.6964 -87.0204)
		(end 31.662624 -87.0204)
		(width 1.016)
		(layer "In5.Cu")
		(net "P3V3")
	)
	(segment
		(start 22.5425 -196.7865)
		(end 23.5712 -195.7578)
		(width 1.016)
		(layer "In5.Cu")
		(net "P3V3")
	)
	(segment
		(start 31.662624 -87.0204)
		(end 30.570424 -85.9282)
		(width 1.016)
		(layer "In5.Cu")
		(net "P3V3")
	)
	(segment
		(start 42.6466 -286.7406)
		(end 55.9562 -286.7406)
		(width 1.016)
		(layer "In5.Cu")
		(net "P3V3")
	)
	(segment
		(start 33.3248 -111.252)
		(end 31.8262 -111.252)
		(width 1.016)
		(layer "In5.Cu")
		(net "P3V3")
	)
	(segment
		(start 21.7424 -397.50619)
		(end 21.7424 -396.5956)
		(width 1.016)
		(layer "In5.Cu")
		(net "P3V3")
	)
	(segment
		(start 29.95803 -190.18123)
		(end 29.95803 -188.9252)
		(width 1.016)
		(layer "In5.Cu")
		(net "P3V3")
	)
	(segment
		(start 55.9562 -286.7406)
		(end 60.3758 -282.321)
		(width 1.016)
		(layer "In5.Cu")
		(net "P3V3")
	)
	(segment
		(start 29.9466 -291.8968)
		(end 22.8092 -299.0342)
		(width 1.016)
		(layer "In5.Cu")
		(net "P3V3")
	)
	(segment
		(start 31.2674 -191.4906)
		(end 29.95803 -190.18123)
		(width 1.016)
		(layer "In5.Cu")
		(net "P3V3")
	)
	(segment
		(start 60.3758 -282.321)
		(end 74.676 -282.321)
		(width 1.016)
		(layer "In5.Cu")
		(net "P3V3")
	)
	(segment
		(start 54.5338 -199.1868)
		(end 45.212 -199.1868)
		(width 1.016)
		(layer "In5.Cu")
		(net "P3V3")
	)
	(segment
		(start 29.9466 -291.8968)
		(end 29.9466 -289.6362)
		(width 1.016)
		(layer "In5.Cu")
		(net "P3V3")
	)
	(segment
		(start 23.5712 -195.7578)
		(end 23.5712 -192.532)
		(width 1.016)
		(layer "In5.Cu")
		(net "P3V3")
	)
	(segment
		(start 222.631 -63.754)
		(end 224.917 -63.754)
		(width 1.016)
		(layer "In5.Cu")
		(net "P3V3")
	)
	(segment
		(start 28.6512 -85.9282)
		(end 29.03093 -85.9282)
		(width 1.016)
		(layer "In5.Cu")
		(net "P3V3")
	)
	(segment
		(start 37.2364 -95.3262)
		(end 38.4302 -95.3262)
		(width 0.508)
		(layer "F.Cu")
		(net "P12V_SSD9")
	)
	(via
		(at 41.7322 -95.8088)
		(size 0.7112)
		(drill 0.3556)
		(layers "F.Cu" "B.Cu")
		(net "P12V_SSD9")
	)
	(via
		(at 38.6842 -94.0816)
		(size 0.7112)
		(drill 0.3556)
		(layers "F.Cu" "B.Cu")
		(net "P12V_SSD9")
	)
	(segment
		(start 37.2618 -198.2724)
		(end 38.5572 -198.2724)
		(width 0.508)
		(layer "F.Cu")
		(net "P12V_SSD8")
	)
	(via
		(at 38.9128 -199.0344)
		(size 0.7112)
		(drill 0.3556)
		(layers "F.Cu" "B.Cu")
		(net "P12V_SSD8")
	)
	(via
		(at 38.735 -196.723)
		(size 0.7112)
		(drill 0.3556)
		(layers "F.Cu" "B.Cu")
		(net "P12V_SSD8")
	)
	(segment
		(start 36.9062 -301.2186)
		(end 38.6588 -301.2186)
		(width 0.508)
		(layer "F.Cu")
		(net "P12V_SSD7")
	)
	(via
		(at 42.1894 -302.2092)
		(size 0.7112)
		(drill 0.3556)
		(layers "F.Cu" "B.Cu")
		(net "P12V_SSD7")
	)
	(via
		(at 38.9636 -302.1838)
		(size 0.7112)
		(drill 0.3556)
		(layers "F.Cu" "B.Cu")
		(net "P12V_SSD7")
	)
	(segment
		(start 38.0492 -403.8092)
		(end 37.6174 -404.241)
		(width 0.508)
		(layer "F.Cu")
		(net "P12V_SSD6")
	)
	(segment
		(start 33.655 -404.241)
		(end 32.95015 -403.53615)
		(width 0.508)
		(layer "F.Cu")
		(net "P12V_SSD6")
	)
	(segment
		(start 37.6174 -404.241)
		(end 33.655 -404.241)
		(width 0.508)
		(layer "F.Cu")
		(net "P12V_SSD6")
	)
	(segment
		(start 38.6588 -403.8092)
		(end 38.0492 -403.8092)
		(width 0.508)
		(layer "F.Cu")
		(net "P12V_SSD6")
	)
	(via
		(at 39.3446 -404.1902)
		(size 0.7112)
		(drill 0.3556)
		(layers "F.Cu" "B.Cu")
		(net "P12V_SSD6")
	)
	(via
		(at 39.37 -402.2852)
		(size 0.7112)
		(drill 0.3556)
		(layers "F.Cu" "B.Cu")
		(net "P12V_SSD6")
	)
	(segment
		(start 22.987 -502.2596)
		(end 22.1488 -501.4214)
		(width 0.508)
		(layer "F.Cu")
		(net "P12V_SSD5")
	)
	(segment
		(start 31.8008 -500.9896)
		(end 31.8008 -501.7008)
		(width 0.508)
		(layer "F.Cu")
		(net "P12V_SSD5")
	)
	(segment
		(start 31.242 -502.2596)
		(end 22.987 -502.2596)
		(width 0.508)
		(layer "F.Cu")
		(net "P12V_SSD5")
	)
	(segment
		(start 22.1488 -501.4214)
		(end 22.1488 -499.872)
		(width 0.508)
		(layer "F.Cu")
		(net "P12V_SSD5")
	)
	(segment
		(start 31.8008 -501.7008)
		(end 31.242 -502.2596)
		(width 0.508)
		(layer "F.Cu")
		(net "P12V_SSD5")
	)
	(via
		(at 38.2524 -500.4562)
		(size 0.508)
		(drill 0.254)
		(layers "F.Cu" "B.Cu")
		(net "P12V_SSD5")
	)
	(via
		(at 27.7114 -491.8202)
		(size 0.7112)
		(drill 0.3556)
		(layers "F.Cu" "B.Cu")
		(net "P12V_SSD5")
	)
	(via
		(at 27.813 -494.7158)
		(size 0.7112)
		(drill 0.3556)
		(layers "F.Cu" "B.Cu")
		(net "P12V_SSD5")
	)
	(via
		(at 34.8742 -500.3546)
		(size 0.508)
		(drill 0.254)
		(layers "F.Cu" "B.Cu")
		(net "P12V_SSD5")
	)
	(via
		(at 38.3032 -497.5606)
		(size 0.508)
		(drill 0.254)
		(layers "F.Cu" "B.Cu")
		(net "P12V_SSD5")
	)
	(via
		(at 34.7472 -497.8146)
		(size 0.508)
		(drill 0.254)
		(layers "F.Cu" "B.Cu")
		(net "P12V_SSD5")
	)
	(segment
		(start 222.0976 -95.6056)
		(end 223.774 -95.6056)
		(width 0.508)
		(layer "F.Cu")
		(net "P12V_SSD4")
	)
	(via
		(at 224.155 -93.218)
		(size 0.7112)
		(drill 0.3556)
		(layers "F.Cu" "B.Cu")
		(net "P12V_SSD4")
	)
	(via
		(at 227.3046 -95.8342)
		(size 0.7112)
		(drill 0.3556)
		(layers "F.Cu" "B.Cu")
		(net "P12V_SSD4")
	)
	(segment
		(start 221.9706 -198.6026)
		(end 223.7486 -198.6026)
		(width 0.508)
		(layer "F.Cu")
		(net "P12V_SSD3")
	)
	(via
		(at 227.2792 -199.1106)
		(size 0.7112)
		(drill 0.3556)
		(layers "F.Cu" "B.Cu")
		(net "P12V_SSD3")
	)
	(via
		(at 224.028 -196.342)
		(size 0.7112)
		(drill 0.3556)
		(layers "F.Cu" "B.Cu")
		(net "P12V_SSD3")
	)
	(segment
		(start 223.0374 -301.5996)
		(end 221.9706 -301.5996)
		(width 0.508)
		(layer "F.Cu")
		(net "P12V_SSD2")
	)
	(segment
		(start 223.6724 -300.9646)
		(end 223.0374 -301.5996)
		(width 0.508)
		(layer "F.Cu")
		(net "P12V_SSD2")
	)
	(via
		(at 225.1456 -300.99)
		(size 0.7112)
		(drill 0.3556)
		(layers "F.Cu" "B.Cu")
		(net "P12V_SSD2")
	)
	(via
		(at 223.647 -299.339)
		(size 0.7112)
		(drill 0.3556)
		(layers "F.Cu" "B.Cu")
		(net "P12V_SSD2")
	)
	(segment
		(start 97.0788 -21.5011)
		(end 97.0788 -20.701)
		(width 0.508)
		(layer "F.Cu")
		(net "P12V_SSD14")
	)
	(via
		(at 38.7096 -10.541)
		(size 0.508)
		(drill 0.254)
		(layers "F.Cu" "B.Cu")
		(net "P12V_SSD14")
	)
	(via
		(at 18.0848 -9.3726)
		(size 0.7112)
		(drill 0.4064)
		(layers "F.Cu" "B.Cu")
		(net "P12V_SSD14")
	)
	(via
		(at 97.0788 -20.701)
		(size 0.508)
		(drill 0.254)
		(layers "F.Cu" "B.Cu")
		(net "P12V_SSD14")
	)
	(via
		(at 37.084 -10.6426)
		(size 0.7112)
		(drill 0.3556)
		(layers "F.Cu" "B.Cu")
		(net "P12V_SSD14")
	)
	(via
		(at 33.147 -11.5316)
		(size 0.7112)
		(drill 0.3556)
		(layers "F.Cu" "B.Cu")
		(net "P12V_SSD14")
	)
	(via
		(at 34.5694 -10.4648)
		(size 0.7112)
		(drill 0.4064)
		(layers "F.Cu" "B.Cu")
		(net "P12V_SSD14")
	)
	(segment
		(start 42.3926 -14.224)
		(end 38.7096 -10.541)
		(width 0.508)
		(layer "B.Cu")
		(net "P12V_SSD14")
	)
	(segment
		(start 97.0788 -20.701)
		(end 96.0882 -21.6916)
		(width 0.508)
		(layer "B.Cu")
		(net "P12V_SSD14")
	)
	(segment
		(start 79.3496 -21.6916)
		(end 71.882 -14.224)
		(width 0.508)
		(layer "B.Cu")
		(net "P12V_SSD14")
	)
	(segment
		(start 96.0882 -21.6916)
		(end 79.3496 -21.6916)
		(width 0.508)
		(layer "B.Cu")
		(net "P12V_SSD14")
	)
	(segment
		(start 71.882 -14.224)
		(end 42.3926 -14.224)
		(width 0.508)
		(layer "B.Cu")
		(net "P12V_SSD14")
	)
	(segment
		(start 24.74595 -101.86035)
		(end 23.45055 -101.86035)
		(width 0.508)
		(layer "F.Cu")
		(net "P12V_SSD13")
	)
	(via
		(at 23.0632 -101.0158)
		(size 0.7112)
		(drill 0.3556)
		(layers "F.Cu" "B.Cu")
		(net "P12V_SSD13")
	)
	(via
		(at 20.3962 -101.0158)
		(size 0.7112)
		(drill 0.3556)
		(layers "F.Cu" "B.Cu")
		(net "P12V_SSD13")
	)
	(segment
		(start 24.7904 -204.6478)
		(end 23.5458 -204.6478)
		(width 0.508)
		(layer "F.Cu")
		(net "P12V_SSD12")
	)
	(via
		(at 20.6502 -204.1144)
		(size 0.7112)
		(drill 0.3556)
		(layers "F.Cu" "B.Cu")
		(net "P12V_SSD12")
	)
	(via
		(at 22.8092 -204.089)
		(size 0.7112)
		(drill 0.3556)
		(layers "F.Cu" "B.Cu")
		(net "P12V_SSD12")
	)
	(segment
		(start 24.765 -307.7972)
		(end 23.3426 -307.7972)
		(width 0.508)
		(layer "F.Cu")
		(net "P12V_SSD11")
	)
	(via
		(at 21.082 -306.9844)
		(size 0.7112)
		(drill 0.3556)
		(layers "F.Cu" "B.Cu")
		(net "P12V_SSD11")
	)
	(via
		(at 23.0632 -306.9844)
		(size 0.7112)
		(drill 0.3556)
		(layers "F.Cu" "B.Cu")
		(net "P12V_SSD11")
	)
	(segment
		(start 23.6474 -411.4038)
		(end 23.9776 -411.4038)
		(width 0.508)
		(layer "F.Cu")
		(net "P12V_SSD10")
	)
	(segment
		(start 23.9776 -411.4038)
		(end 24.7396 -410.6418)
		(width 0.508)
		(layer "F.Cu")
		(net "P12V_SSD10")
	)
	(via
		(at 21.971 -410.1338)
		(size 0.7112)
		(drill 0.3556)
		(layers "F.Cu" "B.Cu")
		(net "P12V_SSD10")
	)
	(via
		(at 19.8374 -410.083)
		(size 0.7112)
		(drill 0.3556)
		(layers "F.Cu" "B.Cu")
		(net "P12V_SSD10")
	)
	(segment
		(start 223.9772 -403.9616)
		(end 222.9612 -404.9776)
		(width 0.508)
		(layer "F.Cu")
		(net "P12V_SSD1")
	)
	(segment
		(start 222.9612 -404.9776)
		(end 221.9706 -404.9776)
		(width 0.508)
		(layer "F.Cu")
		(net "P12V_SSD1")
	)
	(via
		(at 224.282 -401.955)
		(size 0.7112)
		(drill 0.3556)
		(layers "F.Cu" "B.Cu")
		(net "P12V_SSD1")
	)
	(via
		(at 224.8662 -403.9362)
		(size 0.7112)
		(drill 0.3556)
		(layers "F.Cu" "B.Cu")
		(net "P12V_SSD1")
	)
	(segment
		(start 207.8736 -502.158)
		(end 207.096106 -501.380506)
		(width 0.508)
		(layer "F.Cu")
		(net "P12V_SSD0")
	)
	(segment
		(start 216.8144 -501.1674)
		(end 216.8144 -501.7516)
		(width 0.508)
		(layer "F.Cu")
		(net "P12V_SSD0")
	)
	(segment
		(start 207.096106 -501.380506)
		(end 207.096106 -499.619778)
		(width 0.508)
		(layer "F.Cu")
		(net "P12V_SSD0")
	)
	(segment
		(start 216.408 -502.158)
		(end 207.8736 -502.158)
		(width 0.508)
		(layer "F.Cu")
		(net "P12V_SSD0")
	)
	(segment
		(start 216.8144 -501.7516)
		(end 216.408 -502.158)
		(width 0.508)
		(layer "F.Cu")
		(net "P12V_SSD0")
	)
	(via
		(at 212.09 -493.014)
		(size 0.7112)
		(drill 0.3556)
		(layers "F.Cu" "B.Cu")
		(net "P12V_SSD0")
	)
	(via
		(at 212.2932 -494.919)
		(size 0.7112)
		(drill 0.3556)
		(layers "F.Cu" "B.Cu")
		(net "P12V_SSD0")
	)
	(via
		(at 218.948 -497.967)
		(size 0.508)
		(drill 0.254)
		(layers "F.Cu" "B.Cu")
		(net "P12V_SSD0")
	)
	(via
		(at 223.52 -496.697)
		(size 0.508)
		(drill 0.254)
		(layers "F.Cu" "B.Cu")
		(net "P12V_SSD0")
	)
	(via
		(at 218.948 -500.3546)
		(size 0.508)
		(drill 0.254)
		(layers "F.Cu" "B.Cu")
		(net "P12V_SSD0")
	)
	(via
		(at 223.393 -500.38)
		(size 0.508)
		(drill 0.254)
		(layers "F.Cu" "B.Cu")
		(net "P12V_SSD0")
	)
	(segment
		(start 228.219 -439.6105)
		(end 228.219 -440.436)
		(width 0.508)
		(layer "F.Cu")
		(net "P12V")
	)
	(segment
		(start 49.5935 -143.383)
		(end 49.5935 -142.5702)
		(width 0.508)
		(layer "F.Cu")
		(net "P12V")
	)
	(segment
		(start 24.4475 -51.054)
		(end 25.2222 -51.054)
		(width 0.508)
		(layer "F.Cu")
		(net "P12V")
	)
	(segment
		(start 49.4665 -452.501)
		(end 50.2666 -452.501)
		(width 0.508)
		(layer "F.Cu")
		(net "P12V")
	)
	(segment
		(start 228.981 -427.99)
		(end 228.981 -427.101)
		(width 0.508)
		(layer "F.Cu")
		(net "P12V")
	)
	(segment
		(start 234.5055 -142.494)
		(end 235.29671 -142.494)
		(width 0.508)
		(layer "F.Cu")
		(net "P12V")
	)
	(segment
		(start 49.7205 -40.132)
		(end 50.4952 -40.132)
		(width 0.508)
		(layer "F.Cu")
		(net "P12V")
	)
	(segment
		(start 234.5055 -39.497)
		(end 235.292138 -39.497)
		(width 0.508)
		(layer "F.Cu")
		(net "P12V")
	)
	(segment
		(start 24.4475 -360.045)
		(end 24.4475 -359.2576)
		(width 0.508)
		(layer "F.Cu")
		(net "P12V")
	)
	(segment
		(start 23.622 -256.2225)
		(end 23.622 -255.4478)
		(width 0.508)
		(layer "F.Cu")
		(net "P12V")
	)
	(segment
		(start 25.2984 -462.661)
		(end 25.4762 -462.4832)
		(width 0.508)
		(layer "F.Cu")
		(net "P12V")
	)
	(segment
		(start 49.7205 -246.253)
		(end 50.5206 -246.253)
		(width 0.508)
		(layer "F.Cu")
		(net "P12V")
	)
	(segment
		(start 92.3925 -14.732)
		(end 92.3925 -13.7795)
		(width 0.508)
		(layer "F.Cu")
		(net "P12V")
	)
	(segment
		(start 200.250806 -498.070378)
		(end 199.450706 -498.070378)
		(width 0.508)
		(layer "F.Cu")
		(net "P12V")
	)
	(segment
		(start 15.5067 -498.2972)
		(end 14.6812 -498.2972)
		(width 0.508)
		(layer "F.Cu")
		(net "P12V")
	)
	(segment
		(start 234.5055 -451.485)
		(end 235.3056 -451.485)
		(width 0.508)
		(layer "F.Cu")
		(net "P12V")
	)
	(segment
		(start 234.5055 -348.488)
		(end 235.2802 -348.488)
		(width 0.508)
		(layer "F.Cu")
		(net "P12V")
	)
	(segment
		(start 234.5055 -245.491)
		(end 235.325158 -245.491)
		(width 0.508)
		(layer "F.Cu")
		(net "P12V")
	)
	(segment
		(start 48.3235 -348.742)
		(end 49.1236 -348.742)
		(width 0.508)
		(layer "F.Cu")
		(net "P12V")
	)
	(segment
		(start 23.495 -153.2255)
		(end 22.7076 -153.2255)
		(width 0.508)
		(layer "F.Cu")
		(net "P12V")
	)
	(segment
		(start 24.7015 -462.661)
		(end 25.2984 -462.661)
		(width 0.508)
		(layer "F.Cu")
		(net "P12V")
	)
	(via
		(at 245.11 -377.19)
		(size 0.7112)
		(drill 0.4064)
		(layers "F.Cu" "B.Cu")
		(net "P12V")
	)
	(via
		(at 49.5935 -142.5702)
		(size 0.508)
		(drill 0.254)
		(layers "F.Cu" "B.Cu")
		(net "P12V")
	)
	(via
		(at 251.6124 -362.4834)
		(size 0.7112)
		(drill 0.4064)
		(layers "F.Cu" "B.Cu")
		(net "P12V")
	)
	(via
		(at 45.0342 -9.017)
		(size 0.508)
		(drill 0.254)
		(layers "F.Cu" "B.Cu")
		(net "P12V")
	)
	(via
		(at 211.582 -401.955)
		(size 0.508)
		(drill 0.254)
		(layers "F.Cu" "B.Cu")
		(net "P12V")
	)
	(via
		(at 237.49 -367.03)
		(size 0.7112)
		(drill 0.4064)
		(layers "F.Cu" "B.Cu")
		(net "P12V")
	)
	(via
		(at 223.863662 -419.290246)
		(size 0.508)
		(drill 0.254)
		(layers "F.Cu" "B.Cu")
		(net "P12V")
	)
	(via
		(at 34.036 -104.902)
		(size 0.508)
		(drill 0.254)
		(layers "F.Cu" "B.Cu")
		(net "P12V")
	)
	(via
		(at 4.445 -469.265)
		(size 0.7112)
		(drill 0.4064)
		(layers "F.Cu" "B.Cu")
		(net "P12V")
	)
	(via
		(at 3.175 -468.63)
		(size 0.7112)
		(drill 0.4064)
		(layers "F.Cu" "B.Cu")
		(net "P12V")
	)
	(via
		(at 27.178 -400.4818)
		(size 0.508)
		(drill 0.254)
		(layers "F.Cu" "B.Cu")
		(net "P12V")
	)
	(via
		(at 222.974662 -419.290246)
		(size 0.508)
		(drill 0.254)
		(layers "F.Cu" "B.Cu")
		(net "P12V")
	)
	(via
		(at 222.974662 -420.179246)
		(size 0.508)
		(drill 0.254)
		(layers "F.Cu" "B.Cu")
		(net "P12V")
	)
	(via
		(at 27.94 -92.964)
		(size 0.508)
		(drill 0.254)
		(layers "F.Cu" "B.Cu")
		(net "P12V")
	)
	(via
		(at 5.715 -472.44)
		(size 0.7112)
		(drill 0.4064)
		(layers "F.Cu" "B.Cu")
		(net "P12V")
	)
	(via
		(at 27.94 -298.069)
		(size 0.508)
		(drill 0.254)
		(layers "F.Cu" "B.Cu")
		(net "P12V")
	)
	(via
		(at 247.65 -372.11)
		(size 0.7112)
		(drill 0.4064)
		(layers "F.Cu" "B.Cu")
		(net "P12V")
	)
	(via
		(at 213.36 -92.075)
		(size 0.508)
		(drill 0.254)
		(layers "F.Cu" "B.Cu")
		(net "P12V")
	)
	(via
		(at 5.715 -471.17)
		(size 0.7112)
		(drill 0.4064)
		(layers "F.Cu" "B.Cu")
		(net "P12V")
	)
	(via
		(at 199.450706 -498.070378)
		(size 0.508)
		(drill 0.254)
		(layers "F.Cu" "B.Cu")
		(net "P12V")
	)
	(via
		(at 92.3925 -13.7795)
		(size 0.508)
		(drill 0.254)
		(layers "F.Cu" "B.Cu")
		(net "P12V")
	)
	(via
		(at 245.11 -364.49)
		(size 0.7112)
		(drill 0.4064)
		(layers "F.Cu" "B.Cu")
		(net "P12V")
	)
	(via
		(at 33.147 -310.007)
		(size 0.508)
		(drill 0.254)
		(layers "F.Cu" "B.Cu")
		(net "P12V")
	)
	(via
		(at 228.981 -427.101)
		(size 0.508)
		(drill 0.254)
		(layers "F.Cu" "B.Cu")
		(net "P12V")
	)
	(via
		(at 243.84 -370.84)
		(size 0.7112)
		(drill 0.3556)
		(layers "F.Cu" "B.Cu")
		(net "P12V")
	)
	(via
		(at 240.03 -369.57)
		(size 0.7112)
		(drill 0.4064)
		(layers "F.Cu" "B.Cu")
		(net "P12V")
	)
	(via
		(at 211.582 -298.958)
		(size 0.508)
		(drill 0.254)
		(layers "F.Cu" "B.Cu")
		(net "P12V")
	)
	(via
		(at 28.829 -195.072)
		(size 0.508)
		(drill 0.254)
		(layers "F.Cu" "B.Cu")
		(net "P12V")
	)
	(via
		(at 28.829 -92.964)
		(size 0.508)
		(drill 0.254)
		(layers "F.Cu" "B.Cu")
		(net "P12V")
	)
	(via
		(at 19.5326 -497.3066)
		(size 0.508)
		(drill 0.254)
		(layers "F.Cu" "B.Cu")
		(net "P12V")
	)
	(via
		(at 27.051 -92.075)
		(size 0.508)
		(drill 0.254)
		(layers "F.Cu" "B.Cu")
		(net "P12V")
	)
	(via
		(at 33.0962 -414.0454)
		(size 0.508)
		(drill 0.254)
		(layers "F.Cu" "B.Cu")
		(net "P12V")
	)
	(via
		(at 212.471 -401.955)
		(size 0.508)
		(drill 0.254)
		(layers "F.Cu" "B.Cu")
		(net "P12V")
	)
	(via
		(at 250.1646 -363.3216)
		(size 0.7112)
		(drill 0.4064)
		(layers "F.Cu" "B.Cu")
		(net "P12V")
	)
	(via
		(at 4.445 -475.615)
		(size 0.7112)
		(drill 0.4064)
		(layers "F.Cu" "B.Cu")
		(net "P12V")
	)
	(via
		(at 240.03 -361.95)
		(size 0.7112)
		(drill 0.4064)
		(layers "F.Cu" "B.Cu")
		(net "P12V")
	)
	(via
		(at 237.49 -364.49)
		(size 0.7112)
		(drill 0.4064)
		(layers "F.Cu" "B.Cu")
		(net "P12V")
	)
	(via
		(at 3.175 -469.9)
		(size 0.7112)
		(drill 0.4064)
		(layers "F.Cu" "B.Cu")
		(net "P12V")
	)
	(via
		(at 212.471 -195.072)
		(size 0.508)
		(drill 0.254)
		(layers "F.Cu" "B.Cu")
		(net "P12V")
	)
	(via
		(at 22.7076 -153.2255)
		(size 0.508)
		(drill 0.254)
		(layers "F.Cu" "B.Cu")
		(net "P12V")
	)
	(via
		(at 228.219 -440.436)
		(size 0.508)
		(drill 0.254)
		(layers "F.Cu" "B.Cu")
		(net "P12V")
	)
	(via
		(at 33.147 -207.01)
		(size 0.508)
		(drill 0.254)
		(layers "F.Cu" "B.Cu")
		(net "P12V")
	)
	(via
		(at 245.11 -374.65)
		(size 0.7112)
		(drill 0.4064)
		(layers "F.Cu" "B.Cu")
		(net "P12V")
	)
	(via
		(at 3.175 -474.98)
		(size 0.7112)
		(drill 0.4064)
		(layers "F.Cu" "B.Cu")
		(net "P12V")
	)
	(via
		(at 202.498706 -496.139978)
		(size 0.508)
		(drill 0.254)
		(layers "F.Cu" "B.Cu")
		(net "P12V")
	)
	(via
		(at 26.289 -399.5928)
		(size 0.508)
		(drill 0.254)
		(layers "F.Cu" "B.Cu")
		(net "P12V")
	)
	(via
		(at 34.036 -207.01)
		(size 0.508)
		(drill 0.254)
		(layers "F.Cu" "B.Cu")
		(net "P12V")
	)
	(via
		(at 237.49 -369.57)
		(size 0.7112)
		(drill 0.4064)
		(layers "F.Cu" "B.Cu")
		(net "P12V")
	)
	(via
		(at 245.11 -372.11)
		(size 0.7112)
		(drill 0.4064)
		(layers "F.Cu" "B.Cu")
		(net "P12V")
	)
	(via
		(at 29.718 -92.075)
		(size 0.508)
		(drill 0.254)
		(layers "F.Cu" "B.Cu")
		(net "P12V")
	)
	(via
		(at 242.2652 -361.9246)
		(size 0.7112)
		(drill 0.4064)
		(layers "F.Cu" "B.Cu")
		(net "P12V")
	)
	(via
		(at 34.036 -104.013)
		(size 0.508)
		(drill 0.254)
		(layers "F.Cu" "B.Cu")
		(net "P12V")
	)
	(via
		(at 247.65 -364.49)
		(size 0.7112)
		(drill 0.4064)
		(layers "F.Cu" "B.Cu")
		(net "P12V")
	)
	(via
		(at 33.147 -310.896)
		(size 0.508)
		(drill 0.254)
		(layers "F.Cu" "B.Cu")
		(net "P12V")
	)
	(via
		(at 27.051 -298.069)
		(size 0.508)
		(drill 0.254)
		(layers "F.Cu" "B.Cu")
		(net "P12V")
	)
	(via
		(at 24.4475 -359.2576)
		(size 0.508)
		(drill 0.254)
		(layers "F.Cu" "B.Cu")
		(net "P12V")
	)
	(via
		(at 3.175 -471.17)
		(size 0.7112)
		(drill 0.4064)
		(layers "F.Cu" "B.Cu")
		(net "P12V")
	)
	(via
		(at 28.956 -400.4818)
		(size 0.508)
		(drill 0.254)
		(layers "F.Cu" "B.Cu")
		(net "P12V")
	)
	(via
		(at 4.445 -466.725)
		(size 0.7112)
		(drill 0.4064)
		(layers "F.Cu" "B.Cu")
		(net "P12V")
	)
	(via
		(at 237.49 -361.95)
		(size 0.7112)
		(drill 0.4064)
		(layers "F.Cu" "B.Cu")
		(net "P12V")
	)
	(via
		(at 4.445 -465.455)
		(size 0.7112)
		(drill 0.4064)
		(layers "F.Cu" "B.Cu")
		(net "P12V")
	)
	(via
		(at 214.249 -401.955)
		(size 0.508)
		(drill 0.254)
		(layers "F.Cu" "B.Cu")
		(net "P12V")
	)
	(via
		(at 19.5326 -496.4176)
		(size 0.508)
		(drill 0.254)
		(layers "F.Cu" "B.Cu")
		(net "P12V")
	)
	(via
		(at 214.249 -298.958)
		(size 0.508)
		(drill 0.254)
		(layers "F.Cu" "B.Cu")
		(net "P12V")
	)
	(via
		(at 22.225 -496.3922)
		(size 0.508)
		(drill 0.254)
		(layers "F.Cu" "B.Cu")
		(net "P12V")
	)
	(via
		(at 28.067 -399.5928)
		(size 0.508)
		(drill 0.254)
		(layers "F.Cu" "B.Cu")
		(net "P12V")
	)
	(via
		(at 45.9232 -9.017)
		(size 0.508)
		(drill 0.254)
		(layers "F.Cu" "B.Cu")
		(net "P12V")
	)
	(via
		(at 213.36 -401.955)
		(size 0.508)
		(drill 0.254)
		(layers "F.Cu" "B.Cu")
		(net "P12V")
	)
	(via
		(at 32.258 -310.896)
		(size 0.508)
		(drill 0.254)
		(layers "F.Cu" "B.Cu")
		(net "P12V")
	)
	(via
		(at 204.276706 -497.028978)
		(size 0.508)
		(drill 0.254)
		(layers "F.Cu" "B.Cu")
		(net "P12V")
	)
	(via
		(at 33.9852 -414.0454)
		(size 0.508)
		(drill 0.254)
		(layers "F.Cu" "B.Cu")
		(net "P12V")
	)
	(via
		(at 213.36 -92.964)
		(size 0.508)
		(drill 0.254)
		(layers "F.Cu" "B.Cu")
		(net "P12V")
	)
	(via
		(at 28.956 -399.5928)
		(size 0.508)
		(drill 0.254)
		(layers "F.Cu" "B.Cu")
		(net "P12V")
	)
	(via
		(at 242.57 -379.73)
		(size 0.7112)
		(drill 0.4064)
		(layers "F.Cu" "B.Cu")
		(net "P12V")
	)
	(via
		(at 32.2072 -414.0454)
		(size 0.508)
		(drill 0.254)
		(layers "F.Cu" "B.Cu")
		(net "P12V")
	)
	(via
		(at 247.65 -374.65)
		(size 0.7112)
		(drill 0.4064)
		(layers "F.Cu" "B.Cu")
		(net "P12V")
	)
	(via
		(at 247.65 -367.03)
		(size 0.7112)
		(drill 0.4064)
		(layers "F.Cu" "B.Cu")
		(net "P12V")
	)
	(via
		(at 203.387706 -497.028978)
		(size 0.508)
		(drill 0.254)
		(layers "F.Cu" "B.Cu")
		(net "P12V")
	)
	(via
		(at 34.036 -310.896)
		(size 0.508)
		(drill 0.254)
		(layers "F.Cu" "B.Cu")
		(net "P12V")
	)
	(via
		(at 29.718 -298.958)
		(size 0.508)
		(drill 0.254)
		(layers "F.Cu" "B.Cu")
		(net "P12V")
	)
	(via
		(at 252.73 -361.95)
		(size 0.7112)
		(drill 0.4064)
		(layers "F.Cu" "B.Cu")
		(net "P12V")
	)
	(via
		(at 247.65 -379.73)
		(size 0.7112)
		(drill 0.4064)
		(layers "F.Cu" "B.Cu")
		(net "P12V")
	)
	(via
		(at 29.718 -298.069)
		(size 0.508)
		(drill 0.254)
		(layers "F.Cu" "B.Cu")
		(net "P12V")
	)
	(via
		(at 242.57 -369.57)
		(size 0.7112)
		(drill 0.4064)
		(layers "F.Cu" "B.Cu")
		(net "P12V")
	)
	(via
		(at 240.03 -367.03)
		(size 0.7112)
		(drill 0.4064)
		(layers "F.Cu" "B.Cu")
		(net "P12V")
	)
	(via
		(at 29.718 -195.072)
		(size 0.508)
		(drill 0.254)
		(layers "F.Cu" "B.Cu")
		(net "P12V")
	)
	(via
		(at 18.6436 -497.3066)
		(size 0.508)
		(drill 0.254)
		(layers "F.Cu" "B.Cu")
		(net "P12V")
	)
	(via
		(at 245.11 -369.57)
		(size 0.7112)
		(drill 0.4064)
		(layers "F.Cu" "B.Cu")
		(net "P12V")
	)
	(via
		(at 235.2802 -348.488)
		(size 0.508)
		(drill 0.254)
		(layers "F.Cu" "B.Cu")
		(net "P12V")
	)
	(via
		(at 247.65 -361.95)
		(size 0.7112)
		(drill 0.3556)
		(layers "F.Cu" "B.Cu")
		(net "P12V")
	)
	(via
		(at 237.49 -382.27)
		(size 0.7112)
		(drill 0.4064)
		(layers "F.Cu" "B.Cu")
		(net "P12V")
	)
	(via
		(at 4.445 -467.995)
		(size 0.7112)
		(drill 0.4064)
		(layers "F.Cu" "B.Cu")
		(net "P12V")
	)
	(via
		(at 34.8742 -414.0454)
		(size 0.508)
		(drill 0.254)
		(layers "F.Cu" "B.Cu")
		(net "P12V")
	)
	(via
		(at 27.94 -195.072)
		(size 0.508)
		(drill 0.254)
		(layers "F.Cu" "B.Cu")
		(net "P12V")
	)
	(via
		(at 211.582 -92.964)
		(size 0.508)
		(drill 0.254)
		(layers "F.Cu" "B.Cu")
		(net "P12V")
	)
	(via
		(at 242.57 -374.65)
		(size 0.7112)
		(drill 0.4064)
		(layers "F.Cu" "B.Cu")
		(net "P12V")
	)
	(via
		(at 214.249 -92.075)
		(size 0.508)
		(drill 0.254)
		(layers "F.Cu" "B.Cu")
		(net "P12V")
	)
	(via
		(at 242.57 -372.11)
		(size 0.7112)
		(drill 0.4064)
		(layers "F.Cu" "B.Cu")
		(net "P12V")
	)
	(via
		(at 34.925 -207.01)
		(size 0.508)
		(drill 0.254)
		(layers "F.Cu" "B.Cu")
		(net "P12V")
	)
	(via
		(at 26.289 -400.4818)
		(size 0.508)
		(drill 0.254)
		(layers "F.Cu" "B.Cu")
		(net "P12V")
	)
	(via
		(at 214.249 -195.961)
		(size 0.508)
		(drill 0.254)
		(layers "F.Cu" "B.Cu")
		(net "P12V")
	)
	(via
		(at 5.7404 -463.6008)
		(size 0.7112)
		(drill 0.4064)
		(layers "F.Cu" "B.Cu")
		(net "P12V")
	)
	(via
		(at 202.498706 -497.028978)
		(size 0.508)
		(drill 0.254)
		(layers "F.Cu" "B.Cu")
		(net "P12V")
	)
	(via
		(at 4.445 -474.345)
		(size 0.7112)
		(drill 0.4064)
		(layers "F.Cu" "B.Cu")
		(net "P12V")
	)
	(via
		(at 203.387706 -496.139978)
		(size 0.508)
		(drill 0.254)
		(layers "F.Cu" "B.Cu")
		(net "P12V")
	)
	(via
		(at 235.325158 -245.491)
		(size 0.508)
		(drill 0.254)
		(layers "F.Cu" "B.Cu")
		(net "P12V")
	)
	(via
		(at 241.3 -381)
		(size 0.7112)
		(drill 0.3556)
		(layers "F.Cu" "B.Cu")
		(net "P12V")
	)
	(via
		(at 214.249 -195.072)
		(size 0.508)
		(drill 0.254)
		(layers "F.Cu" "B.Cu")
		(net "P12V")
	)
	(via
		(at 255.27 -361.95)
		(size 0.7112)
		(drill 0.4064)
		(layers "F.Cu" "B.Cu")
		(net "P12V")
	)
	(via
		(at 4.445 -464.185)
		(size 0.7112)
		(drill 0.4064)
		(layers "F.Cu" "B.Cu")
		(net "P12V")
	)
	(via
		(at 5.715 -469.9)
		(size 0.7112)
		(drill 0.4064)
		(layers "F.Cu" "B.Cu")
		(net "P12V")
	)
	(via
		(at 29.718 -92.964)
		(size 0.508)
		(drill 0.254)
		(layers "F.Cu" "B.Cu")
		(net "P12V")
	)
	(via
		(at 50.5206 -246.253)
		(size 0.508)
		(drill 0.254)
		(layers "F.Cu" "B.Cu")
		(net "P12V")
	)
	(via
		(at 46.8122 -9.906)
		(size 0.508)
		(drill 0.254)
		(layers "F.Cu" "B.Cu")
		(net "P12V")
	)
	(via
		(at 32.258 -104.902)
		(size 0.508)
		(drill 0.254)
		(layers "F.Cu" "B.Cu")
		(net "P12V")
	)
	(via
		(at 34.036 -207.899)
		(size 0.508)
		(drill 0.254)
		(layers "F.Cu" "B.Cu")
		(net "P12V")
	)
	(via
		(at 212.471 -401.066)
		(size 0.508)
		(drill 0.254)
		(layers "F.Cu" "B.Cu")
		(net "P12V")
	)
	(via
		(at 237.49 -374.65)
		(size 0.7112)
		(drill 0.4064)
		(layers "F.Cu" "B.Cu")
		(net "P12V")
	)
	(via
		(at 213.36 -195.961)
		(size 0.508)
		(drill 0.254)
		(layers "F.Cu" "B.Cu")
		(net "P12V")
	)
	(via
		(at 240.03 -382.27)
		(size 0.7112)
		(drill 0.4064)
		(layers "F.Cu" "B.Cu")
		(net "P12V")
	)
	(via
		(at 32.258 -310.007)
		(size 0.508)
		(drill 0.254)
		(layers "F.Cu" "B.Cu")
		(net "P12V")
	)
	(via
		(at 211.582 -401.066)
		(size 0.508)
		(drill 0.254)
		(layers "F.Cu" "B.Cu")
		(net "P12V")
	)
	(via
		(at 245.11 -367.03)
		(size 0.7112)
		(drill 0.4064)
		(layers "F.Cu" "B.Cu")
		(net "P12V")
	)
	(via
		(at 34.925 -104.013)
		(size 0.508)
		(drill 0.254)
		(layers "F.Cu" "B.Cu")
		(net "P12V")
	)
	(via
		(at 27.051 -92.964)
		(size 0.508)
		(drill 0.254)
		(layers "F.Cu" "B.Cu")
		(net "P12V")
	)
	(via
		(at 33.147 -207.899)
		(size 0.508)
		(drill 0.254)
		(layers "F.Cu" "B.Cu")
		(net "P12V")
	)
	(via
		(at 34.925 -104.902)
		(size 0.508)
		(drill 0.254)
		(layers "F.Cu" "B.Cu")
		(net "P12V")
	)
	(via
		(at 214.249 -401.066)
		(size 0.508)
		(drill 0.254)
		(layers "F.Cu" "B.Cu")
		(net "P12V")
	)
	(via
		(at 50.4952 -40.132)
		(size 0.508)
		(drill 0.254)
		(layers "F.Cu" "B.Cu")
		(net "P12V")
	)
	(via
		(at 204.276706 -496.139978)
		(size 0.508)
		(drill 0.254)
		(layers "F.Cu" "B.Cu")
		(net "P12V")
	)
	(via
		(at 33.0962 -413.1564)
		(size 0.508)
		(drill 0.254)
		(layers "F.Cu" "B.Cu")
		(net "P12V")
	)
	(via
		(at 28.829 -92.075)
		(size 0.508)
		(drill 0.254)
		(layers "F.Cu" "B.Cu")
		(net "P12V")
	)
	(via
		(at 33.147 -104.013)
		(size 0.508)
		(drill 0.254)
		(layers "F.Cu" "B.Cu")
		(net "P12V")
	)
	(via
		(at 23.622 -255.4478)
		(size 0.508)
		(drill 0.254)
		(layers "F.Cu" "B.Cu")
		(net "P12V")
	)
	(via
		(at 27.178 -399.5928)
		(size 0.508)
		(drill 0.254)
		(layers "F.Cu" "B.Cu")
		(net "P12V")
	)
	(via
		(at 213.36 -298.958)
		(size 0.508)
		(drill 0.254)
		(layers "F.Cu" "B.Cu")
		(net "P12V")
	)
	(via
		(at 14.6812 -498.2972)
		(size 0.508)
		(drill 0.254)
		(layers "F.Cu" "B.Cu")
		(net "P12V")
	)
	(via
		(at 237.49 -377.19)
		(size 0.7112)
		(drill 0.4064)
		(layers "F.Cu" "B.Cu")
		(net "P12V")
	)
	(via
		(at 5.715 -467.36)
		(size 0.7112)
		(drill 0.4064)
		(layers "F.Cu" "B.Cu")
		(net "P12V")
	)
	(via
		(at 46.8122 -9.017)
		(size 0.508)
		(drill 0.254)
		(layers "F.Cu" "B.Cu")
		(net "P12V")
	)
	(via
		(at 21.3106 -496.4176)
		(size 0.508)
		(drill 0.254)
		(layers "F.Cu" "B.Cu")
		(net "P12V")
	)
	(via
		(at 214.249 -92.964)
		(size 0.508)
		(drill 0.254)
		(layers "F.Cu" "B.Cu")
		(net "P12V")
	)
	(via
		(at 47.7012 -9.017)
		(size 0.508)
		(drill 0.254)
		(layers "F.Cu" "B.Cu")
		(net "P12V")
	)
	(via
		(at 240.03 -377.19)
		(size 0.7112)
		(drill 0.4064)
		(layers "F.Cu" "B.Cu")
		(net "P12V")
	)
	(via
		(at 20.4216 -497.3066)
		(size 0.508)
		(drill 0.254)
		(layers "F.Cu" "B.Cu")
		(net "P12V")
	)
	(via
		(at 32.258 -207.01)
		(size 0.508)
		(drill 0.254)
		(layers "F.Cu" "B.Cu")
		(net "P12V")
	)
	(via
		(at 45.9232 -9.906)
		(size 0.508)
		(drill 0.254)
		(layers "F.Cu" "B.Cu")
		(net "P12V")
	)
	(via
		(at 45.0342 -9.906)
		(size 0.508)
		(drill 0.254)
		(layers "F.Cu" "B.Cu")
		(net "P12V")
	)
	(via
		(at 25.2222 -51.054)
		(size 0.508)
		(drill 0.254)
		(layers "F.Cu" "B.Cu")
		(net "P12V")
	)
	(via
		(at 242.57 -367.03)
		(size 0.7112)
		(drill 0.4064)
		(layers "F.Cu" "B.Cu")
		(net "P12V")
	)
	(via
		(at 27.051 -195.961)
		(size 0.508)
		(drill 0.254)
		(layers "F.Cu" "B.Cu")
		(net "P12V")
	)
	(via
		(at 34.8742 -413.1564)
		(size 0.508)
		(drill 0.254)
		(layers "F.Cu" "B.Cu")
		(net "P12V")
	)
	(via
		(at 34.925 -310.896)
		(size 0.508)
		(drill 0.254)
		(layers "F.Cu" "B.Cu")
		(net "P12V")
	)
	(via
		(at 242.57 -364.49)
		(size 0.7112)
		(drill 0.4064)
		(layers "F.Cu" "B.Cu")
		(net "P12V")
	)
	(via
		(at 34.036 -310.007)
		(size 0.508)
		(drill 0.254)
		(layers "F.Cu" "B.Cu")
		(net "P12V")
	)
	(via
		(at 27.94 -92.075)
		(size 0.508)
		(drill 0.254)
		(layers "F.Cu" "B.Cu")
		(net "P12V")
	)
	(via
		(at 27.051 -195.072)
		(size 0.508)
		(drill 0.254)
		(layers "F.Cu" "B.Cu")
		(net "P12V")
	)
	(via
		(at 33.147 -104.902)
		(size 0.508)
		(drill 0.254)
		(layers "F.Cu" "B.Cu")
		(net "P12V")
	)
	(via
		(at 242.57 -377.19)
		(size 0.7112)
		(drill 0.4064)
		(layers "F.Cu" "B.Cu")
		(net "P12V")
	)
	(via
		(at 241.3 -373.38)
		(size 0.7112)
		(drill 0.3556)
		(layers "F.Cu" "B.Cu")
		(net "P12V")
	)
	(via
		(at 27.94 -298.958)
		(size 0.508)
		(drill 0.254)
		(layers "F.Cu" "B.Cu")
		(net "P12V")
	)
	(via
		(at 20.4216 -496.4176)
		(size 0.508)
		(drill 0.254)
		(layers "F.Cu" "B.Cu")
		(net "P12V")
	)
	(via
		(at 245.11 -379.73)
		(size 0.7112)
		(drill 0.4064)
		(layers "F.Cu" "B.Cu")
		(net "P12V")
	)
	(via
		(at 32.2072 -413.1564)
		(size 0.508)
		(drill 0.254)
		(layers "F.Cu" "B.Cu")
		(net "P12V")
	)
	(via
		(at 240.03 -372.11)
		(size 0.7112)
		(drill 0.4064)
		(layers "F.Cu" "B.Cu")
		(net "P12V")
	)
	(via
		(at 237.49 -372.11)
		(size 0.7112)
		(drill 0.4064)
		(layers "F.Cu" "B.Cu")
		(net "P12V")
	)
	(via
		(at 245.11 -382.27)
		(size 0.7112)
		(drill 0.4064)
		(layers "F.Cu" "B.Cu")
		(net "P12V")
	)
	(via
		(at 247.65 -369.57)
		(size 0.7112)
		(drill 0.4064)
		(layers "F.Cu" "B.Cu")
		(net "P12V")
	)
	(via
		(at 3.175 -467.36)
		(size 0.7112)
		(drill 0.4064)
		(layers "F.Cu" "B.Cu")
		(net "P12V")
	)
	(via
		(at 211.582 -92.075)
		(size 0.508)
		(drill 0.254)
		(layers "F.Cu" "B.Cu")
		(net "P12V")
	)
	(via
		(at 237.49 -379.73)
		(size 0.7112)
		(drill 0.4064)
		(layers "F.Cu" "B.Cu")
		(net "P12V")
	)
	(via
		(at 34.925 -310.007)
		(size 0.508)
		(drill 0.254)
		(layers "F.Cu" "B.Cu")
		(net "P12V")
	)
	(via
		(at 49.1236 -348.742)
		(size 0.508)
		(drill 0.254)
		(layers "F.Cu" "B.Cu")
		(net "P12V")
	)
	(via
		(at 4.445 -471.805)
		(size 0.7112)
		(drill 0.4064)
		(layers "F.Cu" "B.Cu")
		(net "P12V")
	)
	(via
		(at 5.715 -474.98)
		(size 0.7112)
		(drill 0.4064)
		(layers "F.Cu" "B.Cu")
		(net "P12V")
	)
	(via
		(at 5.715 -468.63)
		(size 0.7112)
		(drill 0.4064)
		(layers "F.Cu" "B.Cu")
		(net "P12V")
	)
	(via
		(at 202.270106 -492.888778)
		(size 0.508)
		(drill 0.254)
		(layers "F.Cu" "B.Cu")
		(net "P12V")
	)
	(via
		(at 28.829 -195.961)
		(size 0.508)
		(drill 0.254)
		(layers "F.Cu" "B.Cu")
		(net "P12V")
	)
	(via
		(at 25.4762 -462.4832)
		(size 0.508)
		(drill 0.254)
		(layers "F.Cu" "B.Cu")
		(net "P12V")
	)
	(via
		(at 241.3 -365.76)
		(size 0.7112)
		(drill 0.3556)
		(layers "F.Cu" "B.Cu")
		(net "P12V")
	)
	(via
		(at 32.258 -207.899)
		(size 0.508)
		(drill 0.254)
		(layers "F.Cu" "B.Cu")
		(net "P12V")
	)
	(via
		(at 27.051 -298.958)
		(size 0.508)
		(drill 0.254)
		(layers "F.Cu" "B.Cu")
		(net "P12V")
	)
	(via
		(at 211.582 -195.072)
		(size 0.508)
		(drill 0.254)
		(layers "F.Cu" "B.Cu")
		(net "P12V")
	)
	(via
		(at 223.863662 -420.179246)
		(size 0.508)
		(drill 0.254)
		(layers "F.Cu" "B.Cu")
		(net "P12V")
	)
	(via
		(at 240.03 -379.73)
		(size 0.7112)
		(drill 0.4064)
		(layers "F.Cu" "B.Cu")
		(net "P12V")
	)
	(via
		(at 50.2666 -452.501)
		(size 0.508)
		(drill 0.254)
		(layers "F.Cu" "B.Cu")
		(net "P12V")
	)
	(via
		(at 1.9304 -471.17)
		(size 0.7112)
		(drill 0.4064)
		(layers "F.Cu" "B.Cu")
		(net "P12V")
	)
	(via
		(at 18.6436 -496.4176)
		(size 0.508)
		(drill 0.254)
		(layers "F.Cu" "B.Cu")
		(net "P12V")
	)
	(via
		(at 240.03 -374.65)
		(size 0.7112)
		(drill 0.4064)
		(layers "F.Cu" "B.Cu")
		(net "P12V")
	)
	(via
		(at 32.258 -104.013)
		(size 0.508)
		(drill 0.254)
		(layers "F.Cu" "B.Cu")
		(net "P12V")
	)
	(via
		(at 29.718 -195.961)
		(size 0.508)
		(drill 0.254)
		(layers "F.Cu" "B.Cu")
		(net "P12V")
	)
	(via
		(at 28.829 -298.958)
		(size 0.508)
		(drill 0.254)
		(layers "F.Cu" "B.Cu")
		(net "P12V")
	)
	(via
		(at 235.29671 -142.494)
		(size 0.508)
		(drill 0.254)
		(layers "F.Cu" "B.Cu")
		(net "P12V")
	)
	(via
		(at 47.7012 -9.906)
		(size 0.508)
		(drill 0.254)
		(layers "F.Cu" "B.Cu")
		(net "P12V")
	)
	(via
		(at 242.57 -382.27)
		(size 0.7112)
		(drill 0.4064)
		(layers "F.Cu" "B.Cu")
		(net "P12V")
	)
	(via
		(at 34.925 -207.899)
		(size 0.508)
		(drill 0.254)
		(layers "F.Cu" "B.Cu")
		(net "P12V")
	)
	(via
		(at 28.829 -298.069)
		(size 0.508)
		(drill 0.254)
		(layers "F.Cu" "B.Cu")
		(net "P12V")
	)
	(via
		(at 235.3056 -451.485)
		(size 0.508)
		(drill 0.254)
		(layers "F.Cu" "B.Cu")
		(net "P12V")
	)
	(via
		(at 212.471 -298.958)
		(size 0.508)
		(drill 0.254)
		(layers "F.Cu" "B.Cu")
		(net "P12V")
	)
	(via
		(at 27.94 -195.961)
		(size 0.508)
		(drill 0.254)
		(layers "F.Cu" "B.Cu")
		(net "P12V")
	)
	(via
		(at 240.03 -364.49)
		(size 0.7112)
		(drill 0.4064)
		(layers "F.Cu" "B.Cu")
		(net "P12V")
	)
	(via
		(at 28.067 -400.4818)
		(size 0.508)
		(drill 0.254)
		(layers "F.Cu" "B.Cu")
		(net "P12V")
	)
	(via
		(at 211.582 -195.961)
		(size 0.508)
		(drill 0.254)
		(layers "F.Cu" "B.Cu")
		(net "P12V")
	)
	(via
		(at 4.445 -470.535)
		(size 0.7112)
		(drill 0.4064)
		(layers "F.Cu" "B.Cu")
		(net "P12V")
	)
	(via
		(at 212.471 -92.964)
		(size 0.508)
		(drill 0.254)
		(layers "F.Cu" "B.Cu")
		(net "P12V")
	)
	(via
		(at 213.36 -195.072)
		(size 0.508)
		(drill 0.254)
		(layers "F.Cu" "B.Cu")
		(net "P12V")
	)
	(via
		(at 5.715 -464.82)
		(size 0.7112)
		(drill 0.4064)
		(layers "F.Cu" "B.Cu")
		(net "P12V")
	)
	(via
		(at 5.715 -473.71)
		(size 0.7112)
		(drill 0.4064)
		(layers "F.Cu" "B.Cu")
		(net "P12V")
	)
	(via
		(at 212.471 -92.075)
		(size 0.508)
		(drill 0.254)
		(layers "F.Cu" "B.Cu")
		(net "P12V")
	)
	(via
		(at 213.36 -401.066)
		(size 0.508)
		(drill 0.254)
		(layers "F.Cu" "B.Cu")
		(net "P12V")
	)
	(via
		(at 202.270106 -491.999778)
		(size 0.508)
		(drill 0.254)
		(layers "F.Cu" "B.Cu")
		(net "P12V")
	)
	(via
		(at 247.65 -377.19)
		(size 0.7112)
		(drill 0.4064)
		(layers "F.Cu" "B.Cu")
		(net "P12V")
	)
	(via
		(at 33.9852 -413.1564)
		(size 0.508)
		(drill 0.254)
		(layers "F.Cu" "B.Cu")
		(net "P12V")
	)
	(via
		(at 212.471 -195.961)
		(size 0.508)
		(drill 0.254)
		(layers "F.Cu" "B.Cu")
		(net "P12V")
	)
	(via
		(at 5.715 -466.09)
		(size 0.7112)
		(drill 0.4064)
		(layers "F.Cu" "B.Cu")
		(net "P12V")
	)
	(via
		(at 235.292138 -39.497)
		(size 0.508)
		(drill 0.254)
		(layers "F.Cu" "B.Cu")
		(net "P12V")
	)
	(segment
		(start 82.7405 -186.8805)
		(end 62.992 -206.629)
		(width 0.17145)
		(layer "F.Cu")
		(net "I2C_MUX_RESET_PEB")
	)
	(segment
		(start 41.0464 -201.1934)
		(end 17.20723 -201.1934)
		(width 0.17145)
		(layer "F.Cu")
		(net "I2C_MUX_RESET_PEB")
	)
	(segment
		(start 12.065 -206.33563)
		(end 12.065 -228.981)
		(width 0.17145)
		(layer "F.Cu")
		(net "I2C_MUX_RESET_PEB")
	)
	(segment
		(start 46.482 -206.629)
		(end 41.0464 -201.1934)
		(width 0.17145)
		(layer "F.Cu")
		(net "I2C_MUX_RESET_PEB")
	)
	(segment
		(start 17.20723 -201.1934)
		(end 12.065 -206.33563)
		(width 0.17145)
		(layer "F.Cu")
		(net "I2C_MUX_RESET_PEB")
	)
	(segment
		(start 62.992 -206.629)
		(end 46.482 -206.629)
		(width 0.17145)
		(layer "F.Cu")
		(net "I2C_MUX_RESET_PEB")
	)
	(segment
		(start 82.7405 -154.686)
		(end 82.7405 -186.8805)
		(width 0.17145)
		(layer "F.Cu")
		(net "I2C_MUX_RESET_PEB")
	)
	(via
		(at 12.065 -228.981)
		(size 0.508)
		(drill 0.254)
		(layers "F.Cu" "B.Cu")
		(net "I2C_MUX_RESET_PEB")
	)
	(via
		(at 10.414 -230.632)
		(size 0.7112)
		(drill 0.3556)
		(layers "F.Cu" "B.Cu")
		(net "I2C_MUX_RESET_PEB")
	)
	(segment
		(start 10.414 -230.632)
		(end 12.065 -228.981)
		(width 0.17145)
		(layer "B.Cu")
		(net "I2C_MUX_RESET_PEB")
	)
	(segment
		(start 6.703822 -234.342178)
		(end 10.414 -230.632)
		(width 0.17145)
		(layer "B.Cu")
		(net "I2C_MUX_RESET_PEB")
	)
	(segment
		(start 1.868932 -234.342178)
		(end 6.703822 -234.342178)
		(width 0.17145)
		(layer "B.Cu")
		(net "I2C_MUX_RESET_PEB")
	)
	(segment
		(start 81.153 -353.6315)
		(end 81.153 -352.806)
		(width 0.17145)
		(layer "F.Cu")
		(net "I2C_MUX_RESET")
	)
	(segment
		(start 83.6295 -153.67)
		(end 84.455 -153.67)
		(width 0.17145)
		(layer "F.Cu")
		(net "I2C_MUX_RESET")
	)
	(segment
		(start 83.6295 -154.686)
		(end 83.6295 -153.67)
		(width 0.17145)
		(layer "F.Cu")
		(net "I2C_MUX_RESET")
	)
	(via
		(at 79.121 -349.123)
		(size 0.7112)
		(drill 0.3556)
		(layers "F.Cu" "B.Cu")
		(net "I2C_MUX_RESET")
	)
	(via
		(at 81.153 -352.806)
		(size 0.508)
		(drill 0.254)
		(layers "F.Cu" "B.Cu")
		(net "I2C_MUX_RESET")
	)
	(via
		(at 84.455 -153.67)
		(size 0.508)
		(drill 0.254)
		(layers "F.Cu" "B.Cu")
		(net "I2C_MUX_RESET")
	)
	(segment
		(start 84.201 -294.64)
		(end 84.201 -300.9392)
		(width 0.17145)
		(layer "B.Cu")
		(net "I2C_MUX_RESET")
	)
	(segment
		(start 82.781648 -316.207648)
		(end 82.781648 -343.684352)
		(width 0.17145)
		(layer "B.Cu")
		(net "I2C_MUX_RESET")
	)
	(segment
		(start 81.0514 -314.4774)
		(end 82.781648 -316.207648)
		(width 0.17145)
		(layer "B.Cu")
		(net "I2C_MUX_RESET")
	)
	(segment
		(start 83.058 -212.344)
		(end 83.058 -214.9094)
		(width 0.17145)
		(layer "B.Cu")
		(net "I2C_MUX_RESET")
	)
	(segment
		(start 82.781648 -343.684352)
		(end 79.121 -347.345)
		(width 0.17145)
		(layer "B.Cu")
		(net "I2C_MUX_RESET")
	)
	(segment
		(start 81.0514 -306.07)
		(end 81.0514 -314.4774)
		(width 0.17145)
		(layer "B.Cu")
		(net "I2C_MUX_RESET")
	)
	(segment
		(start 74.463148 -163.058348)
		(end 76.962 -165.5572)
		(width 0.17145)
		(layer "B.Cu")
		(net "I2C_MUX_RESET")
	)
	(segment
		(start 79.121 -349.123)
		(end 79.121 -349.758)
		(width 0.17145)
		(layer "B.Cu")
		(net "I2C_MUX_RESET")
	)
	(segment
		(start 84.455 -153.67)
		(end 76.708 -153.67)
		(width 0.17145)
		(layer "B.Cu")
		(net "I2C_MUX_RESET")
	)
	(segment
		(start 79.121 -349.758)
		(end 81.153 -351.79)
		(width 0.17145)
		(layer "B.Cu")
		(net "I2C_MUX_RESET")
	)
	(segment
		(start 76.962 -206.248)
		(end 83.058 -212.344)
		(width 0.17145)
		(layer "B.Cu")
		(net "I2C_MUX_RESET")
	)
	(segment
		(start 75.803252 -154.574748)
		(end 75.803252 -155.76677)
		(width 0.17145)
		(layer "B.Cu")
		(net "I2C_MUX_RESET")
	)
	(segment
		(start 83.566 -303.5554)
		(end 81.0514 -306.07)
		(width 0.17145)
		(layer "B.Cu")
		(net "I2C_MUX_RESET")
	)
	(segment
		(start 83.566 -301.5742)
		(end 83.566 -303.5554)
		(width 0.17145)
		(layer "B.Cu")
		(net "I2C_MUX_RESET")
	)
	(segment
		(start 84.201 -300.9392)
		(end 83.566 -301.5742)
		(width 0.17145)
		(layer "B.Cu")
		(net "I2C_MUX_RESET")
	)
	(segment
		(start 75.803252 -155.76677)
		(end 74.463148 -157.106874)
		(width 0.17145)
		(layer "B.Cu")
		(net "I2C_MUX_RESET")
	)
	(segment
		(start 83.058 -214.9094)
		(end 83.5025 -215.3539)
		(width 0.17145)
		(layer "B.Cu")
		(net "I2C_MUX_RESET")
	)
	(segment
		(start 74.463148 -157.106874)
		(end 74.463148 -163.058348)
		(width 0.17145)
		(layer "B.Cu")
		(net "I2C_MUX_RESET")
	)
	(segment
		(start 83.5025 -293.9415)
		(end 84.201 -294.64)
		(width 0.17145)
		(layer "B.Cu")
		(net "I2C_MUX_RESET")
	)
	(segment
		(start 76.962 -165.5572)
		(end 76.962 -206.248)
		(width 0.17145)
		(layer "B.Cu")
		(net "I2C_MUX_RESET")
	)
	(segment
		(start 81.153 -351.79)
		(end 81.153 -352.806)
		(width 0.17145)
		(layer "B.Cu")
		(net "I2C_MUX_RESET")
	)
	(segment
		(start 83.5025 -215.3539)
		(end 83.5025 -293.9415)
		(width 0.17145)
		(layer "B.Cu")
		(net "I2C_MUX_RESET")
	)
	(segment
		(start 79.121 -347.345)
		(end 79.121 -349.123)
		(width 0.17145)
		(layer "B.Cu")
		(net "I2C_MUX_RESET")
	)
	(segment
		(start 76.708 -153.67)
		(end 75.803252 -154.574748)
		(width 0.17145)
		(layer "B.Cu")
		(net "I2C_MUX_RESET")
	)
	(segment
		(start 245.259352 -422.887648)
		(end 243.881148 -422.887648)
		(width 0.17145)
		(layer "F.Cu")
		(net "I2C_C_SDA")
	)
	(segment
		(start 243.5225 -422.529)
		(end 243.586 -422.5925)
		(width 0.17145)
		(layer "F.Cu")
		(net "I2C_C_SDA")
	)
	(segment
		(start 246.253 -421.894)
		(end 245.259352 -422.887648)
		(width 0.17145)
		(layer "F.Cu")
		(net "I2C_C_SDA")
	)
	(segment
		(start 248.793 -422.2115)
		(end 248.793 -422.716198)
		(width 0.17145)
		(layer "F.Cu")
		(net "I2C_C_SDA")
	)
	(segment
		(start 242.5065 -422.529)
		(end 243.5225 -422.529)
		(width 0.17145)
		(layer "F.Cu")
		(net "I2C_C_SDA")
	)
	(segment
		(start 243.881148 -422.887648)
		(end 243.586 -422.5925)
		(width 0.17145)
		(layer "F.Cu")
		(net "I2C_C_SDA")
	)
	(segment
		(start 248.793 -422.716198)
		(end 248.62155 -422.887648)
		(width 0.17145)
		(layer "F.Cu")
		(net "I2C_C_SDA")
	)
	(segment
		(start 248.62155 -422.887648)
		(end 247.246648 -422.887648)
		(width 0.17145)
		(layer "F.Cu")
		(net "I2C_C_SDA")
	)
	(segment
		(start 247.246648 -422.887648)
		(end 246.253 -421.894)
		(width 0.17145)
		(layer "F.Cu")
		(net "I2C_C_SDA")
	)
	(via
		(at 248.793 -422.2115)
		(size 0.5588)
		(drill 0.3048)
		(layers "F.Cu" "B.Cu")
		(net "I2C_C_SDA")
	)
	(segment
		(start 251.818902 -422.887648)
		(end 252.786642 -421.919908)
		(width 0.17145)
		(layer "B.Cu")
		(net "I2C_C_SDA")
	)
	(segment
		(start 248.793 -422.2115)
		(end 248.793 -422.7068)
		(width 0.17145)
		(layer "B.Cu")
		(net "I2C_C_SDA")
	)
	(segment
		(start 252.786642 -421.919908)
		(end 256.093976 -421.919908)
		(width 0.17145)
		(layer "B.Cu")
		(net "I2C_C_SDA")
	)
	(segment
		(start 248.973848 -422.887648)
		(end 251.818902 -422.887648)
		(width 0.17145)
		(layer "B.Cu")
		(net "I2C_C_SDA")
	)
	(segment
		(start 248.793 -422.7068)
		(end 248.973848 -422.887648)
		(width 0.17145)
		(layer "B.Cu")
		(net "I2C_C_SDA")
	)
	(segment
		(start 247.246902 -423.440098)
		(end 246.253 -424.434)
		(width 0.17145)
		(layer "F.Cu")
		(net "I2C_C_SCL")
	)
	(segment
		(start 242.5065 -423.799)
		(end 243.5225 -423.799)
		(width 0.17145)
		(layer "F.Cu")
		(net "I2C_C_SCL")
	)
	(segment
		(start 246.253 -424.434)
		(end 245.259098 -423.440098)
		(width 0.17145)
		(layer "F.Cu")
		(net "I2C_C_SCL")
	)
	(segment
		(start 243.5225 -423.799)
		(end 243.586 -423.7355)
		(width 0.17145)
		(layer "F.Cu")
		(net "I2C_C_SCL")
	)
	(segment
		(start 245.259098 -423.440098)
		(end 243.881402 -423.440098)
		(width 0.17145)
		(layer "F.Cu")
		(net "I2C_C_SCL")
	)
	(segment
		(start 248.793 -423.611548)
		(end 248.62155 -423.440098)
		(width 0.17145)
		(layer "F.Cu")
		(net "I2C_C_SCL")
	)
	(segment
		(start 248.62155 -423.440098)
		(end 247.246902 -423.440098)
		(width 0.17145)
		(layer "F.Cu")
		(net "I2C_C_SCL")
	)
	(segment
		(start 243.881402 -423.440098)
		(end 243.586 -423.7355)
		(width 0.17145)
		(layer "F.Cu")
		(net "I2C_C_SCL")
	)
	(segment
		(start 248.793 -424.1165)
		(end 248.793 -423.611548)
		(width 0.17145)
		(layer "F.Cu")
		(net "I2C_C_SCL")
	)
	(via
		(at 248.793 -424.1165)
		(size 0.5588)
		(drill 0.3048)
		(layers "F.Cu" "B.Cu")
		(net "I2C_C_SCL")
	)
	(segment
		(start 252.832108 -424.459908)
		(end 256.093976 -424.459908)
		(width 0.17145)
		(layer "B.Cu")
		(net "I2C_C_SCL")
	)
	(segment
		(start 248.793 -423.6212)
		(end 248.974102 -423.440098)
		(width 0.17145)
		(layer "B.Cu")
		(net "I2C_C_SCL")
	)
	(segment
		(start 248.793 -424.1165)
		(end 248.793 -423.6212)
		(width 0.17145)
		(layer "B.Cu")
		(net "I2C_C_SCL")
	)
	(segment
		(start 248.974102 -423.440098)
		(end 251.812298 -423.440098)
		(width 0.17145)
		(layer "B.Cu")
		(net "I2C_C_SCL")
	)
	(segment
		(start 251.812298 -423.440098)
		(end 252.832108 -424.459908)
		(width 0.17145)
		(layer "B.Cu")
		(net "I2C_C_SCL")
	)
	(segment
		(start 27.773884 -378.674884)
		(end 28.945078 -378.674884)
		(width 0.17145)
		(layer "F.Cu")
		(net "I2C_B_TMP4_ALERT")
	)
	(segment
		(start 26.416 -376.428)
		(end 26.416 -377.317)
		(width 0.17145)
		(layer "F.Cu")
		(net "I2C_B_TMP4_ALERT")
	)
	(segment
		(start 26.416 -377.317)
		(end 27.773884 -378.674884)
		(width 0.17145)
		(layer "F.Cu")
		(net "I2C_B_TMP4_ALERT")
	)
	(segment
		(start 33.02 -376.428)
		(end 33.02 -376.809)
		(width 0.17145)
		(layer "F.Cu")
		(net "I2C_B_TMP4_A2")
	)
	(segment
		(start 33.02 -376.809)
		(end 33.054798 -376.843798)
		(width 0.17145)
		(layer "F.Cu")
		(net "I2C_B_TMP4_A2")
	)
	(segment
		(start 33.054798 -376.843798)
		(end 33.054798 -378.024644)
		(width 0.17145)
		(layer "F.Cu")
		(net "I2C_B_TMP4_A2")
	)
	(segment
		(start 33.02 -375.0945)
		(end 33.02 -376.428)
		(width 0.17145)
		(layer "F.Cu")
		(net "I2C_B_TMP4_A2")
	)
	(segment
		(start 33.02 -375.0945)
		(end 32.004 -375.0945)
		(width 0.17145)
		(layer "F.Cu")
		(net "I2C_B_TMP4_A2")
	)
	(via
		(at 33.02 -376.428)
		(size 0.7112)
		(drill 0.3556)
		(layers "F.Cu" "B.Cu")
		(net "I2C_B_TMP4_A2")
	)
	(segment
		(start 30.988 -375.0945)
		(end 29.972 -375.0945)
		(width 0.17145)
		(layer "F.Cu")
		(net "I2C_B_TMP4_A1")
	)
	(segment
		(start 30.988 -376.428)
		(end 30.988 -377.317)
		(width 0.17145)
		(layer "F.Cu")
		(net "I2C_B_TMP4_A1")
	)
	(segment
		(start 30.988 -376.428)
		(end 30.988 -375.0945)
		(width 0.17145)
		(layer "F.Cu")
		(net "I2C_B_TMP4_A1")
	)
	(segment
		(start 30.988 -377.317)
		(end 32.345884 -378.674884)
		(width 0.17145)
		(layer "F.Cu")
		(net "I2C_B_TMP4_A1")
	)
	(segment
		(start 32.345884 -378.674884)
		(end 33.054798 -378.674884)
		(width 0.17145)
		(layer "F.Cu")
		(net "I2C_B_TMP4_A1")
	)
	(via
		(at 30.988 -376.428)
		(size 0.7112)
		(drill 0.3556)
		(layers "F.Cu" "B.Cu")
		(net "I2C_B_TMP4_A1")
	)
	(segment
		(start 31.853124 -379.325124)
		(end 28.956 -376.428)
		(width 0.17145)
		(layer "F.Cu")
		(net "I2C_B_TMP4_A0")
	)
	(segment
		(start 28.956 -375.0945)
		(end 28.956 -376.428)
		(width 0.17145)
		(layer "F.Cu")
		(net "I2C_B_TMP4_A0")
	)
	(segment
		(start 28.956 -375.0945)
		(end 27.94 -375.0945)
		(width 0.17145)
		(layer "F.Cu")
		(net "I2C_B_TMP4_A0")
	)
	(segment
		(start 33.054798 -379.325124)
		(end 31.853124 -379.325124)
		(width 0.17145)
		(layer "F.Cu")
		(net "I2C_B_TMP4_A0")
	)
	(via
		(at 28.956 -376.428)
		(size 0.7112)
		(drill 0.3556)
		(layers "F.Cu" "B.Cu")
		(net "I2C_B_TMP4_A0")
	)
	(segment
		(start 205.867 -47.371)
		(end 205.867 -46.482)
		(width 0.17145)
		(layer "F.Cu")
		(net "I2C_B_TMP3_ALERT")
	)
	(segment
		(start 208.4451 -48.674782)
		(end 207.170782 -48.674782)
		(width 0.17145)
		(layer "F.Cu")
		(net "I2C_B_TMP3_ALERT")
	)
	(segment
		(start 207.170782 -48.674782)
		(end 205.867 -47.371)
		(width 0.17145)
		(layer "F.Cu")
		(net "I2C_B_TMP3_ALERT")
	)
	(segment
		(start 212.471 -46.863)
		(end 212.55482 -46.94682)
		(width 0.17145)
		(layer "F.Cu")
		(net "I2C_B_TMP3_A2")
	)
	(segment
		(start 212.55482 -46.94682)
		(end 212.55482 -48.024542)
		(width 0.17145)
		(layer "F.Cu")
		(net "I2C_B_TMP3_A2")
	)
	(segment
		(start 212.471 -46.482)
		(end 212.471 -46.863)
		(width 0.17145)
		(layer "F.Cu")
		(net "I2C_B_TMP3_A2")
	)
	(segment
		(start 212.471 -45.1485)
		(end 212.471 -46.482)
		(width 0.17145)
		(layer "F.Cu")
		(net "I2C_B_TMP3_A2")
	)
	(segment
		(start 211.455 -45.1485)
		(end 212.471 -45.1485)
		(width 0.17145)
		(layer "F.Cu")
		(net "I2C_B_TMP3_A2")
	)
	(via
		(at 212.471 -46.482)
		(size 0.7112)
		(drill 0.3556)
		(layers "F.Cu" "B.Cu")
		(net "I2C_B_TMP3_A2")
	)
	(segment
		(start 210.439 -46.482)
		(end 210.439 -47.371)
		(width 0.17145)
		(layer "F.Cu")
		(net "I2C_B_TMP3_A1")
	)
	(segment
		(start 210.439 -45.1485)
		(end 210.439 -46.482)
		(width 0.17145)
		(layer "F.Cu")
		(net "I2C_B_TMP3_A1")
	)
	(segment
		(start 211.742782 -48.674782)
		(end 212.55482 -48.674782)
		(width 0.17145)
		(layer "F.Cu")
		(net "I2C_B_TMP3_A1")
	)
	(segment
		(start 210.439 -45.1485)
		(end 209.423 -45.1485)
		(width 0.17145)
		(layer "F.Cu")
		(net "I2C_B_TMP3_A1")
	)
	(segment
		(start 210.439 -47.371)
		(end 211.742782 -48.674782)
		(width 0.17145)
		(layer "F.Cu")
		(net "I2C_B_TMP3_A1")
	)
	(via
		(at 210.439 -46.482)
		(size 0.7112)
		(drill 0.3556)
		(layers "F.Cu" "B.Cu")
		(net "I2C_B_TMP3_A1")
	)
	(segment
		(start 211.250022 -49.325022)
		(end 208.407 -46.482)
		(width 0.17145)
		(layer "F.Cu")
		(net "I2C_B_TMP3_A0")
	)
	(segment
		(start 208.407 -46.482)
		(end 208.407 -45.1485)
		(width 0.17145)
		(layer "F.Cu")
		(net "I2C_B_TMP3_A0")
	)
	(segment
		(start 207.391 -45.1485)
		(end 208.407 -45.1485)
		(width 0.17145)
		(layer "F.Cu")
		(net "I2C_B_TMP3_A0")
	)
	(segment
		(start 212.55482 -49.325022)
		(end 211.250022 -49.325022)
		(width 0.17145)
		(layer "F.Cu")
		(net "I2C_B_TMP3_A0")
	)
	(via
		(at 208.407 -46.482)
		(size 0.7112)
		(drill 0.3556)
		(layers "F.Cu" "B.Cu")
		(net "I2C_B_TMP3_A0")
	)
	(segment
		(start 207.214978 -458.674978)
		(end 205.867 -457.327)
		(width 0.17145)
		(layer "F.Cu")
		(net "I2C_B_TMP2_ALERT")
	)
	(segment
		(start 205.867 -457.327)
		(end 205.867 -456.438)
		(width 0.17145)
		(layer "F.Cu")
		(net "I2C_B_TMP2_ALERT")
	)
	(segment
		(start 208.4451 -458.674978)
		(end 207.214978 -458.674978)
		(width 0.17145)
		(layer "F.Cu")
		(net "I2C_B_TMP2_ALERT")
	)
	(segment
		(start 212.55482 -456.60818)
		(end 212.725 -456.438)
		(width 0.17145)
		(layer "F.Cu")
		(net "I2C_B_TMP2_A2")
	)
	(segment
		(start 212.725 -456.438)
		(end 212.725 -455.1045)
		(width 0.17145)
		(layer "F.Cu")
		(net "I2C_B_TMP2_A2")
	)
	(segment
		(start 212.55482 -458.024738)
		(end 212.55482 -456.60818)
		(width 0.17145)
		(layer "F.Cu")
		(net "I2C_B_TMP2_A2")
	)
	(segment
		(start 213.741 -455.1045)
		(end 212.725 -455.1045)
		(width 0.17145)
		(layer "F.Cu")
		(net "I2C_B_TMP2_A2")
	)
	(via
		(at 212.725 -456.438)
		(size 0.7112)
		(drill 0.3556)
		(layers "F.Cu" "B.Cu")
		(net "I2C_B_TMP2_A2")
	)
	(segment
		(start 211.786978 -458.674978)
		(end 212.55482 -458.674978)
		(width 0.17145)
		(layer "F.Cu")
		(net "I2C_B_TMP2_A1")
	)
	(segment
		(start 210.693 -455.1045)
		(end 209.677 -455.1045)
		(width 0.17145)
		(layer "F.Cu")
		(net "I2C_B_TMP2_A1")
	)
	(segment
		(start 210.693 -456.438)
		(end 210.693 -457.581)
		(width 0.17145)
		(layer "F.Cu")
		(net "I2C_B_TMP2_A1")
	)
	(segment
		(start 210.693 -455.1045)
		(end 210.693 -456.438)
		(width 0.17145)
		(layer "F.Cu")
		(net "I2C_B_TMP2_A1")
	)
	(segment
		(start 210.693 -457.581)
		(end 211.786978 -458.674978)
		(width 0.17145)
		(layer "F.Cu")
		(net "I2C_B_TMP2_A1")
	)
	(via
		(at 210.693 -456.438)
		(size 0.7112)
		(drill 0.3556)
		(layers "F.Cu" "B.Cu")
		(net "I2C_B_TMP2_A1")
	)
	(segment
		(start 212.55482 -459.325218)
		(end 211.294218 -459.325218)
		(width 0.17145)
		(layer "F.Cu")
		(net "I2C_B_TMP2_A0")
	)
	(segment
		(start 208.8515 -457.2635)
		(end 208.026 -456.438)
		(width 0.17145)
		(layer "F.Cu")
		(net "I2C_B_TMP2_A0")
	)
	(segment
		(start 207.01 -455.1045)
		(end 208.026 -455.1045)
		(width 0.17145)
		(layer "F.Cu")
		(net "I2C_B_TMP2_A0")
	)
	(segment
		(start 209.2325 -457.2635)
		(end 208.8515 -457.2635)
		(width 0.17145)
		(layer "F.Cu")
		(net "I2C_B_TMP2_A0")
	)
	(segment
		(start 211.294218 -459.325218)
		(end 209.2325 -457.2635)
		(width 0.17145)
		(layer "F.Cu")
		(net "I2C_B_TMP2_A0")
	)
	(segment
		(start 208.026 -456.438)
		(end 208.026 -455.1045)
		(width 0.17145)
		(layer "F.Cu")
		(net "I2C_B_TMP2_A0")
	)
	(via
		(at 208.026 -456.438)
		(size 0.7112)
		(drill 0.3556)
		(layers "F.Cu" "B.Cu")
		(net "I2C_B_TMP2_A0")
	)
	(segment
		(start 197.476872 -459.8924)
		(end 202.6539 -459.8924)
		(width 0.17145)
		(layer "F.Cu")
		(net "I2C_B_SDA")
	)
	(segment
		(start 94.74327 -445.880236)
		(end 94.9706 -446.107566)
		(width 0.17145)
		(layer "F.Cu")
		(net "I2C_B_SDA")
	)
	(segment
		(start 112.13465 -72.897746)
		(end 112.13465 -75.95235)
		(width 0.17145)
		(layer "F.Cu")
		(net "I2C_B_SDA")
	)
	(segment
		(start 178.344322 -440.75985)
		(end 197.476872 -459.8924)
		(width 0.17145)
		(layer "F.Cu")
		(net "I2C_B_SDA")
	)
	(segment
		(start 69.4436 -438.23763)
		(end 69.4436 -437.6801)
		(width 0.17145)
		(layer "F.Cu")
		(net "I2C_B_SDA")
	)
	(segment
		(start 69.240146 -438.441084)
		(end 69.4182 -438.619138)
		(width 0.17145)
		(layer "F.Cu")
		(net "I2C_B_SDA")
	)
	(segment
		(start 69.240146 -438.441084)
		(end 69.4436 -438.23763)
		(width 0.17145)
		(layer "F.Cu")
		(net "I2C_B_SDA")
	)
	(segment
		(start 89.301574 -32.554926)
		(end 89.301574 -50.06467)
		(width 0.17145)
		(layer "F.Cu")
		(net "I2C_B_SDA")
	)
	(segment
		(start 69.4182 -438.619138)
		(end 69.4182 -439.5343)
		(width 0.17145)
		(layer "F.Cu")
		(net "I2C_B_SDA")
	)
	(segment
		(start 21.58365 -380.24435)
		(end 21.58365 -391.075418)
		(width 0.17145)
		(layer "F.Cu")
		(net "I2C_B_SDA")
	)
	(segment
		(start 201.255122 -50.140108)
		(end 201.462132 -49.933098)
		(width 0.17145)
		(layer "F.Cu")
		(net "I2C_B_SDA")
	)
	(segment
		(start 47.28845 -134.63905)
		(end 47.0535 -134.874)
		(width 0.17145)
		(layer "F.Cu")
		(net "I2C_B_SDA")
	)
	(segment
		(start 21.58365 -391.075418)
		(end 21.795232 -391.287)
		(width 0.17145)
		(layer "F.Cu")
		(net "I2C_B_SDA")
	)
	(segment
		(start 108.554774 -76.934568)
		(end 108.554774 -77.352398)
		(width 0.17145)
		(layer "F.Cu")
		(net "I2C_B_SDA")
	)
	(segment
		(start 94.9706 -447.008504)
		(end 95.732346 -447.77025)
		(width 0.17145)
		(layer "F.Cu")
		(net "I2C_B_SDA")
	)
	(segment
		(start 202.6539 -459.8924)
		(end 203.0095 -460.248)
		(width 0.17145)
		(layer "F.Cu")
		(net "I2C_B_SDA")
	)
	(segment
		(start 94.9706 -446.107566)
		(end 94.9706 -447.008504)
		(width 0.17145)
		(layer "F.Cu")
		(net "I2C_B_SDA")
	)
	(segment
		(start 47.758858 -134.63905)
		(end 47.28845 -134.63905)
		(width 0.17145)
		(layer "F.Cu")
		(net "I2C_B_SDA")
	)
	(segment
		(start 23.14575 -379.82525)
		(end 22.00275 -379.82525)
		(width 0.17145)
		(layer "F.Cu")
		(net "I2C_B_SDA")
	)
	(segment
		(start 201.462132 -49.933098)
		(end 202.650598 -49.933098)
		(width 0.17145)
		(layer "F.Cu")
		(net "I2C_B_SDA")
	)
	(segment
		(start 22.00275 -379.82525)
		(end 21.58365 -380.24435)
		(width 0.17145)
		(layer "F.Cu")
		(net "I2C_B_SDA")
	)
	(segment
		(start 105.359454 -440.75985)
		(end 178.344322 -440.75985)
		(width 0.17145)
		(layer "F.Cu")
		(net "I2C_B_SDA")
	)
	(segment
		(start 89.301574 -50.06467)
		(end 112.13465 -72.897746)
		(width 0.17145)
		(layer "F.Cu")
		(net "I2C_B_SDA")
	)
	(segment
		(start 108.806742 -76.6826)
		(end 108.554774 -76.934568)
		(width 0.17145)
		(layer "F.Cu")
		(net "I2C_B_SDA")
	)
	(segment
		(start 89.535 -32.3215)
		(end 89.301574 -32.554926)
		(width 0.17145)
		(layer "F.Cu")
		(net "I2C_B_SDA")
	)
	(segment
		(start 95.732346 -447.77025)
		(end 98.349054 -447.77025)
		(width 0.17145)
		(layer "F.Cu")
		(net "I2C_B_SDA")
	)
	(segment
		(start 98.349054 -447.77025)
		(end 105.359454 -440.75985)
		(width 0.17145)
		(layer "F.Cu")
		(net "I2C_B_SDA")
	)
	(segment
		(start 112.13465 -75.95235)
		(end 111.4044 -76.6826)
		(width 0.17145)
		(layer "F.Cu")
		(net "I2C_B_SDA")
	)
	(segment
		(start 69.4436 -437.6801)
		(end 69.1515 -437.388)
		(width 0.17145)
		(layer "F.Cu")
		(net "I2C_B_SDA")
	)
	(segment
		(start 108.554774 -77.352398)
		(end 108.585 -77.382624)
		(width 0.17145)
		(layer "F.Cu")
		(net "I2C_B_SDA")
	)
	(segment
		(start 69.215 -436.3085)
		(end 69.215 -437.3245)
		(width 0.17145)
		(layer "F.Cu")
		(net "I2C_B_SDA")
	)
	(segment
		(start 69.4182 -439.5343)
		(end 69.215 -439.7375)
		(width 0.17145)
		(layer "F.Cu")
		(net "I2C_B_SDA")
	)
	(segment
		(start 23.5585 -380.238)
		(end 23.14575 -379.82525)
		(width 0.17145)
		(layer "F.Cu")
		(net "I2C_B_SDA")
	)
	(segment
		(start 111.4044 -76.6826)
		(end 108.806742 -76.6826)
		(width 0.17145)
		(layer "F.Cu")
		(net "I2C_B_SDA")
	)
	(segment
		(start 47.968916 -134.849108)
		(end 47.758858 -134.63905)
		(width 0.17145)
		(layer "F.Cu")
		(net "I2C_B_SDA")
	)
	(segment
		(start 202.650598 -49.933098)
		(end 203.0095 -50.292)
		(width 0.17145)
		(layer "F.Cu")
		(net "I2C_B_SDA")
	)
	(segment
		(start 69.215 -437.3245)
		(end 69.1515 -437.388)
		(width 0.17145)
		(layer "F.Cu")
		(net "I2C_B_SDA")
	)
	(via
		(at 201.255122 -50.140108)
		(size 0.508)
		(drill 0.254)
		(layers "F.Cu" "B.Cu")
		(net "I2C_B_SDA")
	)
	(via
		(at 21.795232 -391.287)
		(size 0.508)
		(drill 0.254)
		(layers "F.Cu" "B.Cu")
		(net "I2C_B_SDA")
	)
	(via
		(at 69.240146 -438.441084)
		(size 0.508)
		(drill 0.254)
		(layers "F.Cu" "B.Cu")
		(net "I2C_B_SDA")
	)
	(via
		(at 47.968916 -134.849108)
		(size 0.508)
		(drill 0.254)
		(layers "F.Cu" "B.Cu")
		(net "I2C_B_SDA")
	)
	(via
		(at 108.585 -77.382624)
		(size 0.5588)
		(drill 0.3048)
		(layers "F.Cu" "B.Cu")
		(net "I2C_B_SDA")
	)
	(via
		(at 94.74327 -445.880236)
		(size 0.508)
		(drill 0.254)
		(layers "F.Cu" "B.Cu")
		(net "I2C_B_SDA")
	)
	(segment
		(start 47.809658 -134.68985)
		(end 47.968916 -134.849108)
		(width 0.17145)
		(layer "B.Cu")
		(net "I2C_B_SDA")
	)
	(segment
		(start 94.111826 -447.7512)
		(end 93.3704 -447.7512)
		(width 0.17145)
		(layer "B.Cu")
		(net "I2C_B_SDA")
	)
	(segment
		(start 201.070464 -49.95545)
		(end 201.255122 -50.140108)
		(width 0.17145)
		(layer "B.Cu")
		(net "I2C_B_SDA")
	)
	(segment
		(start 29.972 -218.5162)
		(end 29.972 -214.0712)
		(width 0.17145)
		(layer "B.Cu")
		(net "I2C_B_SDA")
	)
	(segment
		(start 69.4436 -438.23763)
		(end 69.240146 -438.441084)
		(width 0.17145)
		(layer "B.Cu")
		(net "I2C_B_SDA")
	)
	(segment
		(start 30.8356 -213.2076)
		(end 40.6654 -213.2076)
		(width 0.17145)
		(layer "B.Cu")
		(net "I2C_B_SDA")
	)
	(segment
		(start 94.90075 -446.037716)
		(end 94.90075 -446.962276)
		(width 0.17145)
		(layer "B.Cu")
		(net "I2C_B_SDA")
	)
	(segment
		(start 35.492436 -391.92454)
		(end 47.34179 -391.92454)
		(width 0.17145)
		(layer "B.Cu")
		(net "I2C_B_SDA")
	)
	(segment
		(start 26.162 -415.29)
		(end 21.6662 -410.7942)
		(width 0.17145)
		(layer "B.Cu")
		(net "I2C_B_SDA")
	)
	(segment
		(start 52.832 -195.453)
		(end 52.832 -150.6728)
		(width 0.17145)
		(layer "B.Cu")
		(net "I2C_B_SDA")
	)
	(segment
		(start 46.61535 -134.68985)
		(end 47.809658 -134.68985)
		(width 0.17145)
		(layer "B.Cu")
		(net "I2C_B_SDA")
	)
	(segment
		(start 107.904026 -76.70165)
		(end 108.585 -77.382624)
		(width 0.17145)
		(layer "B.Cu")
		(net "I2C_B_SDA")
	)
	(segment
		(start 50.08245 -95.097854)
		(end 68.478654 -76.70165)
		(width 0.17145)
		(layer "B.Cu")
		(net "I2C_B_SDA")
	)
	(segment
		(start 45.0596 -203.2254)
		(end 52.832 -195.453)
		(width 0.17145)
		(layer "B.Cu")
		(net "I2C_B_SDA")
	)
	(segment
		(start 56.53405 -342.53805)
		(end 54.483 -340.487)
		(width 0.17145)
		(layer "B.Cu")
		(net "I2C_B_SDA")
	)
	(segment
		(start 68.478654 -76.70165)
		(end 107.904026 -76.70165)
		(width 0.17145)
		(layer "B.Cu")
		(net "I2C_B_SDA")
	)
	(segment
		(start 66.7766 -444.2968)
		(end 54.12613 -444.2968)
		(width 0.17145)
		(layer "B.Cu")
		(net "I2C_B_SDA")
	)
	(segment
		(start 21.6662 -410.7942)
		(end 21.6662 -391.416032)
		(width 0.17145)
		(layer "B.Cu")
		(net "I2C_B_SDA")
	)
	(segment
		(start 47.34179 -391.92454)
		(end 56.53405 -382.73228)
		(width 0.17145)
		(layer "B.Cu")
		(net "I2C_B_SDA")
	)
	(segment
		(start 42.77233 -432.943)
		(end 35.56 -432.943)
		(width 0.17145)
		(layer "B.Cu")
		(net "I2C_B_SDA")
	)
	(segment
		(start 52.832 -150.6728)
		(end 45.847 -143.6878)
		(width 0.17145)
		(layer "B.Cu")
		(net "I2C_B_SDA")
	)
	(segment
		(start 21.59 -391.081768)
		(end 21.59 -390.017)
		(width 0.17145)
		(layer "B.Cu")
		(net "I2C_B_SDA")
	)
	(segment
		(start 77.390244 -440.889644)
		(end 72.77735 -436.27675)
		(width 0.17145)
		(layer "B.Cu")
		(net "I2C_B_SDA")
	)
	(segment
		(start 29.972 -214.0712)
		(end 30.8356 -213.2076)
		(width 0.17145)
		(layer "B.Cu")
		(net "I2C_B_SDA")
	)
	(segment
		(start 54.483 -340.487)
		(end 54.483 -243.0272)
		(width 0.17145)
		(layer "B.Cu")
		(net "I2C_B_SDA")
	)
	(segment
		(start 94.74327 -445.880236)
		(end 94.90075 -446.037716)
		(width 0.17145)
		(layer "B.Cu")
		(net "I2C_B_SDA")
	)
	(segment
		(start 108.585 -77.382624)
		(end 109.215174 -76.75245)
		(width 0.17145)
		(layer "B.Cu")
		(net "I2C_B_SDA")
	)
	(segment
		(start 23.066248 -388.540752)
		(end 32.108648 -388.540752)
		(width 0.17145)
		(layer "B.Cu")
		(net "I2C_B_SDA")
	)
	(segment
		(start 91.821 -446.2018)
		(end 91.821 -443.0776)
		(width 0.17145)
		(layer "B.Cu")
		(net "I2C_B_SDA")
	)
	(segment
		(start 69.446902 -438.64784)
		(end 69.446902 -441.626498)
		(width 0.17145)
		(layer "B.Cu")
		(net "I2C_B_SDA")
	)
	(segment
		(start 48.223424 -134.5946)
		(end 49.066704 -134.5946)
		(width 0.17145)
		(layer "B.Cu")
		(net "I2C_B_SDA")
	)
	(segment
		(start 54.483 -243.0272)
		(end 29.972 -218.5162)
		(width 0.17145)
		(layer "B.Cu")
		(net "I2C_B_SDA")
	)
	(segment
		(start 21.795232 -391.287)
		(end 21.59 -391.081768)
		(width 0.17145)
		(layer "B.Cu")
		(net "I2C_B_SDA")
	)
	(segment
		(start 45.847 -135.4582)
		(end 46.61535 -134.68985)
		(width 0.17145)
		(layer "B.Cu")
		(net "I2C_B_SDA")
	)
	(segment
		(start 109.215174 -76.75245)
		(end 113.08588 -76.75245)
		(width 0.17145)
		(layer "B.Cu")
		(net "I2C_B_SDA")
	)
	(segment
		(start 69.4436 -436.936896)
		(end 69.4436 -438.23763)
		(width 0.17145)
		(layer "B.Cu")
		(net "I2C_B_SDA")
	)
	(segment
		(start 91.821 -443.0776)
		(end 89.633044 -440.889644)
		(width 0.17145)
		(layer "B.Cu")
		(net "I2C_B_SDA")
	)
	(segment
		(start 56.53405 -382.73228)
		(end 56.53405 -342.53805)
		(width 0.17145)
		(layer "B.Cu")
		(net "I2C_B_SDA")
	)
	(segment
		(start 50.08245 -133.578854)
		(end 50.08245 -95.097854)
		(width 0.17145)
		(layer "B.Cu")
		(net "I2C_B_SDA")
	)
	(segment
		(start 94.90075 -446.962276)
		(end 94.111826 -447.7512)
		(width 0.17145)
		(layer "B.Cu")
		(net "I2C_B_SDA")
	)
	(segment
		(start 32.108648 -388.540752)
		(end 35.492436 -391.92454)
		(width 0.17145)
		(layer "B.Cu")
		(net "I2C_B_SDA")
	)
	(segment
		(start 93.3704 -447.7512)
		(end 91.821 -446.2018)
		(width 0.17145)
		(layer "B.Cu")
		(net "I2C_B_SDA")
	)
	(segment
		(start 21.59 -390.017)
		(end 23.066248 -388.540752)
		(width 0.17145)
		(layer "B.Cu")
		(net "I2C_B_SDA")
	)
	(segment
		(start 26.162 -423.545)
		(end 26.162 -415.29)
		(width 0.17145)
		(layer "B.Cu")
		(net "I2C_B_SDA")
	)
	(segment
		(start 45.0596 -208.8134)
		(end 45.0596 -203.2254)
		(width 0.17145)
		(layer "B.Cu")
		(net "I2C_B_SDA")
	)
	(segment
		(start 21.6662 -391.416032)
		(end 21.795232 -391.287)
		(width 0.17145)
		(layer "B.Cu")
		(net "I2C_B_SDA")
	)
	(segment
		(start 35.56 -432.943)
		(end 26.162 -423.545)
		(width 0.17145)
		(layer "B.Cu")
		(net "I2C_B_SDA")
	)
	(segment
		(start 45.847 -143.6878)
		(end 45.847 -135.4582)
		(width 0.17145)
		(layer "B.Cu")
		(net "I2C_B_SDA")
	)
	(segment
		(start 70.103746 -436.27675)
		(end 69.4436 -436.936896)
		(width 0.17145)
		(layer "B.Cu")
		(net "I2C_B_SDA")
	)
	(segment
		(start 47.968916 -134.849108)
		(end 48.223424 -134.5946)
		(width 0.17145)
		(layer "B.Cu")
		(net "I2C_B_SDA")
	)
	(segment
		(start 113.08588 -76.75245)
		(end 139.88288 -49.95545)
		(width 0.17145)
		(layer "B.Cu")
		(net "I2C_B_SDA")
	)
	(segment
		(start 49.066704 -134.5946)
		(end 50.08245 -133.578854)
		(width 0.17145)
		(layer "B.Cu")
		(net "I2C_B_SDA")
	)
	(segment
		(start 72.77735 -436.27675)
		(end 70.103746 -436.27675)
		(width 0.17145)
		(layer "B.Cu")
		(net "I2C_B_SDA")
	)
	(segment
		(start 54.12613 -444.2968)
		(end 42.77233 -432.943)
		(width 0.17145)
		(layer "B.Cu")
		(net "I2C_B_SDA")
	)
	(segment
		(start 139.88288 -49.95545)
		(end 201.070464 -49.95545)
		(width 0.17145)
		(layer "B.Cu")
		(net "I2C_B_SDA")
	)
	(segment
		(start 40.6654 -213.2076)
		(end 45.0596 -208.8134)
		(width 0.17145)
		(layer "B.Cu")
		(net "I2C_B_SDA")
	)
	(segment
		(start 69.446902 -441.626498)
		(end 66.7766 -444.2968)
		(width 0.17145)
		(layer "B.Cu")
		(net "I2C_B_SDA")
	)
	(segment
		(start 69.240146 -438.441084)
		(end 69.446902 -438.64784)
		(width 0.17145)
		(layer "B.Cu")
		(net "I2C_B_SDA")
	)
	(segment
		(start 89.633044 -440.889644)
		(end 77.390244 -440.889644)
		(width 0.17145)
		(layer "B.Cu")
		(net "I2C_B_SDA")
	)
	(segment
		(start 23.5585 -378.968)
		(end 23.2537 -379.2728)
		(width 0.17145)
		(layer "F.Cu")
		(net "I2C_B_SCL")
	)
	(segment
		(start 105.1306 -440.2074)
		(end 178.573176 -440.2074)
		(width 0.17145)
		(layer "F.Cu")
		(net "I2C_B_SCL")
	)
	(segment
		(start 69.99605 -438.231026)
		(end 69.99605 -437.68645)
		(width 0.17145)
		(layer "F.Cu")
		(net "I2C_B_SCL")
	)
	(segment
		(start 70.206108 -438.441084)
		(end 69.97065 -438.676542)
		(width 0.17145)
		(layer "F.Cu")
		(net "I2C_B_SCL")
	)
	(segment
		(start 70.206108 -438.441084)
		(end 69.99605 -438.231026)
		(width 0.17145)
		(layer "F.Cu")
		(net "I2C_B_SCL")
	)
	(segment
		(start 47.968916 -133.883146)
		(end 47.765462 -134.0866)
		(width 0.17145)
		(layer "F.Cu")
		(net "I2C_B_SCL")
	)
	(segment
		(start 21.0312 -380.015496)
		(end 21.0312 -391.084816)
		(width 0.17145)
		(layer "F.Cu")
		(net "I2C_B_SCL")
	)
	(segment
		(start 202.64755 -459.33995)
		(end 203.0095 -458.978)
		(width 0.17145)
		(layer "F.Cu")
		(net "I2C_B_SCL")
	)
	(segment
		(start 203.0095 -49.022)
		(end 202.650852 -49.380648)
		(width 0.17145)
		(layer "F.Cu")
		(net "I2C_B_SCL")
	)
	(segment
		(start 70.231 -437.3245)
		(end 70.2945 -437.388)
		(width 0.17145)
		(layer "F.Cu")
		(net "I2C_B_SCL")
	)
	(segment
		(start 88.519 -32.3215)
		(end 88.749124 -32.551624)
		(width 0.17145)
		(layer "F.Cu")
		(net "I2C_B_SCL")
	)
	(segment
		(start 95.52305 -446.77965)
		(end 95.9612 -447.2178)
		(width 0.17145)
		(layer "F.Cu")
		(net "I2C_B_SCL")
	)
	(segment
		(start 202.650852 -49.380648)
		(end 201.461624 -49.380648)
		(width 0.17145)
		(layer "F.Cu")
		(net "I2C_B_SCL")
	)
	(segment
		(start 178.573176 -440.2074)
		(end 197.705726 -459.33995)
		(width 0.17145)
		(layer "F.Cu")
		(net "I2C_B_SCL")
	)
	(segment
		(start 95.709232 -445.880236)
		(end 95.52305 -446.066418)
		(width 0.17145)
		(layer "F.Cu")
		(net "I2C_B_SCL")
	)
	(segment
		(start 95.9612 -447.2178)
		(end 98.1202 -447.2178)
		(width 0.17145)
		(layer "F.Cu")
		(net "I2C_B_SCL")
	)
	(segment
		(start 21.0312 -391.084816)
		(end 20.921472 -391.194544)
		(width 0.17145)
		(layer "F.Cu")
		(net "I2C_B_SCL")
	)
	(segment
		(start 69.97065 -439.47715)
		(end 70.231 -439.7375)
		(width 0.17145)
		(layer "F.Cu")
		(net "I2C_B_SCL")
	)
	(segment
		(start 88.749124 -50.293524)
		(end 111.5822 -73.1266)
		(width 0.17145)
		(layer "F.Cu")
		(net "I2C_B_SCL")
	)
	(segment
		(start 47.2821 -134.0866)
		(end 47.0535 -133.858)
		(width 0.17145)
		(layer "F.Cu")
		(net "I2C_B_SCL")
	)
	(segment
		(start 197.705726 -459.33995)
		(end 202.64755 -459.33995)
		(width 0.17145)
		(layer "F.Cu")
		(net "I2C_B_SCL")
	)
	(segment
		(start 111.175546 -76.13015)
		(end 108.79455 -76.13015)
		(width 0.17145)
		(layer "F.Cu")
		(net "I2C_B_SCL")
	)
	(segment
		(start 23.2537 -379.2728)
		(end 21.773896 -379.2728)
		(width 0.17145)
		(layer "F.Cu")
		(net "I2C_B_SCL")
	)
	(segment
		(start 111.5822 -75.723496)
		(end 111.175546 -76.13015)
		(width 0.17145)
		(layer "F.Cu")
		(net "I2C_B_SCL")
	)
	(segment
		(start 47.765462 -134.0866)
		(end 47.2821 -134.0866)
		(width 0.17145)
		(layer "F.Cu")
		(net "I2C_B_SCL")
	)
	(segment
		(start 69.97065 -438.676542)
		(end 69.97065 -439.47715)
		(width 0.17145)
		(layer "F.Cu")
		(net "I2C_B_SCL")
	)
	(segment
		(start 111.5822 -73.1266)
		(end 111.5822 -75.723496)
		(width 0.17145)
		(layer "F.Cu")
		(net "I2C_B_SCL")
	)
	(segment
		(start 88.749124 -32.551624)
		(end 88.749124 -50.293524)
		(width 0.17145)
		(layer "F.Cu")
		(net "I2C_B_SCL")
	)
	(segment
		(start 70.231 -436.3085)
		(end 70.231 -437.3245)
		(width 0.17145)
		(layer "F.Cu")
		(net "I2C_B_SCL")
	)
	(segment
		(start 201.461624 -49.380648)
		(end 201.255122 -49.174146)
		(width 0.17145)
		(layer "F.Cu")
		(net "I2C_B_SCL")
	)
	(segment
		(start 20.921472 -391.194544)
		(end 20.82927 -391.287)
		(width 0.17145)
		(layer "F.Cu")
		(net "I2C_B_SCL")
	)
	(segment
		(start 69.99605 -437.68645)
		(end 70.2945 -437.388)
		(width 0.17145)
		(layer "F.Cu")
		(net "I2C_B_SCL")
	)
	(segment
		(start 21.773896 -379.2728)
		(end 21.0312 -380.015496)
		(width 0.17145)
		(layer "F.Cu")
		(net "I2C_B_SCL")
	)
	(segment
		(start 108.79455 -76.13015)
		(end 108.585 -75.9206)
		(width 0.17145)
		(layer "F.Cu")
		(net "I2C_B_SCL")
	)
	(segment
		(start 108.585 -75.9206)
		(end 108.585 -75.477624)
		(width 0.17145)
		(layer "F.Cu")
		(net "I2C_B_SCL")
	)
	(segment
		(start 95.52305 -446.066418)
		(end 95.52305 -446.77965)
		(width 0.17145)
		(layer "F.Cu")
		(net "I2C_B_SCL")
	)
	(segment
		(start 98.1202 -447.2178)
		(end 105.1306 -440.2074)
		(width 0.17145)
		(layer "F.Cu")
		(net "I2C_B_SCL")
	)
	(via
		(at 201.255122 -49.174146)
		(size 0.508)
		(drill 0.254)
		(layers "F.Cu" "B.Cu")
		(net "I2C_B_SCL")
	)
	(via
		(at 108.585 -75.477624)
		(size 0.5588)
		(drill 0.3048)
		(layers "F.Cu" "B.Cu")
		(net "I2C_B_SCL")
	)
	(via
		(at 95.709232 -445.880236)
		(size 0.508)
		(drill 0.254)
		(layers "F.Cu" "B.Cu")
		(net "I2C_B_SCL")
	)
	(via
		(at 20.82927 -391.287)
		(size 0.508)
		(drill 0.254)
		(layers "F.Cu" "B.Cu")
		(net "I2C_B_SCL")
	)
	(via
		(at 47.968916 -133.883146)
		(size 0.508)
		(drill 0.254)
		(layers "F.Cu" "B.Cu")
		(net "I2C_B_SCL")
	)
	(via
		(at 70.206108 -438.441084)
		(size 0.508)
		(drill 0.254)
		(layers "F.Cu" "B.Cu")
		(net "I2C_B_SCL")
	)
	(segment
		(start 47.112936 -391.37209)
		(end 55.9816 -382.503426)
		(width 0.17145)
		(layer "B.Cu")
		(net "I2C_B_SCL")
	)
	(segment
		(start 68.2498 -76.1492)
		(end 107.913424 -76.1492)
		(width 0.17145)
		(layer "B.Cu")
		(net "I2C_B_SCL")
	)
	(segment
		(start 201.026268 -49.403)
		(end 201.255122 -49.174146)
		(width 0.17145)
		(layer "B.Cu")
		(net "I2C_B_SCL")
	)
	(segment
		(start 42.543476 -433.49545)
		(end 35.331146 -433.49545)
		(width 0.17145)
		(layer "B.Cu")
		(net "I2C_B_SCL")
	)
	(segment
		(start 29.41955 -218.745054)
		(end 29.41955 -213.842346)
		(width 0.17145)
		(layer "B.Cu")
		(net "I2C_B_SCL")
	)
	(segment
		(start 53.897276 -444.84925)
		(end 42.543476 -433.49545)
		(width 0.17145)
		(layer "B.Cu")
		(net "I2C_B_SCL")
	)
	(segment
		(start 55.9816 -342.766904)
		(end 53.93055 -340.715854)
		(width 0.17145)
		(layer "B.Cu")
		(net "I2C_B_SCL")
	)
	(segment
		(start 48.12792 -134.04215)
		(end 48.83785 -134.04215)
		(width 0.17145)
		(layer "B.Cu")
		(net "I2C_B_SCL")
	)
	(segment
		(start 44.50715 -208.584546)
		(end 44.50715 -202.996546)
		(width 0.17145)
		(layer "B.Cu")
		(net "I2C_B_SCL")
	)
	(segment
		(start 108.585 -75.477624)
		(end 109.307376 -76.2)
		(width 0.17145)
		(layer "B.Cu")
		(net "I2C_B_SCL")
	)
	(segment
		(start 52.27955 -150.901654)
		(end 45.29455 -143.916654)
		(width 0.17145)
		(layer "B.Cu")
		(net "I2C_B_SCL")
	)
	(segment
		(start 21.03755 -389.788146)
		(end 22.837394 -387.988302)
		(width 0.17145)
		(layer "B.Cu")
		(net "I2C_B_SCL")
	)
	(segment
		(start 93.141546 -448.30365)
		(end 91.26855 -446.430654)
		(width 0.17145)
		(layer "B.Cu")
		(net "I2C_B_SCL")
	)
	(segment
		(start 45.29455 -135.229346)
		(end 46.386496 -134.1374)
		(width 0.17145)
		(layer "B.Cu")
		(net "I2C_B_SCL")
	)
	(segment
		(start 47.714662 -134.1374)
		(end 47.968916 -133.883146)
		(width 0.17145)
		(layer "B.Cu")
		(net "I2C_B_SCL")
	)
	(segment
		(start 20.82927 -391.287)
		(end 21.03755 -391.07872)
		(width 0.17145)
		(layer "B.Cu")
		(net "I2C_B_SCL")
	)
	(segment
		(start 53.93055 -243.256054)
		(end 29.41955 -218.745054)
		(width 0.17145)
		(layer "B.Cu")
		(net "I2C_B_SCL")
	)
	(segment
		(start 40.436546 -212.65515)
		(end 44.50715 -208.584546)
		(width 0.17145)
		(layer "B.Cu")
		(net "I2C_B_SCL")
	)
	(segment
		(start 53.93055 -340.715854)
		(end 53.93055 -243.256054)
		(width 0.17145)
		(layer "B.Cu")
		(net "I2C_B_SCL")
	)
	(segment
		(start 30.606746 -212.65515)
		(end 40.436546 -212.65515)
		(width 0.17145)
		(layer "B.Cu")
		(net "I2C_B_SCL")
	)
	(segment
		(start 94.34068 -448.30365)
		(end 93.141546 -448.30365)
		(width 0.17145)
		(layer "B.Cu")
		(net "I2C_B_SCL")
	)
	(segment
		(start 52.27955 -195.224146)
		(end 52.27955 -150.901654)
		(width 0.17145)
		(layer "B.Cu")
		(net "I2C_B_SCL")
	)
	(segment
		(start 55.9816 -382.503426)
		(end 55.9816 -342.766904)
		(width 0.17145)
		(layer "B.Cu")
		(net "I2C_B_SCL")
	)
	(segment
		(start 95.4532 -446.136268)
		(end 95.4532 -447.19113)
		(width 0.17145)
		(layer "B.Cu")
		(net "I2C_B_SCL")
	)
	(segment
		(start 69.99605 -437.16575)
		(end 69.99605 -438.231026)
		(width 0.17145)
		(layer "B.Cu")
		(net "I2C_B_SCL")
	)
	(segment
		(start 44.50715 -202.996546)
		(end 52.27955 -195.224146)
		(width 0.17145)
		(layer "B.Cu")
		(net "I2C_B_SCL")
	)
	(segment
		(start 107.913424 -76.1492)
		(end 108.585 -75.477624)
		(width 0.17145)
		(layer "B.Cu")
		(net "I2C_B_SCL")
	)
	(segment
		(start 72.548496 -436.8292)
		(end 70.3326 -436.8292)
		(width 0.17145)
		(layer "B.Cu")
		(net "I2C_B_SCL")
	)
	(segment
		(start 35.331146 -433.49545)
		(end 25.60955 -423.773854)
		(width 0.17145)
		(layer "B.Cu")
		(net "I2C_B_SCL")
	)
	(segment
		(start 21.11375 -411.023054)
		(end 21.11375 -391.57148)
		(width 0.17145)
		(layer "B.Cu")
		(net "I2C_B_SCL")
	)
	(segment
		(start 48.83785 -134.04215)
		(end 49.53 -133.35)
		(width 0.17145)
		(layer "B.Cu")
		(net "I2C_B_SCL")
	)
	(segment
		(start 45.29455 -143.916654)
		(end 45.29455 -135.229346)
		(width 0.17145)
		(layer "B.Cu")
		(net "I2C_B_SCL")
	)
	(segment
		(start 89.40419 -441.442094)
		(end 77.16139 -441.442094)
		(width 0.17145)
		(layer "B.Cu")
		(net "I2C_B_SCL")
	)
	(segment
		(start 91.26855 -446.430654)
		(end 91.26855 -443.306454)
		(width 0.17145)
		(layer "B.Cu")
		(net "I2C_B_SCL")
	)
	(segment
		(start 112.857026 -76.2)
		(end 139.654026 -49.403)
		(width 0.17145)
		(layer "B.Cu")
		(net "I2C_B_SCL")
	)
	(segment
		(start 95.709232 -445.880236)
		(end 95.4532 -446.136268)
		(width 0.17145)
		(layer "B.Cu")
		(net "I2C_B_SCL")
	)
	(segment
		(start 70.206108 -438.441084)
		(end 69.999352 -438.64784)
		(width 0.17145)
		(layer "B.Cu")
		(net "I2C_B_SCL")
	)
	(segment
		(start 91.26855 -443.306454)
		(end 89.40419 -441.442094)
		(width 0.17145)
		(layer "B.Cu")
		(net "I2C_B_SCL")
	)
	(segment
		(start 25.60955 -415.518854)
		(end 21.11375 -411.023054)
		(width 0.17145)
		(layer "B.Cu")
		(net "I2C_B_SCL")
	)
	(segment
		(start 49.53 -94.869)
		(end 68.2498 -76.1492)
		(width 0.17145)
		(layer "B.Cu")
		(net "I2C_B_SCL")
	)
	(segment
		(start 25.60955 -423.773854)
		(end 25.60955 -415.518854)
		(width 0.17145)
		(layer "B.Cu")
		(net "I2C_B_SCL")
	)
	(segment
		(start 21.11375 -391.57148)
		(end 20.82927 -391.287)
		(width 0.17145)
		(layer "B.Cu")
		(net "I2C_B_SCL")
	)
	(segment
		(start 69.99605 -438.231026)
		(end 70.206108 -438.441084)
		(width 0.17145)
		(layer "B.Cu")
		(net "I2C_B_SCL")
	)
	(segment
		(start 139.654026 -49.403)
		(end 201.026268 -49.403)
		(width 0.17145)
		(layer "B.Cu")
		(net "I2C_B_SCL")
	)
	(segment
		(start 47.968916 -133.883146)
		(end 48.12792 -134.04215)
		(width 0.17145)
		(layer "B.Cu")
		(net "I2C_B_SCL")
	)
	(segment
		(start 32.337502 -387.988302)
		(end 35.72129 -391.37209)
		(width 0.17145)
		(layer "B.Cu")
		(net "I2C_B_SCL")
	)
	(segment
		(start 69.999352 -441.855352)
		(end 67.005454 -444.84925)
		(width 0.17145)
		(layer "B.Cu")
		(net "I2C_B_SCL")
	)
	(segment
		(start 109.307376 -76.2)
		(end 112.857026 -76.2)
		(width 0.17145)
		(layer "B.Cu")
		(net "I2C_B_SCL")
	)
	(segment
		(start 67.005454 -444.84925)
		(end 53.897276 -444.84925)
		(width 0.17145)
		(layer "B.Cu")
		(net "I2C_B_SCL")
	)
	(segment
		(start 49.53 -133.35)
		(end 49.53 -94.869)
		(width 0.17145)
		(layer "B.Cu")
		(net "I2C_B_SCL")
	)
	(segment
		(start 22.837394 -387.988302)
		(end 32.337502 -387.988302)
		(width 0.17145)
		(layer "B.Cu")
		(net "I2C_B_SCL")
	)
	(segment
		(start 29.41955 -213.842346)
		(end 30.606746 -212.65515)
		(width 0.17145)
		(layer "B.Cu")
		(net "I2C_B_SCL")
	)
	(segment
		(start 35.72129 -391.37209)
		(end 47.112936 -391.37209)
		(width 0.17145)
		(layer "B.Cu")
		(net "I2C_B_SCL")
	)
	(segment
		(start 77.16139 -441.442094)
		(end 72.548496 -436.8292)
		(width 0.17145)
		(layer "B.Cu")
		(net "I2C_B_SCL")
	)
	(segment
		(start 95.4532 -447.19113)
		(end 94.34068 -448.30365)
		(width 0.17145)
		(layer "B.Cu")
		(net "I2C_B_SCL")
	)
	(segment
		(start 46.386496 -134.1374)
		(end 47.714662 -134.1374)
		(width 0.17145)
		(layer "B.Cu")
		(net "I2C_B_SCL")
	)
	(segment
		(start 69.999352 -438.64784)
		(end 69.999352 -441.855352)
		(width 0.17145)
		(layer "B.Cu")
		(net "I2C_B_SCL")
	)
	(segment
		(start 70.3326 -436.8292)
		(end 69.99605 -437.16575)
		(width 0.17145)
		(layer "B.Cu")
		(net "I2C_B_SCL")
	)
	(segment
		(start 21.03755 -391.07872)
		(end 21.03755 -389.788146)
		(width 0.17145)
		(layer "B.Cu")
		(net "I2C_B_SCL")
	)
	(segment
		(start 89.535 -18.2245)
		(end 89.535 -17.399)
		(width 0.508)
		(layer "F.Cu")
		(net "GND")
	)
	(segment
		(start 2.249932 -329.94219)
		(end 3.81508 -329.94219)
		(width 0.508)
		(layer "F.Cu")
		(net "GND")
	)
	(segment
		(start 4.191 -384.175)
		(end 3.957828 -383.941828)
		(width 0.508)
		(layer "F.Cu")
		(net "GND")
	)
	(segment
		(start 2.249932 -320.342006)
		(end 3.81508 -320.342006)
		(width 0.508)
		(layer "F.Cu")
		(net "GND")
	)
	(segment
		(start 2.249932 -413.541972)
		(end 3.780028 -413.541972)
		(width 0.508)
		(layer "F.Cu")
		(net "GND")
	)
	(segment
		(start 88.011 -309.4355)
		(end 87.122 -309.4355)
		(width 0.508)
		(layer "F.Cu")
		(net "GND")
	)
	(segment
		(start 3.805174 -410.341826)
		(end 4.191 -409.956)
		(width 0.508)
		(layer "F.Cu")
		(net "GND")
	)
	(segment
		(start 22.800056 -246.210074)
		(end 24.384 -246.210074)
		(width 0.508)
		(layer "F.Cu")
		(net "GND")
	)
	(segment
		(start 2.249932 -277.94204)
		(end 4.191 -277.94204)
		(width 0.508)
		(layer "F.Cu")
		(net "GND")
	)
	(segment
		(start 3.81508 -335.542128)
		(end 4.191 -335.166208)
		(width 0.508)
		(layer "F.Cu")
		(net "GND")
	)
	(segment
		(start 212.471 -44.2595)
		(end 213.36 -44.2595)
		(width 0.508)
		(layer "F.Cu")
		(net "GND")
	)
	(segment
		(start 99.236276 -101.85019)
		(end 98.40341 -101.85019)
		(width 0.3048)
		(layer "F.Cu")
		(net "GND")
	)
	(segment
		(start 39.200074 -176.789842)
		(end 37.61613 -176.789842)
		(width 0.508)
		(layer "F.Cu")
		(net "GND")
	)
	(segment
		(start 22.800056 -128.009904)
		(end 24.384 -128.009904)
		(width 0.508)
		(layer "F.Cu")
		(net "GND")
	)
	(segment
		(start 3.887978 -312.342022)
		(end 4.191 -312.039)
		(width 0.508)
		(layer "F.Cu")
		(net "GND")
	)
	(segment
		(start 224.199958 -274.990052)
		(end 222.616014 -274.990052)
		(width 0.508)
		(layer "F.Cu")
		(net "GND")
	)
	(segment
		(start 2.249932 -226.342194)
		(end 3.781806 -226.342194)
		(width 0.508)
		(layer "F.Cu")
		(net "GND")
	)
	(segment
		(start 221.361 -474.98)
		(end 220.345 -474.98)
		(width 0.508)
		(layer "F.Cu")
		(net "GND")
	)
	(segment
		(start 226.3775 -240.262918)
		(end 225.175318 -240.262918)
		(width 0.381)
		(layer "F.Cu")
		(net "GND")
	)
	(segment
		(start 2.249932 -170.342052)
		(end 3.81508 -170.342052)
		(width 0.508)
		(layer "F.Cu")
		(net "GND")
	)
	(segment
		(start 2.249932 -354.741988)
		(end 3.81508 -354.741988)
		(width 0.508)
		(layer "F.Cu")
		(net "GND")
	)
	(segment
		(start 2.249932 -391.941812)
		(end 3.790188 -391.941812)
		(width 0.508)
		(layer "F.Cu")
		(net "GND")
	)
	(segment
		(start 31.051754 -214.755984)
		(end 31.051754 -213.9696)
		(width 0.508)
		(layer "F.Cu")
		(net "GND")
	)
	(segment
		(start 39.200074 -161.589974)
		(end 37.61613 -161.589974)
		(width 0.508)
		(layer "F.Cu")
		(net "GND")
	)
	(segment
		(start 226.974908 -261.605014)
		(end 228.585014 -261.605014)
		(width 0.508)
		(layer "F.Cu")
		(net "GND")
	)
	(segment
		(start 3.84302 -219.942156)
		(end 4.191 -220.290136)
		(width 0.508)
		(layer "F.Cu")
		(net "GND")
	)
	(segment
		(start 226.974908 -379.845062)
		(end 228.585014 -379.845062)
		(width 0.508)
		(layer "F.Cu")
		(net "GND")
	)
	(segment
		(start 2.249932 -300.342046)
		(end 3.842766 -300.342046)
		(width 0.508)
		(layer "F.Cu")
		(net "GND")
	)
	(segment
		(start 102.0445 -305.3715)
		(end 102.108 -305.435)
		(width 0.508)
		(layer "F.Cu")
		(net "GND")
	)
	(segment
		(start 22.800056 -326.810116)
		(end 24.384 -326.810116)
		(width 0.508)
		(layer "F.Cu")
		(net "GND")
	)
	(segment
		(start 12.1539 -497.5733)
		(end 11.71321 -497.13261)
		(width 0.508)
		(layer "F.Cu")
		(net "GND")
	)
	(segment
		(start 85.725 -212.4075)
		(end 86.614 -212.4075)
		(width 0.508)
		(layer "F.Cu")
		(net "GND")
	)
	(segment
		(start 208.534 -196.7865)
		(end 209.38109 -195.93941)
		(width 0.508)
		(layer "F.Cu")
		(net "GND")
	)
	(segment
		(start 199.380856 -496.127278)
		(end 198.174356 -496.127278)
		(width 0.508)
		(layer "F.Cu")
		(net "GND")
	)
	(segment
		(start 224.199958 -163.18992)
		(end 222.616014 -163.18992)
		(width 0.508)
		(layer "F.Cu")
		(net "GND")
	)
	(segment
		(start 20.025106 -454.205086)
		(end 18.415 -454.205086)
		(width 0.508)
		(layer "F.Cu")
		(net "GND")
	)
	(segment
		(start 37.87775 -103.09225)
		(end 37.211 -103.759)
		(width 0.508)
		(layer "F.Cu")
		(net "GND")
	)
	(segment
		(start 99.5045 -300.0375)
		(end 98.530918 -301.011082)
		(width 0.3048)
		(layer "F.Cu")
		(net "GND")
	)
	(segment
		(start 26.2128 -264.795)
		(end 25.8445 -264.4267)
		(width 0.508)
		(layer "F.Cu")
		(net "GND")
	)
	(segment
		(start 25.4635 -196.9389)
		(end 24.638 -196.1134)
		(width 0.508)
		(layer "F.Cu")
		(net "GND")
	)
	(segment
		(start 2.249932 -411.141926)
		(end 3.852926 -411.141926)
		(width 0.508)
		(layer "F.Cu")
		(net "GND")
	)
	(segment
		(start 22.800056 -237.40999)
		(end 24.384 -237.40999)
		(width 0.508)
		(layer "F.Cu")
		(net "GND")
	)
	(segment
		(start 70.993 -455.1045)
		(end 70.993 -455.93)
		(width 0.508)
		(layer "F.Cu")
		(net "GND")
	)
	(segment
		(start 3.790188 -391.941812)
		(end 4.191 -391.541)
		(width 0.508)
		(layer "F.Cu")
		(net "GND")
	)
	(segment
		(start 224.199958 -365.190024)
		(end 222.616014 -365.190024)
		(width 0.508)
		(layer "F.Cu")
		(net "GND")
	)
	(segment
		(start 207.834738 -458.024738)
		(end 207.264 -457.454)
		(width 0.3556)
		(layer "F.Cu")
		(net "GND")
	)
	(segment
		(start 3.97002 -423.942002)
		(end 2.249932 -423.942002)
		(width 0.508)
		(layer "F.Cu")
		(net "GND")
	)
	(segment
		(start 98.9965 -436.9435)
		(end 98.530918 -436.477918)
		(width 0.3048)
		(layer "F.Cu")
		(net "GND")
	)
	(segment
		(start 224.199958 -181.589934)
		(end 222.616014 -181.589934)
		(width 0.508)
		(layer "F.Cu")
		(net "GND")
	)
	(segment
		(start 3.81508 -305.941984)
		(end 4.191 -305.566064)
		(width 0.508)
		(layer "F.Cu")
		(net "GND")
	)
	(segment
		(start 83.6295 -151.638)
		(end 84.455 -151.638)
		(width 0.508)
		(layer "F.Cu")
		(net "GND")
	)
	(segment
		(start 2.249932 -183.142128)
		(end 3.81508 -183.142128)
		(width 0.508)
		(layer "F.Cu")
		(net "GND")
	)
	(segment
		(start 41.975024 -182.734966)
		(end 43.579034 -182.734966)
		(width 0.508)
		(layer "F.Cu")
		(net "GND")
	)
	(segment
		(start 41.975024 -471.41511)
		(end 43.58513 -471.41511)
		(width 0.508)
		(layer "F.Cu")
		(net "GND")
	)
	(segment
		(start 224.199958 -470.590118)
		(end 222.616014 -470.590118)
		(width 0.508)
		(layer "F.Cu")
		(net "GND")
	)
	(segment
		(start 221.71025 -137.08761)
		(end 221.71025 -135.95985)
		(width 0.508)
		(layer "F.Cu")
		(net "GND")
	)
	(segment
		(start 24.003 -196.7484)
		(end 24.003 -196.7865)
		(width 0.508)
		(layer "F.Cu")
		(net "GND")
	)
	(segment
		(start 74.2188 -148.966936)
		(end 73.152 -148.966936)
		(width 0.3048)
		(layer "F.Cu")
		(net "GND")
	)
	(segment
		(start 86.614 -433.3875)
		(end 85.725 -433.3875)
		(width 0.508)
		(layer "F.Cu")
		(net "GND")
	)
	(segment
		(start 88.011 -435.9275)
		(end 88.011 -436.0545)
		(width 0.3048)
		(layer "F.Cu")
		(net "GND")
	)
	(segment
		(start 225.1964 -446.0494)
		(end 225.40976 -446.26276)
		(width 0.381)
		(layer "F.Cu")
		(net "GND")
	)
	(segment
		(start 224.199958 -176.789842)
		(end 222.616014 -176.789842)
		(width 0.508)
		(layer "F.Cu")
		(net "GND")
	)
	(segment
		(start 24.383746 -346.810076)
		(end 24.384 -346.809822)
		(width 0.508)
		(layer "F.Cu")
		(net "GND")
	)
	(segment
		(start 2.249932 -219.942156)
		(end 3.84302 -219.942156)
		(width 0.508)
		(layer "F.Cu")
		(net "GND")
	)
	(segment
		(start 4.191 -427.52518)
		(end 3.807714 -427.141894)
		(width 0.508)
		(layer "F.Cu")
		(net "GND")
	)
	(segment
		(start 86.233 -215.0745)
		(end 87.122 -215.0745)
		(width 0.508)
		(layer "F.Cu")
		(net "GND")
	)
	(segment
		(start 226.974908 -79.734918)
		(end 228.621082 -79.734918)
		(width 0.508)
		(layer "F.Cu")
		(net "GND")
	)
	(segment
		(start 24.383746 -221.410022)
		(end 24.384 -221.409768)
		(width 0.508)
		(layer "F.Cu")
		(net "GND")
	)
	(segment
		(start 224.199958 -266.189968)
		(end 222.616014 -266.189968)
		(width 0.508)
		(layer "F.Cu")
		(net "GND")
	)
	(segment
		(start 22.800056 -134.409942)
		(end 24.384 -134.409942)
		(width 0.508)
		(layer "F.Cu")
		(net "GND")
	)
	(segment
		(start 87.503 -306.7685)
		(end 86.614 -306.7685)
		(width 0.508)
		(layer "F.Cu")
		(net "GND")
	)
	(segment
		(start 78.2066 -215.0618)
		(end 77.3176 -215.0618)
		(width 0.508)
		(layer "F.Cu")
		(net "GND")
	)
	(segment
		(start 49.429924 -450.32676)
		(end 48.603662 -450.32676)
		(width 0.508)
		(layer "F.Cu")
		(net "GND")
	)
	(segment
		(start 77.7748 -432.689)
		(end 77.7748 -434.2384)
		(width 0.508)
		(layer "F.Cu")
		(net "GND")
	)
	(segment
		(start 3.81508 -329.94219)
		(end 4.191 -329.56627)
		(width 0.508)
		(layer "F.Cu")
		(net "GND")
	)
	(segment
		(start 228.60889 -491.73511)
		(end 228.981 -491.363)
		(width 0.508)
		(layer "F.Cu")
		(net "GND")
	)
	(segment
		(start 24.383746 -427.410118)
		(end 24.384 -427.409864)
		(width 0.508)
		(layer "F.Cu")
		(net "GND")
	)
	(segment
		(start 224.199958 -382.789938)
		(end 222.616014 -382.789938)
		(width 0.508)
		(layer "F.Cu")
		(net "GND")
	)
	(segment
		(start 88.825324 -90.346022)
		(end 88.4555 -89.976198)
		(width 0.508)
		(layer "F.Cu")
		(net "GND")
	)
	(segment
		(start 2.249932 -339.54212)
		(end 3.84302 -339.54212)
		(width 0.508)
		(layer "F.Cu")
		(net "GND")
	)
	(segment
		(start 226.974908 -368.415062)
		(end 228.585014 -368.415062)
		(width 0.508)
		(layer "F.Cu")
		(net "GND")
	)
	(segment
		(start 98.40341 -305.43119)
		(end 100.42271 -305.43119)
		(width 0.3048)
		(layer "F.Cu")
		(net "GND")
	)
	(segment
		(start 39.200074 -268.590014)
		(end 37.61613 -268.590014)
		(width 0.508)
		(layer "F.Cu")
		(net "GND")
	)
	(segment
		(start 87.503 -433.3875)
		(end 86.614 -433.3875)
		(width 0.508)
		(layer "F.Cu")
		(net "GND")
	)
	(segment
		(start 36.5125 -412.8135)
		(end 36.449 -412.877)
		(width 0.508)
		(layer "F.Cu")
		(net "GND")
	)
	(segment
		(start 68.50126 -374.142)
		(end 68.50126 -378.498608)
		(width 0.508)
		(layer "F.Cu")
		(net "GND")
	)
	(segment
		(start 208.534 -402.7805)
		(end 209.38109 -401.93341)
		(width 0.508)
		(layer "F.Cu")
		(net "GND")
	)
	(segment
		(start 3.84302 -321.142106)
		(end 4.191 -321.490086)
		(width 0.508)
		(layer "F.Cu")
		(net "GND")
	)
	(segment
		(start 3.84302 -180.742082)
		(end 4.191 -181.090062)
		(width 0.508)
		(layer "F.Cu")
		(net "GND")
	)
	(segment
		(start 18.491962 -323.265038)
		(end 18.034 -323.723)
		(width 0.508)
		(layer "F.Cu")
		(net "GND")
	)
	(segment
		(start 226.974908 -471.41511)
		(end 228.585014 -471.41511)
		(width 0.508)
		(layer "F.Cu")
		(net "GND")
	)
	(segment
		(start 2.249932 -158.342076)
		(end 3.842766 -158.342076)
		(width 0.508)
		(layer "F.Cu")
		(net "GND")
	)
	(segment
		(start 226.974908 -158.604966)
		(end 228.585014 -158.604966)
		(width 0.508)
		(layer "F.Cu")
		(net "GND")
	)
	(segment
		(start 22.800056 -33.80994)
		(end 24.15794 -33.80994)
		(width 0.508)
		(layer "F.Cu")
		(net "GND")
	)
	(segment
		(start 39.200074 -272.590006)
		(end 37.61613 -272.590006)
		(width 0.508)
		(layer "F.Cu")
		(net "GND")
	)
	(segment
		(start 99.949 -211.6455)
		(end 100.6475 -212.344)
		(width 0.508)
		(layer "F.Cu")
		(net "GND")
	)
	(segment
		(start 44.677076 -343.674192)
		(end 45.503338 -343.674192)
		(width 0.508)
		(layer "F.Cu")
		(net "GND")
	)
	(segment
		(start 86.614 -212.4075)
		(end 87.503 -212.4075)
		(width 0.508)
		(layer "F.Cu")
		(net "GND")
	)
	(segment
		(start 209.38109 -195.93941)
		(end 209.9945 -196.55282)
		(width 0.508)
		(layer "F.Cu")
		(net "GND")
	)
	(segment
		(start 37.973 -412.1785)
		(end 36.70935 -412.1785)
		(width 0.508)
		(layer "F.Cu")
		(net "GND")
	)
	(segment
		(start 221.615 -372.11)
		(end 220.599 -372.11)
		(width 0.508)
		(layer "F.Cu")
		(net "GND")
	)
	(segment
		(start 10.6172 -497.6749)
		(end 11.15949 -497.13261)
		(width 0.508)
		(layer "F.Cu")
		(net "GND")
	)
	(segment
		(start 25.4635 -196.98335)
		(end 25.4635 -196.9389)
		(width 0.508)
		(layer "F.Cu")
		(net "GND")
	)
	(segment
		(start 99.949 -300.0375)
		(end 100.7745 -300.0375)
		(width 0.508)
		(layer "F.Cu")
		(net "GND")
	)
	(segment
		(start 20.025106 -240.58499)
		(end 18.415 -240.58499)
		(width 0.508)
		(layer "F.Cu")
		(net "GND")
	)
	(segment
		(start 20.828 -165.7985)
		(end 21.6535 -165.7985)
		(width 0.508)
		(layer "F.Cu")
		(net "GND")
	)
	(segment
		(start 226.974908 -482.84511)
		(end 228.585014 -482.84511)
		(width 0.508)
		(layer "F.Cu")
		(net "GND")
	)
	(segment
		(start 41.975024 -175.114966)
		(end 43.58513 -175.114966)
		(width 0.508)
		(layer "F.Cu")
		(net "GND")
	)
	(segment
		(start 39.200074 -385.189984)
		(end 37.61613 -385.189984)
		(width 0.508)
		(layer "F.Cu")
		(net "GND")
	)
	(segment
		(start 93.345 -434.594)
		(end 93.98 -434.594)
		(width 0.3048)
		(layer "F.Cu")
		(net "GND")
	)
	(segment
		(start 2.249932 -407.141934)
		(end 3.830066 -407.141934)
		(width 0.508)
		(layer "F.Cu")
		(net "GND")
	)
	(segment
		(start 2.249932 -203.142088)
		(end 3.81508 -203.142088)
		(width 0.508)
		(layer "F.Cu")
		(net "GND")
	)
	(segment
		(start 3.81508 -157.54223)
		(end 4.191 -157.16631)
		(width 0.508)
		(layer "F.Cu")
		(net "GND")
	)
	(segment
		(start 50.8 -8.1915)
		(end 49.95291 -9.03859)
		(width 0.508)
		(layer "F.Cu")
		(net "GND")
	)
	(segment
		(start 41.975024 -162.414966)
		(end 43.66133 -162.414966)
		(width 0.508)
		(layer "F.Cu")
		(net "GND")
	)
	(segment
		(start 20.025106 -426.265086)
		(end 18.488914 -426.265086)
		(width 0.508)
		(layer "F.Cu")
		(net "GND")
	)
	(segment
		(start 39.05885 -413.8549)
		(end 39.0398 -413.87395)
		(width 0.508)
		(layer "F.Cu")
		(net "GND")
	)
	(segment
		(start 2.249932 -342.742012)
		(end 3.842766 -342.742012)
		(width 0.508)
		(layer "F.Cu")
		(net "GND")
	)
	(segment
		(start 226.974908 -51.794918)
		(end 228.585014 -51.794918)
		(width 0.508)
		(layer "F.Cu")
		(net "GND")
	)
	(segment
		(start 22.800056 -25.009856)
		(end 24.384 -25.009856)
		(width 0.508)
		(layer "F.Cu")
		(net "GND")
	)
	(segment
		(start 3.84302 -352.342196)
		(end 4.191 -352.690176)
		(width 0.508)
		(layer "F.Cu")
		(net "GND")
	)
	(segment
		(start 93.22943 -302.133)
		(end 92.97543 -302.387)
		(width 0.3048)
		(layer "F.Cu")
		(net "GND")
	)
	(segment
		(start 3.842766 -174.342044)
		(end 4.191 -174.690278)
		(width 0.508)
		(layer "F.Cu")
		(net "GND")
	)
	(segment
		(start 93.22943 -309.60441)
		(end 93.22943 -308.09057)
		(width 0.3048)
		(layer "F.Cu")
		(net "GND")
	)
	(segment
		(start 99.18319 -211.07019)
		(end 99.7585 -211.6455)
		(width 0.3048)
		(layer "F.Cu")
		(net "GND")
	)
	(segment
		(start 224.199958 -272.590006)
		(end 222.616014 -272.590006)
		(width 0.508)
		(layer "F.Cu")
		(net "GND")
	)
	(segment
		(start 228.611938 -388.735062)
		(end 228.981 -388.366)
		(width 0.508)
		(layer "F.Cu")
		(net "GND")
	)
	(segment
		(start 2.249932 -216.74201)
		(end 3.842766 -216.74201)
		(width 0.508)
		(layer "F.Cu")
		(net "GND")
	)
	(segment
		(start 210.693 -454.2155)
		(end 210.693 -453.39)
		(width 0.508)
		(layer "F.Cu")
		(net "GND")
	)
	(segment
		(start 3.84302 -191.942212)
		(end 4.191 -192.290192)
		(width 0.508)
		(layer "F.Cu")
		(net "GND")
	)
	(segment
		(start 226.974908 -265.415014)
		(end 228.585014 -265.415014)
		(width 0.508)
		(layer "F.Cu")
		(net "GND")
	)
	(segment
		(start 68.961 -455.1045)
		(end 68.961 -455.93)
		(width 0.508)
		(layer "F.Cu")
		(net "GND")
	)
	(segment
		(start 39.200074 -284.589982)
		(end 37.61613 -284.589982)
		(width 0.508)
		(layer "F.Cu")
		(net "GND")
	)
	(segment
		(start 228.618034 -182.734966)
		(end 228.981 -182.372)
		(width 0.508)
		(layer "F.Cu")
		(net "GND")
	)
	(segment
		(start 224.199958 -179.189888)
		(end 222.616014 -179.189888)
		(width 0.508)
		(layer "F.Cu")
		(net "GND")
	)
	(segment
		(start 224.199958 -284.589982)
		(end 222.616014 -284.589982)
		(width 0.508)
		(layer "F.Cu")
		(net "GND")
	)
	(segment
		(start 41.975024 -484.11511)
		(end 43.58513 -484.11511)
		(width 0.508)
		(layer "F.Cu")
		(net "GND")
	)
	(segment
		(start 39.200074 -468.190072)
		(end 37.61613 -468.190072)
		(width 0.508)
		(layer "F.Cu")
		(net "GND")
	)
	(segment
		(start 20.025106 -21.884894)
		(end 18.415 -21.884894)
		(width 0.508)
		(layer "F.Cu")
		(net "GND")
	)
	(segment
		(start 105.227374 -208.470754)
		(end 105.24617 -208.470754)
		(width 0.508)
		(layer "F.Cu")
		(net "GND")
	)
	(segment
		(start 106.045 -437.3245)
		(end 105.231946 -437.3245)
		(width 0.508)
		(layer "F.Cu")
		(net "GND")
	)
	(segment
		(start 224.199958 -264.590022)
		(end 222.616014 -264.590022)
		(width 0.508)
		(layer "F.Cu")
		(net "GND")
	)
	(segment
		(start 93.22943 -300.75759)
		(end 93.22943 -302.133)
		(width 0.3048)
		(layer "F.Cu")
		(net "GND")
	)
	(segment
		(start 90.7415 -29.718)
		(end 90.7415 -30.607)
		(width 0.508)
		(layer "F.Cu")
		(net "GND")
	)
	(segment
		(start 22.800056 -329.210162)
		(end 24.384 -329.210162)
		(width 0.508)
		(layer "F.Cu")
		(net "GND")
	)
	(segment
		(start 92.97543 -208.026)
		(end 92.71 -208.026)
		(width 0.3048)
		(layer "F.Cu")
		(net "GND")
	)
	(segment
		(start 3.830066 -407.141934)
		(end 4.191 -406.781)
		(width 0.508)
		(layer "F.Cu")
		(net "GND")
	)
	(segment
		(start 209.9945 -299.54982)
		(end 209.9945 -299.98035)
		(width 0.508)
		(layer "F.Cu")
		(net "GND")
	)
	(segment
		(start 24.4094 -298.8818)
		(end 25.4635 -299.9359)
		(width 0.508)
		(layer "F.Cu")
		(net "GND")
	)
	(segment
		(start 2.249932 -289.942016)
		(end 3.81508 -289.942016)
		(width 0.508)
		(layer "F.Cu")
		(net "GND")
	)
	(segment
		(start 78.486 -435.7878)
		(end 77.5462 -435.7878)
		(width 0.508)
		(layer "F.Cu")
		(net "GND")
	)
	(segment
		(start 37.2618 -309.7784)
		(end 37.2618 -309.73395)
		(width 0.508)
		(layer "F.Cu")
		(net "GND")
	)
	(segment
		(start 2.249932 -349.14205)
		(end 3.842766 -349.14205)
		(width 0.508)
		(layer "F.Cu")
		(net "GND")
	)
	(segment
		(start 2.249932 -401.541996)
		(end 3.777996 -401.541996)
		(width 0.508)
		(layer "F.Cu")
		(net "GND")
	)
	(segment
		(start 36.41725 -103.11765)
		(end 36.41725 -102.8954)
		(width 0.508)
		(layer "F.Cu")
		(net "GND")
	)
	(segment
		(start 39.200074 -362.789978)
		(end 37.61613 -362.789978)
		(width 0.508)
		(layer "F.Cu")
		(net "GND")
	)
	(segment
		(start 4.191 -168.205404)
		(end 3.927602 -167.942006)
		(width 0.508)
		(layer "F.Cu")
		(net "GND")
	)
	(segment
		(start 98.530918 -97.84969)
		(end 99.57181 -97.84969)
		(width 0.3048)
		(layer "F.Cu")
		(net "GND")
	)
	(segment
		(start 2.249932 -447.941954)
		(end 3.822954 -447.941954)
		(width 0.508)
		(layer "F.Cu")
		(net "GND")
	)
	(segment
		(start 87.3125 -222.885)
		(end 87.3125 -222.071946)
		(width 0.508)
		(layer "F.Cu")
		(net "GND")
	)
	(segment
		(start 37.973 -206.1972)
		(end 37.973 -206.1845)
		(width 0.508)
		(layer "F.Cu")
		(net "GND")
	)
	(segment
		(start 20.025106 -117.264942)
		(end 18.498058 -117.264942)
		(width 0.508)
		(layer "F.Cu")
		(net "GND")
	)
	(segment
		(start 2.249932 -297.142154)
		(end 3.84302 -297.142154)
		(width 0.508)
		(layer "F.Cu")
		(net "GND")
	)
	(segment
		(start 45.0215 -140.589)
		(end 44.196 -140.589)
		(width 0.508)
		(layer "F.Cu")
		(net "GND")
	)
	(segment
		(start 3.84302 -317.942214)
		(end 4.191 -318.290194)
		(width 0.508)
		(layer "F.Cu")
		(net "GND")
	)
	(segment
		(start 27.71775 -401.5486)
		(end 28.915614 -401.5486)
		(width 0.508)
		(layer "F.Cu")
		(net "GND")
	)
	(segment
		(start 39.200074 -474.59011)
		(end 37.61613 -474.59011)
		(width 0.508)
		(layer "F.Cu")
		(net "GND")
	)
	(segment
		(start 22.800056 -219.009976)
		(end 24.384 -219.009976)
		(width 0.508)
		(layer "F.Cu")
		(net "GND")
	)
	(segment
		(start 68.50126 -378.498608)
		(end 68.50126 -382.855216)
		(width 0.508)
		(layer "F.Cu")
		(net "GND")
	)
	(segment
		(start 93.345 -104.394)
		(end 93.98 -104.394)
		(width 0.3048)
		(layer "F.Cu")
		(net "GND")
	)
	(segment
		(start 85.0265 -209.042)
		(end 84.201 -209.042)
		(width 0.508)
		(layer "F.Cu")
		(net "GND")
	)
	(segment
		(start 31.5595 -308.98465)
		(end 30.361636 -308.98465)
		(width 0.508)
		(layer "F.Cu")
		(net "GND")
	)
	(segment
		(start 208.31175 -401.1295)
		(end 207.42275 -401.1295)
		(width 0.508)
		(layer "F.Cu")
		(net "GND")
	)
	(segment
		(start 96.3295 -222.071946)
		(end 96.323912 -222.066358)
		(width 0.508)
		(layer "F.Cu")
		(net "GND")
	)
	(segment
		(start 208.4451 -48.024542)
		(end 207.790542 -48.024542)
		(width 0.3556)
		(layer "F.Cu")
		(net "GND")
	)
	(segment
		(start 97.8535 -198.755)
		(end 97.8535 -199.5678)
		(width 0.508)
		(layer "F.Cu")
		(net "GND")
	)
	(segment
		(start 221.71025 -446.0875)
		(end 221.71025 -444.9064)
		(width 0.508)
		(layer "F.Cu")
		(net "GND")
	)
	(segment
		(start 2.249932 -323.542152)
		(end 3.81508 -323.542152)
		(width 0.508)
		(layer "F.Cu")
		(net "GND")
	)
	(segment
		(start 86.614 -306.7685)
		(end 85.725 -306.7685)
		(width 0.508)
		(layer "F.Cu")
		(net "GND")
	)
	(segment
		(start 3.81508 -222.342202)
		(end 4.191 -221.966282)
		(width 0.508)
		(layer "F.Cu")
		(net "GND")
	)
	(segment
		(start 2.249932 -155.142184)
		(end 3.84302 -155.142184)
		(width 0.508)
		(layer "F.Cu")
		(net "GND")
	)
	(segment
		(start 22.800056 -138.409934)
		(end 24.384 -138.409934)
		(width 0.508)
		(layer "F.Cu")
		(net "GND")
	)
	(segment
		(start 22.800056 -17.809972)
		(end 24.384 -17.809972)
		(width 0.508)
		(layer "F.Cu")
		(net "GND")
	)
	(segment
		(start 28.956 -374.2055)
		(end 28.956 -373.38)
		(width 0.508)
		(layer "F.Cu")
		(net "GND")
	)
	(segment
		(start 224.199958 -369.190016)
		(end 222.616014 -369.190016)
		(width 0.508)
		(layer "F.Cu")
		(net "GND")
	)
	(segment
		(start 20.025106 -330.885038)
		(end 18.415 -330.885038)
		(width 0.508)
		(layer "F.Cu")
		(net "GND")
	)
	(segment
		(start 37.7698 -105.0036)
		(end 37.9349 -104.8385)
		(width 0.508)
		(layer "F.Cu")
		(net "GND")
	)
	(segment
		(start 2.249932 -450.342)
		(end 3.81 -450.342)
		(width 0.508)
		(layer "F.Cu")
		(net "GND")
	)
	(segment
		(start 41.975024 -55.604918)
		(end 43.58513 -55.604918)
		(width 0.508)
		(layer "F.Cu")
		(net "GND")
	)
	(segment
		(start 2.249932 -309.14213)
		(end 3.81508 -309.14213)
		(width 0.508)
		(layer "F.Cu")
		(net "GND")
	)
	(segment
		(start 209.9945 -196.55282)
		(end 209.9945 -196.98335)
		(width 0.508)
		(layer "F.Cu")
		(net "GND")
	)
	(segment
		(start 98.530918 -214.57031)
		(end 99.94519 -214.57031)
		(width 0.3048)
		(layer "F.Cu")
		(net "GND")
	)
	(segment
		(start 36.576 -371.856)
		(end 35.56 -371.856)
		(width 0.508)
		(layer "F.Cu")
		(net "GND")
	)
	(segment
		(start 24.13508 -13.00988)
		(end 24.4094 -13.2842)
		(width 0.508)
		(layer "F.Cu")
		(net "GND")
	)
	(segment
		(start 36.576 -166.116)
		(end 35.56 -166.116)
		(width 0.508)
		(layer "F.Cu")
		(net "GND")
	)
	(segment
		(start 92.97543 -429.006)
		(end 92.71 -429.006)
		(width 0.3048)
		(layer "F.Cu")
		(net "GND")
	)
	(segment
		(start 18.365724 -351.205038)
		(end 20.025106 -351.205038)
		(width 0.508)
		(layer "F.Cu")
		(net "GND")
	)
	(segment
		(start 22.800056 -20.210018)
		(end 24.384 -20.210018)
		(width 0.508)
		(layer "F.Cu")
		(net "GND")
	)
	(segment
		(start 79.502 -142.8115)
		(end 79.502 -141.986)
		(width 0.508)
		(layer "F.Cu")
		(net "GND")
	)
	(segment
		(start 2.249932 -183.942228)
		(end 3.84302 -183.942228)
		(width 0.508)
		(layer "F.Cu")
		(net "GND")
	)
	(segment
		(start 82.4865 -435.102)
		(end 81.661 -435.102)
		(width 0.508)
		(layer "F.Cu")
		(net "GND")
	)
	(segment
		(start 256.474976 -413.029908)
		(end 253.212092 -413.029908)
		(width 0.8128)
		(layer "F.Cu")
		(net "GND")
	)
	(segment
		(start 3.84302 -303.542192)
		(end 4.191 -303.890172)
		(width 0.508)
		(layer "F.Cu")
		(net "GND")
	)
	(segment
		(start 2.249932 -231.942132)
		(end 3.81508 -231.942132)
		(width 0.508)
		(layer "F.Cu")
		(net "GND")
	)
	(segment
		(start 3.744976 -438.342024)
		(end 4.191 -437.896)
		(width 0.508)
		(layer "F.Cu")
		(net "GND")
	)
	(segment
		(start 31.10103 -188.129418)
		(end 31.10103 -188.9252)
		(width 0.508)
		(layer "F.Cu")
		(net "GND")
	)
	(segment
		(start 39.200074 -279.78989)
		(end 37.61613 -279.78989)
		(width 0.508)
		(layer "F.Cu")
		(net "GND")
	)
	(segment
		(start 20.025106 -38.394894)
		(end 18.415 -38.394894)
		(width 0.508)
		(layer "F.Cu")
		(net "GND")
	)
	(segment
		(start 208.31175 -195.1355)
		(end 207.10525 -195.1355)
		(width 0.508)
		(layer "F.Cu")
		(net "GND")
	)
	(segment
		(start 209.38109 -298.93641)
		(end 209.9945 -299.54982)
		(width 0.508)
		(layer "F.Cu")
		(net "GND")
	)
	(segment
		(start 22.800056 -445.810132)
		(end 24.384 -445.810132)
		(width 0.508)
		(layer "F.Cu")
		(net "GND")
	)
	(segment
		(start 3.780028 -413.541972)
		(end 4.191 -413.131)
		(width 0.508)
		(layer "F.Cu")
		(net "GND")
	)
	(segment
		(start 3.842766 -158.342076)
		(end 4.191 -158.69031)
		(width 0.508)
		(layer "F.Cu")
		(net "GND")
	)
	(segment
		(start 39.63924 -140.80236)
		(end 40.005 -140.4366)
		(width 0.3556)
		(layer "F.Cu")
		(net "GND")
	)
	(segment
		(start 93.22943 -308.09057)
		(end 93.345 -307.975)
		(width 0.3048)
		(layer "F.Cu")
		(net "GND")
	)
	(segment
		(start 89.34196 -223.659954)
		(end 89.3445 -223.657414)
		(width 0.508)
		(layer "F.Cu")
		(net "GND")
	)
	(segment
		(start 3.84302 -306.742084)
		(end 4.191 -307.090064)
		(width 0.508)
		(layer "F.Cu")
		(net "GND")
	)
	(segment
		(start 2.249932 -335.542128)
		(end 3.81508 -335.542128)
		(width 0.508)
		(layer "F.Cu")
		(net "GND")
	)
	(segment
		(start 207.790542 -48.024542)
		(end 207.264 -47.498)
		(width 0.3556)
		(layer "F.Cu")
		(net "GND")
	)
	(segment
		(start 4.191 -436.235348)
		(end 3.89763 -435.941978)
		(width 0.508)
		(layer "F.Cu")
		(net "GND")
	)
	(segment
		(start 2.249932 -432.741832)
		(end 3.884168 -432.741832)
		(width 0.508)
		(layer "F.Cu")
		(net "GND")
	)
	(segment
		(start 226.974908 -257.795014)
		(end 228.585014 -257.795014)
		(width 0.508)
		(layer "F.Cu")
		(net "GND")
	)
	(segment
		(start 99.405186 -102.0191)
		(end 99.236276 -101.85019)
		(width 0.3048)
		(layer "F.Cu")
		(net "GND")
	)
	(segment
		(start 22.800056 -140.80998)
		(end 24.383746 -140.80998)
		(width 0.508)
		(layer "F.Cu")
		(net "GND")
	)
	(segment
		(start 98.3615 -113.187226)
		(end 98.3615 -113.665)
		(width 0.508)
		(layer "F.Cu")
		(net "GND")
	)
	(segment
		(start 43.572938 -388.735062)
		(end 43.942 -388.366)
		(width 0.508)
		(layer "F.Cu")
		(net "GND")
	)
	(segment
		(start 17.992852 -351.57791)
		(end 18.365724 -351.205038)
		(width 0.508)
		(layer "F.Cu")
		(net "GND")
	)
	(segment
		(start 87.3125 -443.033912)
		(end 87.302086 -443.023498)
		(width 0.508)
		(layer "F.Cu")
		(net "GND")
	)
	(segment
		(start 220.7895 -35.84575)
		(end 220.7895 -36.7665)
		(width 0.508)
		(layer "F.Cu")
		(net "GND")
	)
	(segment
		(start 76.449936 -363.0422)
		(end 76.449936 -364.109)
		(width 0.3048)
		(layer "F.Cu")
		(net "GND")
	)
	(segment
		(start 85.0265 -430.53)
		(end 84.201 -430.53)
		(width 0.508)
		(layer "F.Cu")
		(net "GND")
	)
	(segment
		(start 28.393644 -378.024644)
		(end 28.945078 -378.024644)
		(width 0.3556)
		(layer "F.Cu")
		(net "GND")
	)
	(segment
		(start 17.0053 -498.17655)
		(end 18.203164 -498.17655)
		(width 0.508)
		(layer "F.Cu")
		(net "GND")
	)
	(segment
		(start 82.4865 -214.122)
		(end 81.661 -214.122)
		(width 0.508)
		(layer "F.Cu")
		(net "GND")
	)
	(segment
		(start 22.800056 -235.009944)
		(end 24.384 -235.009944)
		(width 0.508)
		(layer "F.Cu")
		(net "GND")
	)
	(segment
		(start 224.199958 -286.990028)
		(end 222.616014 -286.990028)
		(width 0.508)
		(layer "F.Cu")
		(net "GND")
	)
	(segment
		(start 85.0265 -99.822)
		(end 84.201 -99.822)
		(width 0.508)
		(layer "F.Cu")
		(net "GND")
	)
	(segment
		(start 3.84302 -355.542088)
		(end 4.191 -355.890068)
		(width 0.508)
		(layer "F.Cu")
		(net "GND")
	)
	(segment
		(start 22.800056 -425.010072)
		(end 24.384 -425.010072)
		(width 0.508)
		(layer "F.Cu")
		(net "GND")
	)
	(segment
		(start 41.975024 -364.605062)
		(end 43.58513 -364.605062)
		(width 0.508)
		(layer "F.Cu")
		(net "GND")
	)
	(segment
		(start 3.884168 -432.741832)
		(end 4.191 -432.435)
		(width 0.508)
		(layer "F.Cu")
		(net "GND")
	)
	(segment
		(start 214.9475 -93.98635)
		(end 216.145364 -93.98635)
		(width 0.508)
		(layer "F.Cu")
		(net "GND")
	)
	(segment
		(start 2.249932 -303.542192)
		(end 3.84302 -303.542192)
		(width 0.508)
		(layer "F.Cu")
		(net "GND")
	)
	(segment
		(start 224.199958 -167.990012)
		(end 222.616014 -167.990012)
		(width 0.508)
		(layer "F.Cu")
		(net "GND")
	)
	(segment
		(start 27.6987 -393.2428)
		(end 26.8478 -393.2428)
		(width 0.508)
		(layer "F.Cu")
		(net "GND")
	)
	(segment
		(start 226.974908 -72.114918)
		(end 228.585014 -72.114918)
		(width 0.508)
		(layer "F.Cu")
		(net "GND")
	)
	(segment
		(start 99.949 -214.5665)
		(end 100.838 -214.5665)
		(width 0.508)
		(layer "F.Cu")
		(net "GND")
	)
	(segment
		(start 88.646 -305.93157)
		(end 87.80907 -306.7685)
		(width 0.3048)
		(layer "F.Cu")
		(net "GND")
	)
	(segment
		(start 92.97543 -98.806)
		(end 92.71 -98.806)
		(width 0.3048)
		(layer "F.Cu")
		(net "GND")
	)
	(segment
		(start 3.842766 -207.14208)
		(end 4.191 -207.490314)
		(width 0.508)
		(layer "F.Cu")
		(net "GND")
	)
	(segment
		(start 3.81508 -154.342084)
		(end 4.191 -153.966164)
		(width 0.508)
		(layer "F.Cu")
		(net "GND")
	)
	(segment
		(start 85.0265 -303.403)
		(end 84.201 -303.403)
		(width 0.508)
		(layer "F.Cu")
		(net "GND")
	)
	(segment
		(start 4.191 -163.71062)
		(end 3.959606 -163.942014)
		(width 0.508)
		(layer "F.Cu")
		(net "GND")
	)
	(segment
		(start 41.975024 -173.844966)
		(end 43.58513 -173.844966)
		(width 0.508)
		(layer "F.Cu")
		(net "GND")
	)
	(segment
		(start 224.199958 -367.59007)
		(end 222.616014 -367.59007)
		(width 0.508)
		(layer "F.Cu")
		(net "GND")
	)
	(segment
		(start 30.4165 -299.98035)
		(end 31.5214 -299.98035)
		(width 0.508)
		(layer "F.Cu")
		(net "GND")
	)
	(segment
		(start 89.55659 -435.04993)
		(end 88.88857 -435.04993)
		(width 0.3048)
		(layer "F.Cu")
		(net "GND")
	)
	(segment
		(start 3.84302 -210.342226)
		(end 4.191 -210.690206)
		(width 0.508)
		(layer "F.Cu")
		(net "GND")
	)
	(segment
		(start 256.474976 -414.299908)
		(end 252.704092 -414.299908)
		(width 0.8128)
		(layer "F.Cu")
		(net "GND")
	)
	(segment
		(start 74.422 -443.484)
		(end 74.422 -442.595)
		(width 0.508)
		(layer "F.Cu")
		(net "GND")
	)
	(segment
		(start 226.699064 -436.494936)
		(end 226.699064 -435.878224)
		(width 0.3048)
		(layer "F.Cu")
		(net "GND")
	)
	(segment
		(start 3.728212 -403.941788)
		(end 4.191 -403.479)
		(width 0.508)
		(layer "F.Cu")
		(net "GND")
	)
	(segment
		(start 32.11703 -85.107018)
		(end 32.11703 -85.9282)
		(width 0.508)
		(layer "F.Cu")
		(net "GND")
	)
	(segment
		(start 208.31175 -298.1325)
		(end 207.10525 -298.1325)
		(width 0.508)
		(layer "F.Cu")
		(net "GND")
	)
	(segment
		(start 226.974908 -360.795062)
		(end 228.585014 -360.795062)
		(width 0.508)
		(layer "F.Cu")
		(net "GND")
	)
	(segment
		(start 3.957828 -383.941828)
		(end 2.249932 -383.941828)
		(width 0.508)
		(layer "F.Cu")
		(net "GND")
	)
	(segment
		(start 49.3395 -7.99465)
		(end 49.3395 -8.42518)
		(width 0.508)
		(layer "F.Cu")
		(net "GND")
	)
	(segment
		(start 3.84302 -336.342228)
		(end 4.191 -336.690208)
		(width 0.508)
		(layer "F.Cu")
		(net "GND")
	)
	(segment
		(start 2.249932 -177.54219)
		(end 3.84302 -177.54219)
		(width 0.508)
		(layer "F.Cu")
		(net "GND")
	)
	(segment
		(start 3.84302 -229.542086)
		(end 4.191 -229.890066)
		(width 0.508)
		(layer "F.Cu")
		(net "GND")
	)
	(segment
		(start 3.81508 -160.742122)
		(end 4.191 -160.366202)
		(width 0.508)
		(layer "F.Cu")
		(net "GND")
	)
	(segment
		(start 87.3125 -113.665)
		(end 87.3125 -114.554)
		(width 0.508)
		(layer "F.Cu")
		(net "GND")
	)
	(segment
		(start 39.200074 -179.189888)
		(end 37.61613 -179.189888)
		(width 0.508)
		(layer "F.Cu")
		(net "GND")
	)
	(segment
		(start 3.750818 -414.341818)
		(end 4.191 -414.782)
		(width 0.508)
		(layer "F.Cu")
		(net "GND")
	)
	(segment
		(start 2.249932 -229.542086)
		(end 3.84302 -229.542086)
		(width 0.508)
		(layer "F.Cu")
		(net "GND")
	)
	(segment
		(start 22.800056 -239.810036)
		(end 24.164036 -239.810036)
		(width 0.508)
		(layer "F.Cu")
		(net "GND")
	)
	(segment
		(start 221.71025 -240.087658)
		(end 221.71025 -238.99495)
		(width 0.508)
		(layer "F.Cu")
		(net "GND")
	)
	(segment
		(start 201.800206 -497.975128)
		(end 202.99807 -497.975128)
		(width 0.508)
		(layer "F.Cu")
		(net "GND")
	)
	(segment
		(start 224.199958 -483.390194)
		(end 222.616014 -483.390194)
		(width 0.508)
		(layer "F.Cu")
		(net "GND")
	)
	(segment
		(start 22.800056 -324.41007)
		(end 24.384 -324.41007)
		(width 0.508)
		(layer "F.Cu")
		(net "GND")
	)
	(segment
		(start 39.200074 -389.990076)
		(end 37.61613 -389.990076)
		(width 0.508)
		(layer "F.Cu")
		(net "GND")
	)
	(segment
		(start 224.199958 -76.18984)
		(end 222.616014 -76.18984)
		(width 0.508)
		(layer "F.Cu")
		(net "GND")
	)
	(segment
		(start 22.800056 -441.01004)
		(end 24.384 -441.01004)
		(width 0.508)
		(layer "F.Cu")
		(net "GND")
	)
	(segment
		(start 20.025106 -323.265038)
		(end 18.491962 -323.265038)
		(width 0.508)
		(layer "F.Cu")
		(net "GND")
	)
	(segment
		(start 84.0105 -424.942)
		(end 83.185 -424.942)
		(width 0.508)
		(layer "F.Cu")
		(net "GND")
	)
	(segment
		(start 2.249932 -157.54223)
		(end 3.81508 -157.54223)
		(width 0.508)
		(layer "F.Cu")
		(net "GND")
	)
	(segment
		(start 39.200074 -64.989964)
		(end 37.61613 -64.989964)
		(width 0.508)
		(layer "F.Cu")
		(net "GND")
	)
	(segment
		(start 225.5012 -437.6928)
		(end 226.314 -436.88)
		(width 0.508)
		(layer "F.Cu")
		(net "GND")
	)
	(segment
		(start 224.199958 -165.589966)
		(end 222.616014 -165.589966)
		(width 0.508)
		(layer "F.Cu")
		(net "GND")
	)
	(segment
		(start 39.200074 -470.590118)
		(end 37.61613 -470.590118)
		(width 0.508)
		(layer "F.Cu")
		(net "GND")
	)
	(segment
		(start 37.2618 -309.73395)
		(end 36.5125 -308.98465)
		(width 0.508)
		(layer "F.Cu")
		(net "GND")
	)
	(segment
		(start 2.249932 -345.942158)
		(end 3.84302 -345.942158)
		(width 0.508)
		(layer "F.Cu")
		(net "GND")
	)
	(segment
		(start 226.974908 -175.114966)
		(end 228.585014 -175.114966)
		(width 0.508)
		(layer "F.Cu")
		(net "GND")
	)
	(segment
		(start 3.695192 -444.741808)
		(end 4.191 -444.246)
		(width 0.508)
		(layer "F.Cu")
		(net "GND")
	)
	(segment
		(start 39.200074 -159.189928)
		(end 37.61613 -159.189928)
		(width 0.508)
		(layer "F.Cu")
		(net "GND")
	)
	(segment
		(start 88.011 -105.8545)
		(end 88.011 -105.7275)
		(width 0.3048)
		(layer "F.Cu")
		(net "GND")
	)
	(segment
		(start 22.800056 -449.810124)
		(end 24.384 -449.810124)
		(width 0.508)
		(layer "F.Cu")
		(net "GND")
	)
	(segment
		(start 39.200074 -472.190064)
		(end 37.61613 -472.190064)
		(width 0.508)
		(layer "F.Cu")
		(net "GND")
	)
	(segment
		(start 3.81508 -289.942016)
		(end 4.191 -289.566096)
		(width 0.508)
		(layer "F.Cu")
		(net "GND")
	)
	(segment
		(start 2.249932 -389.54202)
		(end 3.84302 -389.54202)
		(width 0.508)
		(layer "F.Cu")
		(net "GND")
	)
	(segment
		(start 224.199958 -485.789986)
		(end 222.616014 -485.789986)
		(width 0.508)
		(layer "F.Cu")
		(net "GND")
	)
	(segment
		(start 2.249932 -151.942038)
		(end 4.191 -151.942038)
		(width 0.508)
		(layer "F.Cu")
		(net "GND")
	)
	(segment
		(start 3.745738 -439.14187)
		(end 2.249932 -439.14187)
		(width 0.508)
		(layer "F.Cu")
		(net "GND")
	)
	(segment
		(start 21.017992 -371.322092)
		(end 21.017992 -372.25224)
		(width 0.508)
		(layer "F.Cu")
		(net "GND")
	)
	(segment
		(start 22.800056 -116.009928)
		(end 24.384 -116.009928)
		(width 0.508)
		(layer "F.Cu")
		(net "GND")
	)
	(segment
		(start 224.199958 -490.590078)
		(end 222.616014 -490.590078)
		(width 0.508)
		(layer "F.Cu")
		(net "GND")
	)
	(segment
		(start 20.025106 -433.885086)
		(end 18.415 -433.885086)
		(width 0.508)
		(layer "F.Cu")
		(net "GND")
	)
	(segment
		(start 82.8294 -148.1836)
		(end 83.6676 -148.1836)
		(width 0.508)
		(layer "F.Cu")
		(net "GND")
	)
	(segment
		(start 226.3775 -137.26287)
		(end 226.3775 -136.525)
		(width 0.381)
		(layer "F.Cu")
		(net "GND")
	)
	(segment
		(start 22.800056 -221.410022)
		(end 24.383746 -221.410022)
		(width 0.508)
		(layer "F.Cu")
		(net "GND")
	)
	(segment
		(start 224.199958 -259.78993)
		(end 222.616014 -259.78993)
		(width 0.508)
		(layer "F.Cu")
		(net "GND")
	)
	(segment
		(start 98.7425 -426.635418)
		(end 98.530918 -426.847)
		(width 0.3048)
		(layer "F.Cu")
		(net "GND")
	)
	(segment
		(start 226.974908 -276.845014)
		(end 228.585014 -276.845014)
		(width 0.508)
		(layer "F.Cu")
		(net "GND")
	)
	(segment
		(start 51.08575 -241.992658)
		(end 51.08575 -243.1288)
		(width 0.508)
		(layer "F.Cu")
		(net "GND")
	)
	(segment
		(start 2.249932 -305.941984)
		(end 3.81508 -305.941984)
		(width 0.508)
		(layer "F.Cu")
		(net "GND")
	)
	(segment
		(start 24.003 -299.2882)
		(end 24.4094 -298.8818)
		(width 0.508)
		(layer "F.Cu")
		(net "GND")
	)
	(segment
		(start 95.885 -25.7175)
		(end 95.885 -24.892)
		(width 0.508)
		(layer "F.Cu")
		(net "GND")
	)
	(segment
		(start 215.3539 -495.2238)
		(end 214.5792 -495.2238)
		(width 0.508)
		(layer "F.Cu")
		(net "GND")
	)
	(segment
		(start 3.81508 -348.342204)
		(end 4.191 -347.966284)
		(width 0.508)
		(layer "F.Cu")
		(net "GND")
	)
	(segment
		(start 31.6865 -381.508)
		(end 31.369 -381.8255)
		(width 0.508)
		(layer "F.Cu")
		(net "GND")
	)
	(segment
		(start 22.800056 -349.210122)
		(end 24.384 -349.210122)
		(width 0.508)
		(layer "F.Cu")
		(net "GND")
	)
	(segment
		(start 3.81508 -176.74209)
		(end 4.191 -176.36617)
		(width 0.508)
		(layer "F.Cu")
		(net "GND")
	)
	(segment
		(start 2.249932 -194.342004)
		(end 3.81508 -194.342004)
		(width 0.508)
		(layer "F.Cu")
		(net "GND")
	)
	(segment
		(start 224.199958 -80.989932)
		(end 222.616014 -80.989932)
		(width 0.508)
		(layer "F.Cu")
		(net "GND")
	)
	(segment
		(start 18.034 -14.732)
		(end 18.501106 -14.264894)
		(width 0.508)
		(layer "F.Cu")
		(net "GND")
	)
	(segment
		(start 228.621082 -79.734918)
		(end 228.981 -79.375)
		(width 0.508)
		(layer "F.Cu")
		(net "GND")
	)
	(segment
		(start 44.3865 -7.99465)
		(end 43.188636 -7.99465)
		(width 0.508)
		(layer "F.Cu")
		(net "GND")
	)
	(segment
		(start 22.800056 -120.81002)
		(end 24.384 -120.81002)
		(width 0.508)
		(layer "F.Cu")
		(net "GND")
	)
	(segment
		(start 217.043 -290.9951)
		(end 217.043 -291.7698)
		(width 0.508)
		(layer "F.Cu")
		(net "GND")
	)
	(segment
		(start 78.2066 -105.7148)
		(end 77.3176 -105.7148)
		(width 0.508)
		(layer "F.Cu")
		(net "GND")
	)
	(segment
		(start 39.200074 -262.189976)
		(end 37.61613 -262.189976)
		(width 0.508)
		(layer "F.Cu")
		(net "GND")
	)
	(segment
		(start 3.84302 -183.942228)
		(end 4.191 -184.290208)
		(width 0.508)
		(layer "F.Cu")
		(net "GND")
	)
	(segment
		(start 2.249932 -180.742082)
		(end 3.84302 -180.742082)
		(width 0.508)
		(layer "F.Cu")
		(net "GND")
	)
	(segment
		(start 209.38109 -401.93341)
		(end 209.9945 -402.54682)
		(width 0.508)
		(layer "F.Cu")
		(net "GND")
	)
	(segment
		(start 39.200074 -259.78993)
		(end 37.61613 -259.78993)
		(width 0.508)
		(layer "F.Cu")
		(net "GND")
	)
	(segment
		(start 2.249932 -410.341826)
		(end 3.805174 -410.341826)
		(width 0.508)
		(layer "F.Cu")
		(net "GND")
	)
	(segment
		(start 39.200074 -56.18988)
		(end 37.61613 -56.18988)
		(width 0.508)
		(layer "F.Cu")
		(net "GND")
	)
	(segment
		(start 39.200074 -488.190032)
		(end 37.61613 -488.190032)
		(width 0.508)
		(layer "F.Cu")
		(net "GND")
	)
	(segment
		(start 25.4635 -299.9359)
		(end 25.4635 -299.98035)
		(width 0.508)
		(layer "F.Cu")
		(net "GND")
	)
	(segment
		(start 2.249932 -403.941788)
		(end 3.728212 -403.941788)
		(width 0.508)
		(layer "F.Cu")
		(net "GND")
	)
	(segment
		(start 39.200074 -71.390002)
		(end 37.61613 -71.390002)
		(width 0.508)
		(layer "F.Cu")
		(net "GND")
	)
	(segment
		(start 224.199958 -488.190032)
		(end 222.616014 -488.190032)
		(width 0.508)
		(layer "F.Cu")
		(net "GND")
	)
	(segment
		(start 37.3634 -206.8068)
		(end 37.33165 -206.8068)
		(width 0.508)
		(layer "F.Cu")
		(net "GND")
	)
	(segment
		(start 2.249932 -281.142186)
		(end 3.84302 -281.142186)
		(width 0.508)
		(layer "F.Cu")
		(net "GND")
	)
	(segment
		(start 98.9965 -437.769)
		(end 99.822 -437.769)
		(width 0.508)
		(layer "F.Cu")
		(net "GND")
	)
	(segment
		(start 3.842766 -216.74201)
		(end 4.191 -217.090244)
		(width 0.508)
		(layer "F.Cu")
		(net "GND")
	)
	(segment
		(start 3.84302 -203.942188)
		(end 4.191 -204.290168)
		(width 0.508)
		(layer "F.Cu")
		(net "GND")
	)
	(segment
		(start 3.81508 -179.941982)
		(end 4.191 -179.566062)
		(width 0.508)
		(layer "F.Cu")
		(net "GND")
	)
	(segment
		(start 93.22943 -213.72957)
		(end 93.345 -213.614)
		(width 0.3048)
		(layer "F.Cu")
		(net "GND")
	)
	(segment
		(start 3.81508 -351.542096)
		(end 4.191 -351.166176)
		(width 0.508)
		(layer "F.Cu")
		(net "GND")
	)
	(segment
		(start 2.249932 -341.942166)
		(end 3.81508 -341.942166)
		(width 0.508)
		(layer "F.Cu")
		(net "GND")
	)
	(segment
		(start 3.84302 -155.142184)
		(end 4.191 -155.490164)
		(width 0.508)
		(layer "F.Cu")
		(net "GND")
	)
	(segment
		(start 87.3125 -317.246)
		(end 87.3125 -316.41288)
		(width 0.508)
		(layer "F.Cu")
		(net "GND")
	)
	(segment
		(start 211.1375 -51.562)
		(end 210.312 -51.562)
		(width 0.508)
		(layer "F.Cu")
		(net "GND")
	)
	(segment
		(start 36.576 -62.865)
		(end 35.56 -62.865)
		(width 0.508)
		(layer "F.Cu")
		(net "GND")
	)
	(segment
		(start 224.199958 -373.990108)
		(end 222.616014 -373.990108)
		(width 0.508)
		(layer "F.Cu")
		(net "GND")
	)
	(segment
		(start 22.800056 -427.410118)
		(end 24.383746 -427.410118)
		(width 0.508)
		(layer "F.Cu")
		(net "GND")
	)
	(segment
		(start 20.025106 -244.39499)
		(end 18.415 -244.39499)
		(width 0.508)
		(layer "F.Cu")
		(net "GND")
	)
	(segment
		(start 100.4824 -102.0191)
		(end 99.405186 -102.0191)
		(width 0.3048)
		(layer "F.Cu")
		(net "GND")
	)
	(segment
		(start 224.199958 -262.189976)
		(end 222.616014 -262.189976)
		(width 0.508)
		(layer "F.Cu")
		(net "GND")
	)
	(segment
		(start 3.81508 -299.5422)
		(end 4.191 -299.16628)
		(width 0.508)
		(layer "F.Cu")
		(net "GND")
	)
	(segment
		(start 88.88857 -435.04993)
		(end 88.011 -435.9275)
		(width 0.3048)
		(layer "F.Cu")
		(net "GND")
	)
	(segment
		(start 2.249932 -441.541916)
		(end 3.720084 -441.541916)
		(width 0.508)
		(layer "F.Cu")
		(net "GND")
	)
	(segment
		(start 3.81508 -283.542232)
		(end 4.191 -283.166312)
		(width 0.508)
		(layer "F.Cu")
		(net "GND")
	)
	(segment
		(start 3.90398 -186.34202)
		(end 4.191 -186.055)
		(width 0.508)
		(layer "F.Cu")
		(net "GND")
	)
	(segment
		(start 208.026 -454.2155)
		(end 208.026 -453.39)
		(width 0.508)
		(layer "F.Cu")
		(net "GND")
	)
	(segment
		(start 39.200074 -171.990004)
		(end 37.61613 -171.990004)
		(width 0.508)
		(layer "F.Cu")
		(net "GND")
	)
	(segment
		(start 210.439 -44.2595)
		(end 210.439 -43.434)
		(width 0.508)
		(layer "F.Cu")
		(net "GND")
	)
	(segment
		(start 89.3445 -318.056768)
		(end 89.3445 -317.246)
		(width 0.508)
		(layer "F.Cu")
		(net "GND")
	)
	(segment
		(start 41.975024 -463.79511)
		(end 43.58513 -463.79511)
		(width 0.508)
		(layer "F.Cu")
		(net "GND")
	)
	(segment
		(start 224.199958 -282.189936)
		(end 222.616014 -282.189936)
		(width 0.508)
		(layer "F.Cu")
		(net "GND")
	)
	(segment
		(start 39.200074 -167.990012)
		(end 37.61613 -167.990012)
		(width 0.508)
		(layer "F.Cu")
		(net "GND")
	)
	(segment
		(start 41.975024 -388.735062)
		(end 43.572938 -388.735062)
		(width 0.508)
		(layer "F.Cu")
		(net "GND")
	)
	(segment
		(start 105.226612 -310.7055)
		(end 105.225596 -310.704484)
		(width 0.508)
		(layer "F.Cu")
		(net "GND")
	)
	(segment
		(start 87.503 -103.1875)
		(end 87.80907 -103.1875)
		(width 0.3048)
		(layer "F.Cu")
		(net "GND")
	)
	(segment
		(start 226.974908 -463.79511)
		(end 228.585014 -463.79511)
		(width 0.508)
		(layer "F.Cu")
		(net "GND")
	)
	(segment
		(start 3.82778 -407.94178)
		(end 4.191 -408.305)
		(width 0.508)
		(layer "F.Cu")
		(net "GND")
	)
	(segment
		(start 224.199958 -73.789794)
		(end 222.616014 -73.789794)
		(width 0.508)
		(layer "F.Cu")
		(net "GND")
	)
	(segment
		(start 41.975024 -491.73511)
		(end 43.56989 -491.73511)
		(width 0.508)
		(layer "F.Cu")
		(net "GND")
	)
	(segment
		(start 41.975024 -257.795014)
		(end 43.58513 -257.795014)
		(width 0.508)
		(layer "F.Cu")
		(net "GND")
	)
	(segment
		(start 2.249932 -426.341794)
		(end 3.807206 -426.341794)
		(width 0.508)
		(layer "F.Cu")
		(net "GND")
	)
	(segment
		(start 2.249932 -414.341818)
		(end 3.750818 -414.341818)
		(width 0.508)
		(layer "F.Cu")
		(net "GND")
	)
	(segment
		(start 20.025106 -229.15499)
		(end 18.415 -229.15499)
		(width 0.508)
		(layer "F.Cu")
		(net "GND")
	)
	(segment
		(start 3.81508 -194.342004)
		(end 4.191 -193.966084)
		(width 0.508)
		(layer "F.Cu")
		(net "GND")
	)
	(segment
		(start 39.200074 -483.390194)
		(end 37.61613 -483.390194)
		(width 0.508)
		(layer "F.Cu")
		(net "GND")
	)
	(segment
		(start 12.1539 -498.20195)
		(end 12.1539 -497.5733)
		(width 0.508)
		(layer "F.Cu")
		(net "GND")
	)
	(segment
		(start 89.349834 -318.062102)
		(end 89.3445 -318.056768)
		(width 0.508)
		(layer "F.Cu")
		(net "GND")
	)
	(segment
		(start 37.0586 -103.759)
		(end 36.41725 -103.11765)
		(width 0.508)
		(layer "F.Cu")
		(net "GND")
	)
	(segment
		(start 90.4875 -419.735)
		(end 90.4875 -420.55034)
		(width 0.508)
		(layer "F.Cu")
		(net "GND")
	)
	(segment
		(start 24.044402 -92.1385)
		(end 24.345646 -91.837256)
		(width 0.508)
		(layer "F.Cu")
		(net "GND")
	)
	(segment
		(start 3.84302 -389.54202)
		(end 4.191 -389.89)
		(width 0.508)
		(layer "F.Cu")
		(net "GND")
	)
	(segment
		(start 3.959606 -163.942014)
		(end 2.249932 -163.942014)
		(width 0.508)
		(layer "F.Cu")
		(net "GND")
	)
	(segment
		(start 3.81508 -345.142058)
		(end 4.191 -344.766138)
		(width 0.508)
		(layer "F.Cu")
		(net "GND")
	)
	(segment
		(start 89.34196 -223.702118)
		(end 89.34196 -223.659954)
		(width 0.508)
		(layer "F.Cu")
		(net "GND")
	)
	(segment
		(start 88.011 -215.0745)
		(end 88.011 -214.9475)
		(width 0.3048)
		(layer "F.Cu")
		(net "GND")
	)
	(segment
		(start 43.56989 -491.73511)
		(end 43.942 -491.363)
		(width 0.508)
		(layer "F.Cu")
		(net "GND")
	)
	(segment
		(start 224.663 -437.6928)
		(end 225.5012 -437.6928)
		(width 0.508)
		(layer "F.Cu")
		(net "GND")
	)
	(segment
		(start 226.974908 -162.414966)
		(end 228.585014 -162.414966)
		(width 0.508)
		(layer "F.Cu")
		(net "GND")
	)
	(segment
		(start 3.81508 -231.942132)
		(end 4.191 -231.566212)
		(width 0.508)
		(layer "F.Cu")
		(net "GND")
	)
	(segment
		(start 78.232 -309.245)
		(end 77.343 -309.245)
		(width 0.508)
		(layer "F.Cu")
		(net "GND")
	)
	(segment
		(start 98.530918 -206.523082)
		(end 98.530918 -207.06969)
		(width 0.3048)
		(layer "F.Cu")
		(net "GND")
	)
	(segment
		(start 3.81508 -357.942134)
		(end 4.191 -357.566214)
		(width 0.508)
		(layer "F.Cu")
		(net "GND")
	)
	(segment
		(start 39.200074 -169.589958)
		(end 37.61613 -169.589958)
		(width 0.508)
		(layer "F.Cu")
		(net "GND")
	)
	(segment
		(start 3.84302 -290.742116)
		(end 4.191 -291.090096)
		(width 0.508)
		(layer "F.Cu")
		(net "GND")
	)
	(segment
		(start 77.089 -353.6315)
		(end 77.089 -352.806)
		(width 0.508)
		(layer "F.Cu")
		(net "GND")
	)
	(segment
		(start 37.9349 -104.8385)
		(end 38.65245 -104.8385)
		(width 0.508)
		(layer "F.Cu")
		(net "GND")
	)
	(segment
		(start 18.501106 -14.264894)
		(end 20.025106 -14.264894)
		(width 0.508)
		(layer "F.Cu")
		(net "GND")
	)
	(segment
		(start 256.474976 -418.109908)
		(end 252.704092 -418.109908)
		(width 0.8128)
		(layer "F.Cu")
		(net "GND")
	)
	(segment
		(start 232.791 -438.5564)
		(end 232.791 -439.293)
		(width 0.508)
		(layer "F.Cu")
		(net "GND")
	)
	(segment
		(start 2.249932 -195.142104)
		(end 3.84302 -195.142104)
		(width 0.508)
		(layer "F.Cu")
		(net "GND")
	)
	(segment
		(start 10.287 -408.559)
		(end 10.4394 -408.7114)
		(width 1.016)
		(layer "F.Cu")
		(net "GND")
	)
	(segment
		(start 224.199958 -385.189984)
		(end 222.616014 -385.189984)
		(width 0.508)
		(layer "F.Cu")
		(net "GND")
	)
	(segment
		(start 20.828 -62.798452)
		(end 21.6535 -62.798452)
		(width 0.508)
		(layer "F.Cu")
		(net "GND")
	)
	(segment
		(start 39.200074 -270.99006)
		(end 37.61613 -270.99006)
		(width 0.508)
		(layer "F.Cu")
		(net "GND")
	)
	(segment
		(start 4.191 -416.52063)
		(end 3.969766 -416.741864)
		(width 0.508)
		(layer "F.Cu")
		(net "GND")
	)
	(segment
		(start 22.800056 -322.010024)
		(end 24.384 -322.010024)
		(width 0.508)
		(layer "F.Cu")
		(net "GND")
	)
	(segment
		(start 87.503 -103.1875)
		(end 86.614 -103.1875)
		(width 0.508)
		(layer "F.Cu")
		(net "GND")
	)
	(segment
		(start 96.3295 -222.885)
		(end 96.3295 -222.071946)
		(width 0.508)
		(layer "F.Cu")
		(net "GND")
	)
	(segment
		(start 3.81508 -209.542126)
		(end 4.191 -209.166206)
		(width 0.508)
		(layer "F.Cu")
		(net "GND")
	)
	(segment
		(start 95.0722 -21.5011)
		(end 95.0722 -20.6756)
		(width 0.508)
		(layer "F.Cu")
		(net "GND")
	)
	(segment
		(start 93.22943 -428.752)
		(end 92.97543 -429.006)
		(width 0.3048)
		(layer "F.Cu")
		(net "GND")
	)
	(segment
		(start 99.5045 -89.535)
		(end 99.5045 -90.3605)
		(width 0.508)
		(layer "F.Cu")
		(net "GND")
	)
	(segment
		(start 22.800056 -331.609954)
		(end 24.384 -331.609954)
		(width 0.508)
		(layer "F.Cu")
		(net "GND")
	)
	(segment
		(start 90.7415 -30.607)
		(end 90.7415 -31.496)
		(width 0.508)
		(layer "F.Cu")
		(net "GND")
	)
	(segment
		(start 22.800056 -136.809988)
		(end 24.160988 -136.809988)
		(width 0.508)
		(layer "F.Cu")
		(net "GND")
	)
	(segment
		(start 31.5595 -411.98165)
		(end 30.361636 -411.98165)
		(width 0.508)
		(layer "F.Cu")
		(net "GND")
	)
	(segment
		(start 2.249932 -395.141958)
		(end 3.765042 -395.141958)
		(width 0.508)
		(layer "F.Cu")
		(net "GND")
	)
	(segment
		(start 87.503 -212.4075)
		(end 87.80907 -212.4075)
		(width 0.3048)
		(layer "F.Cu")
		(net "GND")
	)
	(segment
		(start 88.011 -105.7275)
		(end 88.88857 -104.84993)
		(width 0.3048)
		(layer "F.Cu")
		(net "GND")
	)
	(segment
		(start 22.800056 -241.409982)
		(end 24.384 -241.409982)
		(width 0.508)
		(layer "F.Cu")
		(net "GND")
	)
	(segment
		(start 3.807714 -427.141894)
		(end 2.249932 -427.141894)
		(width 0.508)
		(layer "F.Cu")
		(net "GND")
	)
	(segment
		(start 3.748786 -430.341786)
		(end 4.191 -430.784)
		(width 0.508)
		(layer "F.Cu")
		(net "GND")
	)
	(segment
		(start 24.164036 -239.810036)
		(end 24.384 -240.03)
		(width 0.508)
		(layer "F.Cu")
		(net "GND")
	)
	(segment
		(start 2.249932 -398.34185)
		(end 3.74015 -398.34185)
		(width 0.508)
		(layer "F.Cu")
		(net "GND")
	)
	(segment
		(start 2.249932 -404.741888)
		(end 3.802888 -404.741888)
		(width 0.508)
		(layer "F.Cu")
		(net "GND")
	)
	(segment
		(start 41.377616 -34.516822)
		(end 40.384222 -34.516822)
		(width 0.3556)
		(layer "F.Cu")
		(net "GND")
	)
	(segment
		(start 20.025106 -34.584894)
		(end 18.415 -34.584894)
		(width 0.508)
		(layer "F.Cu")
		(net "GND")
	)
	(segment
		(start 38.67785 -207.8609)
		(end 37.8333 -207.8609)
		(width 0.508)
		(layer "F.Cu")
		(net "GND")
	)
	(segment
		(start 30.988 -374.2055)
		(end 30.988 -373.38)
		(width 0.508)
		(layer "F.Cu")
		(net "GND")
	)
	(segment
		(start 3.836162 -455.141838)
		(end 4.191 -454.787)
		(width 0.508)
		(layer "F.Cu")
		(net "GND")
	)
	(segment
		(start 229.67696 -343.674192)
		(end 230.503222 -343.674192)
		(width 0.508)
		(layer "F.Cu")
		(net "GND")
	)
	(segment
		(start 30.0355 -318.0207)
		(end 30.861 -318.0207)
		(width 0.508)
		(layer "F.Cu")
		(net "GND")
	)
	(segment
		(start 208.534 -93.7895)
		(end 209.38109 -92.94241)
		(width 0.508)
		(layer "F.Cu")
		(net "GND")
	)
	(segment
		(start 33.02 -374.2055)
		(end 33.02 -373.38)
		(width 0.508)
		(layer "F.Cu")
		(net "GND")
	)
	(segment
		(start 22.800056 -434.610002)
		(end 24.384 -434.610002)
		(width 0.508)
		(layer "F.Cu")
		(net "GND")
	)
	(segment
		(start 229.93096 -34.674302)
		(end 230.757222 -34.674302)
		(width 0.508)
		(layer "F.Cu")
		(net "GND")
	)
	(segment
		(start 20.025106 -435.155086)
		(end 18.415 -435.155086)
		(width 0.508)
		(layer "F.Cu")
		(net "GND")
	)
	(segment
		(start 71.247 -439.7375)
		(end 72.136 -439.7375)
		(width 0.508)
		(layer "F.Cu")
		(net "GND")
	)
	(segment
		(start 2.249932 -225.542094)
		(end 3.800094 -225.542094)
		(width 0.508)
		(layer "F.Cu")
		(net "GND")
	)
	(segment
		(start 2.249932 -293.942008)
		(end 3.842766 -293.942008)
		(width 0.508)
		(layer "F.Cu")
		(net "GND")
	)
	(segment
		(start 88.646 -102.35057)
		(end 89.55659 -102.35057)
		(width 0.3048)
		(layer "F.Cu")
		(net "GND")
	)
	(segment
		(start 20.025106 -137.584942)
		(end 18.415 -137.584942)
		(width 0.508)
		(layer "F.Cu")
		(net "GND")
	)
	(segment
		(start 93.345 -307.975)
		(end 93.98 -307.975)
		(width 0.3048)
		(layer "F.Cu")
		(net "GND")
	)
	(segment
		(start 3.81508 -341.942166)
		(end 4.191 -341.566246)
		(width 0.508)
		(layer "F.Cu")
		(net "GND")
	)
	(segment
		(start 99.949 -300.0375)
		(end 99.5045 -300.0375)
		(width 0.3048)
		(layer "F.Cu")
		(net "GND")
	)
	(segment
		(start 3.765042 -395.141958)
		(end 4.191 -394.716)
		(width 0.508)
		(layer "F.Cu")
		(net "GND")
	)
	(segment
		(start 2.249932 -197.54215)
		(end 4.191 -197.54215)
		(width 0.508)
		(layer "F.Cu")
		(net "GND")
	)
	(segment
		(start 25.4 -134.874)
		(end 26.416 -134.874)
		(width 0.508)
		(layer "F.Cu")
		(net "GND")
	)
	(segment
		(start 22.800056 -15.409926)
		(end 24.333454 -15.409926)
		(width 0.508)
		(layer "F.Cu")
		(net "GND")
	)
	(segment
		(start 226.974908 -364.605062)
		(end 228.585014 -364.605062)
		(width 0.508)
		(layer "F.Cu")
		(net "GND")
	)
	(segment
		(start 93.22943 -207.772)
		(end 92.97543 -208.026)
		(width 0.3048)
		(layer "F.Cu")
		(net "GND")
	)
	(segment
		(start 20.025106 -126.154942)
		(end 18.415 -126.154942)
		(width 0.508)
		(layer "F.Cu")
		(net "GND")
	)
	(segment
		(start 226.974908 -70.844918)
		(end 228.585014 -70.844918)
		(width 0.508)
		(layer "F.Cu")
		(net "GND")
	)
	(segment
		(start 3.81508 -323.542152)
		(end 4.191 -323.166232)
		(width 0.508)
		(layer "F.Cu")
		(net "GND")
	)
	(segment
		(start 22.800056 -437.010048)
		(end 24.384 -437.010048)
		(width 0.508)
		(layer "F.Cu")
		(net "GND")
	)
	(segment
		(start 100.6475 -212.344)
		(end 101.981 -212.344)
		(width 0.508)
		(layer "F.Cu")
		(net "GND")
	)
	(segment
		(start 20.025106 -141.394942)
		(end 18.415 -141.394942)
		(width 0.508)
		(layer "F.Cu")
		(net "GND")
	)
	(segment
		(start 3.84302 -309.94223)
		(end 4.191 -310.29021)
		(width 0.508)
		(layer "F.Cu")
		(net "GND")
	)
	(segment
		(start 39.200074 -282.189936)
		(end 37.61613 -282.189936)
		(width 0.508)
		(layer "F.Cu")
		(net "GND")
	)
	(segment
		(start 2.249932 -386.341874)
		(end 4.191 -386.341874)
		(width 0.508)
		(layer "F.Cu")
		(net "GND")
	)
	(segment
		(start 22.800056 -443.410086)
		(end 24.2316 -443.410086)
		(width 0.508)
		(layer "F.Cu")
		(net "GND")
	)
	(segment
		(start 20.025106 -124.884942)
		(end 18.415 -124.884942)
		(width 0.508)
		(layer "F.Cu")
		(net "GND")
	)
	(segment
		(start 94.488 -218.8845)
		(end 94.488 -219.71)
		(width 0.508)
		(layer "F.Cu")
		(net "GND")
	)
	(segment
		(start 2.249932 -345.142058)
		(end 3.81508 -345.142058)
		(width 0.508)
		(layer "F.Cu")
		(net "GND")
	)
	(segment
		(start 24.333454 -15.409926)
		(end 24.384 -15.460472)
		(width 0.508)
		(layer "F.Cu")
		(net "GND")
	)
	(segment
		(start 43.575986 -285.735014)
		(end 43.942 -285.369)
		(width 0.508)
		(layer "F.Cu")
		(net "GND")
	)
	(segment
		(start 3.842766 -342.742012)
		(end 4.191 -343.090246)
		(width 0.508)
		(layer "F.Cu")
		(net "GND")
	)
	(segment
		(start 87.80907 -212.4075)
		(end 88.646 -211.57057)
		(width 0.3048)
		(layer "F.Cu")
		(net "GND")
	)
	(segment
		(start 24.6761 -93.1164)
		(end 24.003 -93.7895)
		(width 0.508)
		(layer "F.Cu")
		(net "GND")
	)
	(segment
		(start 2.249932 -392.741912)
		(end 3.740912 -392.741912)
		(width 0.508)
		(layer "F.Cu")
		(net "GND")
	)
	(segment
		(start 25.4 -445.897)
		(end 25.4 -446.786)
		(width 0.508)
		(layer "F.Cu")
		(net "GND")
	)
	(segment
		(start 3.81508 -228.741986)
		(end 4.191 -228.366066)
		(width 0.508)
		(layer "F.Cu")
		(net "GND")
	)
	(segment
		(start 2.249932 -299.5422)
		(end 3.81508 -299.5422)
		(width 0.508)
		(layer "F.Cu")
		(net "GND")
	)
	(segment
		(start 224.199958 -270.99006)
		(end 222.616014 -270.99006)
		(width 0.508)
		(layer "F.Cu")
		(net "GND")
	)
	(segment
		(start 30.4165 -93.98635)
		(end 31.614364 -93.98635)
		(width 0.508)
		(layer "F.Cu")
		(net "GND")
	)
	(segment
		(start 22.800056 -336.410046)
		(end 24.384 -336.410046)
		(width 0.508)
		(layer "F.Cu")
		(net "GND")
	)
	(segment
		(start 99.5045 -90.3605)
		(end 99.5172 -90.3732)
		(width 0.508)
		(layer "F.Cu")
		(net "GND")
	)
	(segment
		(start 2.249932 -176.74209)
		(end 3.81508 -176.74209)
		(width 0.508)
		(layer "F.Cu")
		(net "GND")
	)
	(segment
		(start 22.800056 -125.609858)
		(end 24.384 -125.609858)
		(width 0.508)
		(layer "F.Cu")
		(net "GND")
	)
	(segment
		(start 99.2505 -310.3245)
		(end 99.949 -310.3245)
		(width 0.3048)
		(layer "F.Cu")
		(net "GND")
	)
	(segment
		(start 3.84302 -345.942158)
		(end 4.191 -346.290138)
		(width 0.508)
		(layer "F.Cu")
		(net "GND")
	)
	(segment
		(start 3.842766 -293.942008)
		(end 4.191 -294.290242)
		(width 0.508)
		(layer "F.Cu")
		(net "GND")
	)
	(segment
		(start 39.200074 -68.989956)
		(end 37.61613 -68.989956)
		(width 0.508)
		(layer "F.Cu")
		(net "GND")
	)
	(segment
		(start 34.57575 -143.1925)
		(end 33.6169 -143.1925)
		(width 0.508)
		(layer "F.Cu")
		(net "GND")
	)
	(segment
		(start 23.14575 -398.8435)
		(end 23.14575 -397.7386)
		(width 0.508)
		(layer "F.Cu")
		(net "GND")
	)
	(segment
		(start 224.199958 -480.990148)
		(end 222.616014 -480.990148)
		(width 0.508)
		(layer "F.Cu")
		(net "GND")
	)
	(segment
		(start 3.842766 -324.341998)
		(end 4.191 -324.690232)
		(width 0.508)
		(layer "F.Cu")
		(net "GND")
	)
	(segment
		(start 217.4494 -188.0235)
		(end 217.4494 -188.7982)
		(width 0.508)
		(layer "F.Cu")
		(net "GND")
	)
	(segment
		(start 25.4 -340.614)
		(end 26.416 -340.614)
		(width 0.508)
		(layer "F.Cu")
		(net "GND")
	)
	(segment
		(start 221.615 -269.113)
		(end 220.599 -269.113)
		(width 0.508)
		(layer "F.Cu")
		(net "GND")
	)
	(segment
		(start 36.576 -269.113)
		(end 35.56 -269.113)
		(width 0.508)
		(layer "F.Cu")
		(net "GND")
	)
	(segment
		(start 91.059 -22.4409)
		(end 91.059 -23.749)
		(width 0.3048)
		(layer "F.Cu")
		(net "GND")
	)
	(segment
		(start 88.646 -211.57057)
		(end 89.55659 -211.57057)
		(width 0.3048)
		(layer "F.Cu")
		(net "GND")
	)
	(segment
		(start 24.823674 -268.733524)
		(end 25.9588 -268.733524)
		(width 0.381)
		(layer "F.Cu")
		(net "GND")
	)
	(segment
		(start 2.249932 -215.942164)
		(end 3.81508 -215.942164)
		(width 0.508)
		(layer "F.Cu")
		(net "GND")
	)
	(segment
		(start 3.84302 -297.142154)
		(end 4.191 -297.490134)
		(width 0.508)
		(layer "F.Cu")
		(net "GND")
	)
	(segment
		(start 25.9588 -268.733524)
		(end 26.010362 -268.785086)
		(width 0.381)
		(layer "F.Cu")
		(net "GND")
	)
	(segment
		(start 37.8333 -207.8609)
		(end 37.7444 -207.9498)
		(width 0.508)
		(layer "F.Cu")
		(net "GND")
	)
	(segment
		(start 25.8445 -264.4267)
		(end 25.8445 -263.871202)
		(width 0.508)
		(layer "F.Cu")
		(net "GND")
	)
	(segment
		(start 2.249932 -283.542232)
		(end 3.81508 -283.542232)
		(width 0.508)
		(layer "F.Cu")
		(net "GND")
	)
	(segment
		(start 24.003 -299.7835)
		(end 24.003 -299.2882)
		(width 0.508)
		(layer "F.Cu")
		(net "GND")
	)
	(segment
		(start 88.011 -105.8545)
		(end 87.122 -105.8545)
		(width 0.508)
		(layer "F.Cu")
		(net "GND")
	)
	(segment
		(start 214.9475 -402.97735)
		(end 216.145364 -402.97735)
		(width 0.508)
		(layer "F.Cu")
		(net "GND")
	)
	(segment
		(start 24.383746 -140.80998)
		(end 24.384 -140.809726)
		(width 0.508)
		(layer "F.Cu")
		(net "GND")
	)
	(segment
		(start 226.974908 -285.735014)
		(end 228.614986 -285.735014)
		(width 0.508)
		(layer "F.Cu")
		(net "GND")
	)
	(segment
		(start 4.191 -424.162982)
		(end 3.97002 -423.942002)
		(width 0.508)
		(layer "F.Cu")
		(net "GND")
	)
	(segment
		(start 224.199958 -171.990004)
		(end 222.616014 -171.990004)
		(width 0.508)
		(layer "F.Cu")
		(net "GND")
	)
	(segment
		(start 3.84302 -327.542144)
		(end 4.191 -327.890124)
		(width 0.508)
		(layer "F.Cu")
		(net "GND")
	)
	(segment
		(start 2.249932 -452.741792)
		(end 3.796792 -452.741792)
		(width 0.508)
		(layer "F.Cu")
		(net "GND")
	)
	(segment
		(start 40.005 -140.4366)
		(end 40.005 -140.0048)
		(width 0.3556)
		(layer "F.Cu")
		(net "GND")
	)
	(segment
		(start 3.78206 -429.54194)
		(end 4.191 -429.133)
		(width 0.508)
		(layer "F.Cu")
		(net "GND")
	)
	(segment
		(start 22.800056 -13.00988)
		(end 24.13508 -13.00988)
		(width 0.508)
		(layer "F.Cu")
		(net "GND")
	)
	(segment
		(start 19.55165 -472.3511)
		(end 19.55165 -471.658696)
		(width 0.508)
		(layer "F.Cu")
		(net "GND")
	)
	(segment
		(start 37.33165 -206.8068)
		(end 36.5125 -205.98765)
		(width 0.508)
		(layer "F.Cu")
		(net "GND")
	)
	(segment
		(start 224.199958 -389.990076)
		(end 222.616014 -389.990076)
		(width 0.508)
		(layer "F.Cu")
		(net "GND")
	)
	(segment
		(start 3.81508 -173.542198)
		(end 4.191 -173.166278)
		(width 0.508)
		(layer "F.Cu")
		(net "GND")
	)
	(segment
		(start 89.55659 -308.43093)
		(end 88.88857 -308.43093)
		(width 0.3048)
		(layer "F.Cu")
		(net "GND")
	)
	(segment
		(start 22.800056 -123.210066)
		(end 24.384 -123.210066)
		(width 0.508)
		(layer "F.Cu")
		(net "GND")
	)
	(segment
		(start 229.67696 -446.67424)
		(end 230.503222 -446.67424)
		(width 0.508)
		(layer "F.Cu")
		(net "GND")
	)
	(segment
		(start 3.81508 -338.74202)
		(end 4.191 -338.3661)
		(width 0.508)
		(layer "F.Cu")
		(net "GND")
	)
	(segment
		(start 2.249932 -213.542118)
		(end 3.84302 -213.542118)
		(width 0.508)
		(layer "F.Cu")
		(net "GND")
	)
	(segment
		(start 2.249932 -171.142152)
		(end 3.84302 -171.142152)
		(width 0.508)
		(layer "F.Cu")
		(net "GND")
	)
	(segment
		(start 99.949 -310.007)
		(end 99.441 -309.499)
		(width 0.508)
		(layer "F.Cu")
		(net "GND")
	)
	(segment
		(start 22.800056 -344.41003)
		(end 24.384 -344.41003)
		(width 0.508)
		(layer "F.Cu")
		(net "GND")
	)
	(segment
		(start 98.3615 -223.774)
		(end 98.3615 -222.885)
		(width 0.508)
		(layer "F.Cu")
		(net "GND")
	)
	(segment
		(start 208.31175 -92.1385)
		(end 207.10525 -92.1385)
		(width 0.508)
		(layer "F.Cu")
		(net "GND")
	)
	(segment
		(start 98.530918 -436.477918)
		(end 98.530918 -435.55031)
		(width 0.3048)
		(layer "F.Cu")
		(net "GND")
	)
	(segment
		(start 39.200074 -380.390146)
		(end 37.61613 -380.390146)
		(width 0.508)
		(layer "F.Cu")
		(net "GND")
	)
	(segment
		(start 20.025106 -220.26499)
		(end 18.49501 -220.26499)
		(width 0.508)
		(layer "F.Cu")
		(net "GND")
	)
	(segment
		(start 2.249932 -161.542222)
		(end 3.84302 -161.542222)
		(width 0.508)
		(layer "F.Cu")
		(net "GND")
	)
	(segment
		(start 2.249932 -287.542224)
		(end 3.824224 -287.542224)
		(width 0.508)
		(layer "F.Cu")
		(net "GND")
	)
	(segment
		(start 106.934 -206.4385)
		(end 106.045 -206.4385)
		(width 0.508)
		(layer "F.Cu")
		(net "GND")
	)
	(segment
		(start 83.6295 -149.606)
		(end 84.455 -149.606)
		(width 0.508)
		(layer "F.Cu")
		(net "GND")
	)
	(segment
		(start 2.249932 -203.942188)
		(end 3.84302 -203.942188)
		(width 0.508)
		(layer "F.Cu")
		(net "GND")
	)
	(segment
		(start 87.122 -105.8545)
		(end 86.233 -105.8545)
		(width 0.508)
		(layer "F.Cu")
		(net "GND")
	)
	(segment
		(start 209.9945 -93.55582)
		(end 209.9945 -93.98635)
		(width 0.508)
		(layer "F.Cu")
		(net "GND")
	)
	(segment
		(start 4.191 -442.812424)
		(end 3.720592 -442.342016)
		(width 0.508)
		(layer "F.Cu")
		(net "GND")
	)
	(segment
		(start 2.249932 -333.142082)
		(end 4.169918 -333.142082)
		(width 0.508)
		(layer "F.Cu")
		(net "GND")
	)
	(segment
		(start 2.249932 -355.542088)
		(end 3.84302 -355.542088)
		(width 0.508)
		(layer "F.Cu")
		(net "GND")
	)
	(segment
		(start 224.199958 -156.789882)
		(end 222.616014 -156.789882)
		(width 0.508)
		(layer "F.Cu")
		(net "GND")
	)
	(segment
		(start 3.81508 -326.742044)
		(end 4.191 -326.366124)
		(width 0.508)
		(layer "F.Cu")
		(net "GND")
	)
	(segment
		(start 92.3925 -19.431)
		(end 92.3925 -18.6182)
		(width 0.508)
		(layer "F.Cu")
		(net "GND")
	)
	(segment
		(start 29.6164 -11.8872)
		(end 29.3878 -11.6586)
		(width 0.508)
		(layer "F.Cu")
		(net "GND")
	)
	(segment
		(start 37.973 -309.1815)
		(end 37.4015 -309.753)
		(width 0.508)
		(layer "F.Cu")
		(net "GND")
	)
	(segment
		(start 105.24617 -208.470754)
		(end 105.246424 -208.4705)
		(width 0.508)
		(layer "F.Cu")
		(net "GND")
	)
	(segment
		(start 22.800056 -132.009896)
		(end 24.384 -132.009896)
		(width 0.508)
		(layer "F.Cu")
		(net "GND")
	)
	(segment
		(start 224.199958 -62.589918)
		(end 222.616014 -62.589918)
		(width 0.508)
		(layer "F.Cu")
		(net "GND")
	)
	(segment
		(start 3.842766 -223.142048)
		(end 4.191 -223.490282)
		(width 0.508)
		(layer "F.Cu")
		(net "GND")
	)
	(segment
		(start 93.22943 -206.39659)
		(end 93.22943 -207.772)
		(width 0.3048)
		(layer "F.Cu")
		(net "GND")
	)
	(segment
		(start 99.5045 -293.116)
		(end 99.5045 -294.090598)
		(width 0.508)
		(layer "F.Cu")
		(net "GND")
	)
	(segment
		(start 224.199958 -492.990124)
		(end 222.616014 -492.990124)
		(width 0.508)
		(layer "F.Cu")
		(net "GND")
	)
	(segment
		(start 46.228 -241.9985)
		(end 46.228 -241.046)
		(width 0.508)
		(layer "F.Cu")
		(net "GND")
	)
	(segment
		(start 22.800056 -340.410038)
		(end 24.384 -340.410038)
		(width 0.508)
		(layer "F.Cu")
		(net "GND")
	)
	(segment
		(start 3.720592 -442.342016)
		(end 2.249932 -442.342016)
		(width 0.508)
		(layer "F.Cu")
		(net "GND")
	)
	(segment
		(start 244.729 -424.434)
		(end 244.729 -425.45)
		(width 0.508)
		(layer "F.Cu")
		(net "GND")
	)
	(segment
		(start 244.729 -421.894)
		(end 244.729 -420.878)
		(width 0.508)
		(layer "F.Cu")
		(net "GND")
	)
	(segment
		(start 50.546 -134.9375)
		(end 49.657 -134.9375)
		(width 0.508)
		(layer "F.Cu")
		(net "GND")
	)
	(segment
		(start 87.80907 -103.1875)
		(end 88.646 -102.35057)
		(width 0.3048)
		(layer "F.Cu")
		(net "GND")
	)
	(segment
		(start 87.122 -436.0545)
		(end 86.233 -436.0545)
		(width 0.508)
		(layer "F.Cu")
		(net "GND")
	)
	(segment
		(start 20.025106 -42.204894)
		(end 18.415 -42.204894)
		(width 0.508)
		(layer "F.Cu")
		(net "GND")
	)
	(segment
		(start 3.81508 -206.342234)
		(end 4.191 -205.966314)
		(width 0.508)
		(layer "F.Cu")
		(net "GND")
	)
	(segment
		(start 97.4725 -292.227)
		(end 97.4725 -293.116)
		(width 0.508)
		(layer "F.Cu")
		(net "GND")
	)
	(segment
		(start 39.200074 -485.789986)
		(end 37.61613 -485.789986)
		(width 0.508)
		(layer "F.Cu")
		(net "GND")
	)
	(segment
		(start 22.800056 -223.810068)
		(end 24.384 -223.810068)
		(width 0.508)
		(layer "F.Cu")
		(net "GND")
	)
	(segment
		(start 92.97543 -302.387)
		(end 92.71 -302.387)
		(width 0.3048)
		(layer "F.Cu")
		(net "GND")
	)
	(segment
		(start 24.638 -196.1134)
		(end 24.003 -196.7484)
		(width 0.508)
		(layer "F.Cu")
		(net "GND")
	)
	(segment
		(start 98.530918 -105.35031)
		(end 99.94519 -105.35031)
		(width 0.3048)
		(layer "F.Cu")
		(net "GND")
	)
	(segment
		(start 39.200074 -156.789882)
		(end 37.61613 -156.789882)
		(width 0.508)
		(layer "F.Cu")
		(net "GND")
	)
	(segment
		(start 41.975024 -70.844918)
		(end 43.58513 -70.844918)
		(width 0.508)
		(layer "F.Cu")
		(net "GND")
	)
	(segment
		(start 221.615 -166.116)
		(end 220.599 -166.116)
		(width 0.508)
		(layer "F.Cu")
		(net "GND")
	)
	(segment
		(start 256.474976 -425.729908)
		(end 252.755908 -425.729908)
		(width 0.8128)
		(layer "F.Cu")
		(net "GND")
	)
	(segment
		(start 22.800056 -231.009952)
		(end 24.384 -231.009952)
		(width 0.508)
		(layer "F.Cu")
		(net "GND")
	)
	(segment
		(start 226.974908 -59.414918)
		(end 228.585014 -59.414918)
		(width 0.508)
		(layer "F.Cu")
		(net "GND")
	)
	(segment
		(start 224.199958 -468.190072)
		(end 222.616014 -468.190072)
		(width 0.508)
		(layer "F.Cu")
		(net "GND")
	)
	(segment
		(start 2.249932 -352.342196)
		(end 3.84302 -352.342196)
		(width 0.508)
		(layer "F.Cu")
		(net "GND")
	)
	(segment
		(start 3.796792 -452.741792)
		(end 4.191 -453.136)
		(width 0.508)
		(layer "F.Cu")
		(net "GND")
	)
	(segment
		(start 224.199958 -169.589958)
		(end 222.616014 -169.589958)
		(width 0.508)
		(layer "F.Cu")
		(net "GND")
	)
	(segment
		(start 93.345 -213.614)
		(end 93.98 -213.614)
		(width 0.3048)
		(layer "F.Cu")
		(net "GND")
	)
	(segment
		(start 39.200074 -277.390098)
		(end 37.61613 -277.390098)
		(width 0.508)
		(layer "F.Cu")
		(net "GND")
	)
	(segment
		(start 226.974908 -55.604918)
		(end 228.585014 -55.604918)
		(width 0.508)
		(layer "F.Cu")
		(net "GND")
	)
	(segment
		(start 2.249932 -219.142056)
		(end 3.81508 -219.142056)
		(width 0.508)
		(layer "F.Cu")
		(net "GND")
	)
	(segment
		(start 252.704092 -413.537908)
		(end 252.704092 -414.299908)
		(width 0.8128)
		(layer "F.Cu")
		(net "GND")
	)
	(segment
		(start 30.4165 -196.98335)
		(end 31.741364 -196.98335)
		(width 0.508)
		(layer "F.Cu")
		(net "GND")
	)
	(segment
		(start 3.84302 -171.142152)
		(end 4.191 -171.490132)
		(width 0.508)
		(layer "F.Cu")
		(net "GND")
	)
	(segment
		(start 224.199958 -68.989956)
		(end 222.616014 -68.989956)
		(width 0.508)
		(layer "F.Cu")
		(net "GND")
	)
	(segment
		(start 27.813 -377.444)
		(end 28.393644 -378.024644)
		(width 0.3556)
		(layer "F.Cu")
		(net "GND")
	)
	(segment
		(start 11.71321 -497.13261)
		(end 11.15949 -497.13261)
		(width 0.508)
		(layer "F.Cu")
		(net "GND")
	)
	(segment
		(start 41.975024 -59.414918)
		(end 43.58513 -59.414918)
		(width 0.508)
		(layer "F.Cu")
		(net "GND")
	)
	(segment
		(start 23.32355 -92.1385)
		(end 24.044402 -92.1385)
		(width 0.508)
		(layer "F.Cu")
		(net "GND")
	)
	(segment
		(start 41.975024 -158.604966)
		(end 43.58513 -158.604966)
		(width 0.508)
		(layer "F.Cu")
		(net "GND")
	)
	(segment
		(start 19.55165 -472.3511)
		(end 19.55165 -473.456)
		(width 0.508)
		(layer "F.Cu")
		(net "GND")
	)
	(segment
		(start 36.576 -474.98)
		(end 35.56 -474.98)
		(width 0.508)
		(layer "F.Cu")
		(net "GND")
	)
	(segment
		(start 41.975024 -360.795062)
		(end 43.58513 -360.795062)
		(width 0.508)
		(layer "F.Cu")
		(net "GND")
	)
	(segment
		(start 98.40341 -432.05019)
		(end 100.44811 -432.05019)
		(width 0.3048)
		(layer "F.Cu")
		(net "GND")
	)
	(segment
		(start 224.199958 -64.989964)
		(end 222.616014 -64.989964)
		(width 0.508)
		(layer "F.Cu")
		(net "GND")
	)
	(segment
		(start 226.974908 -491.73511)
		(end 228.60889 -491.73511)
		(width 0.508)
		(layer "F.Cu")
		(net "GND")
	)
	(segment
		(start 226.974908 -388.735062)
		(end 228.611938 -388.735062)
		(width 0.508)
		(layer "F.Cu")
		(net "GND")
	)
	(segment
		(start 99.5045 -205.5495)
		(end 98.530918 -206.523082)
		(width 0.3048)
		(layer "F.Cu")
		(net "GND")
	)
	(segment
		(start 2.249932 -296.342054)
		(end 3.81508 -296.342054)
		(width 0.508)
		(layer "F.Cu")
		(net "GND")
	)
	(segment
		(start 20.025106 -343.585038)
		(end 18.415 -343.585038)
		(width 0.508)
		(layer "F.Cu")
		(net "GND")
	)
	(segment
		(start 2.249932 -160.742122)
		(end 3.81508 -160.742122)
		(width 0.508)
		(layer "F.Cu")
		(net "GND")
	)
	(segment
		(start 39.200074 -373.990108)
		(end 37.61613 -373.990108)
		(width 0.508)
		(layer "F.Cu")
		(net "GND")
	)
	(segment
		(start 221.71025 -343.087452)
		(end 221.71025 -342.007952)
		(width 0.508)
		(layer "F.Cu")
		(net "GND")
	)
	(segment
		(start 93.22943 -98.552)
		(end 92.97543 -98.806)
		(width 0.3048)
		(layer "F.Cu")
		(net "GND")
	)
	(segment
		(start 3.765804 -395.941804)
		(end 4.191 -396.367)
		(width 0.508)
		(layer "F.Cu")
		(net "GND")
	)
	(segment
		(start 224.199958 -71.390002)
		(end 222.616014 -71.390002)
		(width 0.508)
		(layer "F.Cu")
		(net "GND")
	)
	(segment
		(start 100.4824 -102.0191)
		(end 101.9429 -102.0191)
		(width 0.508)
		(layer "F.Cu")
		(net "GND")
	)
	(segment
		(start 3.81508 -354.741988)
		(end 4.191 -354.366068)
		(width 0.508)
		(layer "F.Cu")
		(net "GND")
	)
	(segment
		(start 96.3295 -316.428882)
		(end 96.329246 -316.428628)
		(width 0.508)
		(layer "F.Cu")
		(net "GND")
	)
	(segment
		(start 217.297 -394.0175)
		(end 217.297 -394.7922)
		(width 0.508)
		(layer "F.Cu")
		(net "GND")
	)
	(segment
		(start 25.4 -31.75)
		(end 26.416 -31.75)
		(width 0.508)
		(layer "F.Cu")
		(net "GND")
	)
	(segment
		(start 37.2872 -309.753)
		(end 37.2618 -309.7784)
		(width 0.508)
		(layer "F.Cu")
		(net "GND")
	)
	(segment
		(start 22.800056 -40.209978)
		(end 24.384 -40.209978)
		(width 0.508)
		(layer "F.Cu")
		(net "GND")
	)
	(segment
		(start 96.3295 -317.246)
		(end 96.3295 -316.428882)
		(width 0.508)
		(layer "F.Cu")
		(net "GND")
	)
	(segment
		(start 38.65245 -104.8385)
		(end 38.67785 -104.8639)
		(width 0.508)
		(layer "F.Cu")
		(net "GND")
	)
	(segment
		(start 2.249932 -302.742092)
		(end 3.81508 -302.742092)
		(width 0.508)
		(layer "F.Cu")
		(net "GND")
	)
	(segment
		(start 224.199958 -387.59003)
		(end 222.616014 -387.59003)
		(width 0.508)
		(layer "F.Cu")
		(net "GND")
	)
	(segment
		(start 3.824224 -287.542224)
		(end 4.191 -287.909)
		(width 0.508)
		(layer "F.Cu")
		(net "GND")
	)
	(segment
		(start 3.842766 -300.342046)
		(end 4.191 -300.69028)
		(width 0.508)
		(layer "F.Cu")
		(net "GND")
	)
	(segment
		(start 49.3395 -8.42518)
		(end 49.95291 -9.03859)
		(width 0.508)
		(layer "F.Cu")
		(net "GND")
	)
	(segment
		(start 38.38575 -348.43339)
		(end 38.38575 -349.658432)
		(width 0.508)
		(layer "F.Cu")
		(net "GND")
	)
	(segment
		(start 31.0896 -291.0967)
		(end 31.0896 -291.8968)
		(width 0.508)
		(layer "F.Cu")
		(net "GND")
	)
	(segment
		(start 226.974908 -467.60511)
		(end 228.585014 -467.60511)
		(width 0.508)
		(layer "F.Cu")
		(net "GND")
	)
	(segment
		(start 224.199958 -60.189872)
		(end 222.616014 -60.189872)
		(width 0.508)
		(layer "F.Cu")
		(net "GND")
	)
	(segment
		(start 93.22943 -106.02341)
		(end 93.22943 -104.50957)
		(width 0.3048)
		(layer "F.Cu")
		(net "GND")
	)
	(segment
		(start 89.3445 -113.255044)
		(end 89.3445 -113.665)
		(width 0.508)
		(layer "F.Cu")
		(net "GND")
	)
	(segment
		(start 39.200074 -490.590078)
		(end 37.61613 -490.590078)
		(width 0.508)
		(layer "F.Cu")
		(net "GND")
	)
	(segment
		(start 2.249932 -336.342228)
		(end 3.84302 -336.342228)
		(width 0.508)
		(layer "F.Cu")
		(net "GND")
	)
	(segment
		(start 224.199958 -380.390146)
		(end 222.616014 -380.390146)
		(width 0.508)
		(layer "F.Cu")
		(net "GND")
	)
	(segment
		(start 3.969766 -416.741864)
		(end 2.249932 -416.741864)
		(width 0.508)
		(layer "F.Cu")
		(net "GND")
	)
	(segment
		(start 68.50126 -378.498608)
		(end 72.857868 -378.498608)
		(width 0.508)
		(layer "F.Cu")
		(net "GND")
	)
	(segment
		(start 2.249932 -438.342024)
		(end 3.744976 -438.342024)
		(width 0.508)
		(layer "F.Cu")
		(net "GND")
	)
	(segment
		(start 106.934 -435.2925)
		(end 106.045 -435.2925)
		(width 0.508)
		(layer "F.Cu")
		(net "GND")
	)
	(segment
		(start 39.200074 -58.589926)
		(end 37.61613 -58.589926)
		(width 0.508)
		(layer "F.Cu")
		(net "GND")
	)
	(segment
		(start 73.025 -455.1045)
		(end 73.025 -455.93)
		(width 0.508)
		(layer "F.Cu")
		(net "GND")
	)
	(segment
		(start 20.025106 -450.395086)
		(end 18.415 -450.395086)
		(width 0.508)
		(layer "F.Cu")
		(net "GND")
	)
	(segment
		(start 3.852926 -411.141926)
		(end 4.191 -411.48)
		(width 0.508)
		(layer "F.Cu")
		(net "GND")
	)
	(segment
		(start 22.800056 -27.409902)
		(end 24.384 -27.409902)
		(width 0.508)
		(layer "F.Cu")
		(net "GND")
	)
	(segment
		(start 77.343 -208.9277)
		(end 76.5302 -208.9277)
		(width 0.508)
		(layer "F.Cu")
		(net "GND")
	)
	(segment
		(start 229.67696 -137.67435)
		(end 230.503222 -137.67435)
		(width 0.508)
		(layer "F.Cu")
		(net "GND")
	)
	(segment
		(start 196.847206 -497.975128)
		(end 196.847206 -496.749832)
		(width 0.508)
		(layer "F.Cu")
		(net "GND")
	)
	(segment
		(start 98.40341 -211.07019)
		(end 99.18319 -211.07019)
		(width 0.3048)
		(layer "F.Cu")
		(net "GND")
	)
	(segment
		(start 2.249932 -212.742018)
		(end 3.81508 -212.742018)
		(width 0.508)
		(layer "F.Cu")
		(net "GND")
	)
	(segment
		(start 41.975024 -265.415014)
		(end 43.58513 -265.415014)
		(width 0.508)
		(layer "F.Cu")
		(net "GND")
	)
	(segment
		(start 37.4015 -309.753)
		(end 37.2872 -309.753)
		(width 0.508)
		(layer "F.Cu")
		(net "GND")
	)
	(segment
		(start 39.200074 -76.18984)
		(end 37.61613 -76.18984)
		(width 0.508)
		(layer "F.Cu")
		(net "GND")
	)
	(segment
		(start 22.800056 -31.409894)
		(end 24.384 -31.409894)
		(width 0.508)
		(layer "F.Cu")
		(net "GND")
	)
	(segment
		(start 23.5077 -469.1761)
		(end 23.7744 -469.4428)
		(width 0.381)
		(layer "F.Cu")
		(net "GND")
	)
	(segment
		(start 90.4875 -420.55034)
		(end 90.484452 -420.553388)
		(width 0.508)
		(layer "F.Cu")
		(net "GND")
	)
	(segment
		(start 18.884646 -347.395038)
		(end 18.36039 -346.870782)
		(width 0.508)
		(layer "F.Cu")
		(net "GND")
	)
	(segment
		(start 93.22943 -434.70957)
		(end 93.345 -434.594)
		(width 0.3048)
		(layer "F.Cu")
		(net "GND")
	)
	(segment
		(start 22.3266 -298.0182)
		(end 22.5425 -298.2341)
		(width 0.508)
		(layer "F.Cu")
		(net "GND")
	)
	(segment
		(start 39.200074 -62.589918)
		(end 37.61613 -62.589918)
		(width 0.508)
		(layer "F.Cu")
		(net "GND")
	)
	(segment
		(start 29.3878 -11.6586)
		(end 29.3878 -11.0617)
		(width 0.508)
		(layer "F.Cu")
		(net "GND")
	)
	(segment
		(start 39.200074 -369.190016)
		(end 37.61613 -369.190016)
		(width 0.508)
		(layer "F.Cu")
		(net "GND")
	)
	(segment
		(start 88.011 -214.9475)
		(end 88.88857 -214.06993)
		(width 0.3048)
		(layer "F.Cu")
		(net "GND")
	)
	(segment
		(start 3.81508 -320.342006)
		(end 4.191 -319.966086)
		(width 0.508)
		(layer "F.Cu")
		(net "GND")
	)
	(segment
		(start 3.84302 -213.542118)
		(end 4.191 -213.890098)
		(width 0.508)
		(layer "F.Cu")
		(net "GND")
	)
	(segment
		(start 22.800056 -334.01)
		(end 24.384 -334.01)
		(width 0.508)
		(layer "F.Cu")
		(net "GND")
	)
	(segment
		(start 22.770592 -401.542758)
		(end 22.76475 -401.5486)
		(width 0.508)
		(layer "F.Cu")
		(net "GND")
	)
	(segment
		(start 99.5045 -204.851)
		(end 100.33 -204.851)
		(width 0.508)
		(layer "F.Cu")
		(net "GND")
	)
	(segment
		(start 224.199958 -78.589886)
		(end 222.616014 -78.589886)
		(width 0.508)
		(layer "F.Cu")
		(net "GND")
	)
	(segment
		(start 22.800056 -35.409886)
		(end 24.384 -35.409886)
		(width 0.508)
		(layer "F.Cu")
		(net "GND")
	)
	(segment
		(start 21.144992 -268.322044)
		(end 21.144992 -269.147544)
		(width 0.508)
		(layer "F.Cu")
		(net "GND")
	)
	(segment
		(start 22.800056 -233.409998)
		(end 24.384 -233.409998)
		(width 0.508)
		(layer "F.Cu")
		(net "GND")
	)
	(segment
		(start 2.249932 -222.342202)
		(end 3.81508 -222.342202)
		(width 0.508)
		(layer "F.Cu")
		(net "GND")
	)
	(segment
		(start 224.199958 -279.78989)
		(end 222.616014 -279.78989)
		(width 0.508)
		(layer "F.Cu")
		(net "GND")
	)
	(segment
		(start 3.81508 -219.142056)
		(end 4.191 -218.766136)
		(width 0.508)
		(layer "F.Cu")
		(net "GND")
	)
	(segment
		(start 3.81508 -215.942164)
		(end 4.191 -215.566244)
		(width 0.508)
		(layer "F.Cu")
		(net "GND")
	)
	(segment
		(start 96.3295 -113.665)
		(end 96.3295 -114.554)
		(width 0.508)
		(layer "F.Cu")
		(net "GND")
	)
	(segment
		(start 39.200074 -264.590022)
		(end 37.61613 -264.590022)
		(width 0.508)
		(layer "F.Cu")
		(net "GND")
	)
	(segment
		(start 20.025106 -145.204942)
		(end 18.415 -145.204942)
		(width 0.508)
		(layer "F.Cu")
		(net "GND")
	)
	(segment
		(start 18.498058 -117.264942)
		(end 18.034 -117.729)
		(width 0.508)
		(layer "F.Cu")
		(net "GND")
	)
	(segment
		(start 83.6676 -148.1836)
		(end 83.7184 -148.1328)
		(width 0.508)
		(layer "F.Cu")
		(net "GND")
	)
	(segment
		(start 2.249932 -306.742084)
		(end 3.84302 -306.742084)
		(width 0.508)
		(layer "F.Cu")
		(net "GND")
	)
	(segment
		(start 88.646 -432.55057)
		(end 87.80907 -433.3875)
		(width 0.3048)
		(layer "F.Cu")
		(net "GND")
	)
	(segment
		(start 225.40976 -446.26276)
		(end 226.3775 -446.26276)
		(width 0.381)
		(layer "F.Cu")
		(net "GND")
	)
	(segment
		(start 22.800056 -346.810076)
		(end 24.383746 -346.810076)
		(width 0.508)
		(layer "F.Cu")
		(net "GND")
	)
	(segment
		(start 230.251 -439.6105)
		(end 230.251 -440.4614)
		(width 0.508)
		(layer "F.Cu")
		(net "GND")
	)
	(segment
		(start 41.975024 -278.115014)
		(end 43.58513 -278.115014)
		(width 0.508)
		(layer "F.Cu")
		(net "GND")
	)
	(segment
		(start 252.704092 -414.934908)
		(end 252.095 -415.544)
		(width 0.8128)
		(layer "F.Cu")
		(net "GND")
	)
	(segment
		(start 2.249932 -321.142106)
		(end 3.84302 -321.142106)
		(width 0.508)
		(layer "F.Cu")
		(net "GND")
	)
	(segment
		(start 39.200074 -181.589934)
		(end 37.61613 -181.589934)
		(width 0.508)
		(layer "F.Cu")
		(net "GND")
	)
	(segment
		(start 20.025106 -23.154894)
		(end 18.415 -23.154894)
		(width 0.508)
		(layer "F.Cu")
		(net "GND")
	)
	(segment
		(start 2.249932 -186.34202)
		(end 3.90398 -186.34202)
		(width 0.508)
		(layer "F.Cu")
		(net "GND")
	)
	(segment
		(start 25.4 -237.744)
		(end 26.416 -237.744)
		(width 0.508)
		(layer "F.Cu")
		(net "GND")
	)
	(segment
		(start 224.199958 -56.18988)
		(end 222.616014 -56.18988)
		(width 0.508)
		(layer "F.Cu")
		(net "GND")
	)
	(segment
		(start 224.199958 -183.98998)
		(end 222.616014 -183.98998)
		(width 0.508)
		(layer "F.Cu")
		(net "GND")
	)
	(segment
		(start 10.4394 -408.7114)
		(end 10.4394 -410.2481)
		(width 1.016)
		(layer "F.Cu")
		(net "GND")
	)
	(segment
		(start 3.74015 -398.34185)
		(end 4.191 -397.891)
		(width 0.508)
		(layer "F.Cu")
		(net "GND")
	)
	(segment
		(start 24.15794 -33.80994)
		(end 24.384 -34.036)
		(width 0.508)
		(layer "F.Cu")
		(net "GND")
	)
	(segment
		(start 3.81508 -212.742018)
		(end 4.191 -212.366098)
		(width 0.508)
		(layer "F.Cu")
		(net "GND")
	)
	(segment
		(start 41.975024 -79.734918)
		(end 43.582082 -79.734918)
		(width 0.508)
		(layer "F.Cu")
		(net "GND")
	)
	(segment
		(start 69.38264 -450.7484)
		(end 68.2752 -450.7484)
		(width 0.3556)
		(layer "F.Cu")
		(net "GND")
	)
	(segment
		(start 77.5208 -306.07)
		(end 77.5208 -306.9082)
		(width 0.508)
		(layer "F.Cu")
		(net "GND")
	)
	(segment
		(start 22.371304 -400.284696)
		(end 22.770592 -400.683984)
		(width 0.508)
		(layer "F.Cu")
		(net "GND")
	)
	(segment
		(start 3.84302 -281.142186)
		(end 4.191 -281.490166)
		(width 0.508)
		(layer "F.Cu")
		(net "GND")
	)
	(segment
		(start 45.503338 -35.029902)
		(end 44.677076 -35.029902)
		(width 0.508)
		(layer "F.Cu")
		(net "GND")
	)
	(segment
		(start 226.314 -436.88)
		(end 226.699064 -436.494936)
		(width 0.3048)
		(layer "F.Cu")
		(net "GND")
	)
	(segment
		(start 87.3125 -443.865)
		(end 87.3125 -443.033912)
		(width 0.508)
		(layer "F.Cu")
		(net "GND")
	)
	(segment
		(start 224.199958 -159.189928)
		(end 222.616014 -159.189928)
		(width 0.508)
		(layer "F.Cu")
		(net "GND")
	)
	(segment
		(start 8.053578 -274.647914)
		(end 8.053578 -275.844)
		(width 0.508)
		(layer "F.Cu")
		(net "GND")
	)
	(segment
		(start 98.350832 -318.061848)
		(end 98.350832 -317.256668)
		(width 0.508)
		(layer "F.Cu")
		(net "GND")
	)
	(segment
		(start 3.81508 -309.14213)
		(end 4.191 -308.76621)
		(width 0.508)
		(layer "F.Cu")
		(net "GND")
	)
	(segment
		(start 87.80907 -433.3875)
		(end 87.503 -433.3875)
		(width 0.3048)
		(layer "F.Cu")
		(net "GND")
	)
	(segment
		(start 99.5045 -294.090598)
		(end 99.50831 -294.094408)
		(width 0.508)
		(layer "F.Cu")
		(net "GND")
	)
	(segment
		(start 39.200074 -274.990052)
		(end 37.61613 -274.990052)
		(width 0.508)
		(layer "F.Cu")
		(net "GND")
	)
	(segment
		(start 39.200074 -375.590054)
		(end 37.61613 -375.590054)
		(width 0.508)
		(layer "F.Cu")
		(net "GND")
	)
	(segment
		(start 93.599 -218.8845)
		(end 93.599 -219.71)
		(width 0.508)
		(layer "F.Cu")
		(net "GND")
	)
	(segment
		(start 3.740912 -392.741912)
		(end 4.191 -393.192)
		(width 0.508)
		(layer "F.Cu")
		(net "GND")
	)
	(segment
		(start 209.9945 -402.54682)
		(end 209.9945 -402.97735)
		(width 0.508)
		(layer "F.Cu")
		(net "GND")
	)
	(segment
		(start 226.974908 -484.11511)
		(end 228.585014 -484.11511)
		(width 0.508)
		(layer "F.Cu")
		(net "GND")
	)
	(segment
		(start 98.7425 -425.831)
		(end 98.7425 -426.635418)
		(width 0.3048)
		(layer "F.Cu")
		(net "GND")
	)
	(segment
		(start 195.386706 -496.767104)
		(end 195.386706 -497.778278)
		(width 0.508)
		(layer "F.Cu")
		(net "GND")
	)
	(segment
		(start 2.249932 -444.741808)
		(end 3.695192 -444.741808)
		(width 0.508)
		(layer "F.Cu")
		(net "GND")
	)
	(segment
		(start 2.249932 -395.941804)
		(end 3.765804 -395.941804)
		(width 0.508)
		(layer "F.Cu")
		(net "GND")
	)
	(segment
		(start 224.199958 -174.39005)
		(end 222.616014 -174.39005)
		(width 0.508)
		(layer "F.Cu")
		(net "GND")
	)
	(segment
		(start 70.2945 -357.505)
		(end 69.469 -357.505)
		(width 0.508)
		(layer "F.Cu")
		(net "GND")
	)
	(segment
		(start 38.75405 -310.8579)
		(end 39.96055 -310.8579)
		(width 0.508)
		(layer "F.Cu")
		(net "GND")
	)
	(segment
		(start 39.200074 -476.990156)
		(end 37.61613 -476.990156)
		(width 0.508)
		(layer "F.Cu")
		(net "GND")
	)
	(segment
		(start 2.249932 -223.142048)
		(end 3.842766 -223.142048)
		(width 0.508)
		(layer "F.Cu")
		(net "GND")
	)
	(segment
		(start 98.530918 -308.93131)
		(end 98.530918 -309.604918)
		(width 0.3048)
		(layer "F.Cu")
		(net "GND")
	)
	(segment
		(start 224.199958 -375.590054)
		(end 222.616014 -375.590054)
		(width 0.508)
		(layer "F.Cu")
		(net "GND")
	)
	(segment
		(start 22.800056 -118.409974)
		(end 24.384 -118.409974)
		(width 0.508)
		(layer "F.Cu")
		(net "GND")
	)
	(segment
		(start 94.869 -25.7175)
		(end 94.869 -24.892)
		(width 0.508)
		(layer "F.Cu")
		(net "GND")
	)
	(segment
		(start 37.36975 -39.6875)
		(end 37.36975 -40.767)
		(width 0.508)
		(layer "F.Cu")
		(net "GND")
	)
	(segment
		(start 2.249932 -200.742042)
		(end 3.842766 -200.742042)
		(width 0.508)
		(layer "F.Cu")
		(net "GND")
	)
	(segment
		(start 39.200074 -60.189872)
		(end 37.61613 -60.189872)
		(width 0.508)
		(layer "F.Cu")
		(net "GND")
	)
	(segment
		(start 3.802888 -404.741888)
		(end 4.191 -405.13)
		(width 0.508)
		(layer "F.Cu")
		(net "GND")
	)
	(segment
		(start 3.800094 -225.542094)
		(end 4.191 -225.933)
		(width 0.508)
		(layer "F.Cu")
		(net "GND")
	)
	(segment
		(start 41.975024 -51.794918)
		(end 43.58513 -51.794918)
		(width 0.508)
		(layer "F.Cu")
		(net "GND")
	)
	(segment
		(start 2.249932 -210.342226)
		(end 3.84302 -210.342226)
		(width 0.508)
		(layer "F.Cu")
		(net "GND")
	)
	(segment
		(start 253.212092 -413.029908)
		(end 252.704092 -413.537908)
		(width 0.8128)
		(layer "F.Cu")
		(net "GND")
	)
	(segment
		(start 3.807206 -426.341794)
		(end 4.191 -425.958)
		(width 0.508)
		(layer "F.Cu")
		(net "GND")
	)
	(segment
		(start 100.42271 -305.43119)
		(end 100.4824 -305.3715)
		(width 0.3048)
		(layer "F.Cu")
		(net "GND")
	)
	(segment
		(start 36.5125 -411.98165)
		(end 36.5125 -412.8135)
		(width 0.508)
		(layer "F.Cu")
		(net "GND")
	)
	(segment
		(start 224.199958 -362.789978)
		(end 222.616014 -362.789978)
		(width 0.508)
		(layer "F.Cu")
		(net "GND")
	)
	(segment
		(start 3.81508 -302.742092)
		(end 4.191 -302.366172)
		(width 0.508)
		(layer "F.Cu")
		(net "GND")
	)
	(segment
		(start 224.9805 -431.292)
		(end 224.9805 -432.181)
		(width 0.508)
		(layer "F.Cu")
		(net "GND")
	)
	(segment
		(start 3.84302 -161.542222)
		(end 4.191 -161.890202)
		(width 0.508)
		(layer "F.Cu")
		(net "GND")
	)
	(segment
		(start 3.89763 -435.941978)
		(end 2.249932 -435.941978)
		(width 0.508)
		(layer "F.Cu")
		(net "GND")
	)
	(segment
		(start 19.55165 -471.658696)
		(end 19.465798 -471.572844)
		(width 0.508)
		(layer "F.Cu")
		(net "GND")
	)
	(segment
		(start 99.94519 -105.35031)
		(end 99.949 -105.3465)
		(width 0.3048)
		(layer "F.Cu")
		(net "GND")
	)
	(segment
		(start 2.249932 -290.742116)
		(end 3.84302 -290.742116)
		(width 0.508)
		(layer "F.Cu")
		(net "GND")
	)
	(segment
		(start 19.465798 -471.572844)
		(end 19.465798 -470.984072)
		(width 0.508)
		(layer "F.Cu")
		(net "GND")
	)
	(segment
		(start 39.200074 -266.189968)
		(end 37.61613 -266.189968)
		(width 0.508)
		(layer "F.Cu")
		(net "GND")
	)
	(segment
		(start 2.249932 -312.342022)
		(end 3.887978 -312.342022)
		(width 0.508)
		(layer "F.Cu")
		(net "GND")
	)
	(segment
		(start 43.582082 -79.734918)
		(end 43.942 -79.375)
		(width 0.508)
		(layer "F.Cu")
		(net "GND")
	)
	(segment
		(start 224.199958 -58.589926)
		(end 222.616014 -58.589926)
		(width 0.508)
		(layer "F.Cu")
		(net "GND")
	)
	(segment
		(start 224.199958 -465.790026)
		(end 222.616014 -465.790026)
		(width 0.508)
		(layer "F.Cu")
		(net "GND")
	)
	(segment
		(start 82.4865 -308.483)
		(end 81.661 -308.483)
		(width 0.508)
		(layer "F.Cu")
		(net "GND")
	)
	(segment
		(start 102.108 -432.054)
		(end 102.0445 -431.9905)
		(width 0.508)
		(layer "F.Cu")
		(net "GND")
	)
	(segment
		(start 3.81508 -293.142162)
		(end 4.191 -292.766242)
		(width 0.508)
		(layer "F.Cu")
		(net "GND")
	)
	(segment
		(start 15.65275 -496.3795)
		(end 14.44625 -496.3795)
		(width 0.508)
		(layer "F.Cu")
		(net "GND")
	)
	(segment
		(start 226.974908 -182.734966)
		(end 228.618034 -182.734966)
		(width 0.508)
		(layer "F.Cu")
		(net "GND")
	)
	(segment
		(start 102.0445 -431.9905)
		(end 100.5078 -431.9905)
		(width 0.508)
		(layer "F.Cu")
		(net "GND")
	)
	(segment
		(start 229.67696 -240.674398)
		(end 230.503222 -240.674398)
		(width 0.508)
		(layer "F.Cu")
		(net "GND")
	)
	(segment
		(start 39.200074 -371.590062)
		(end 37.61613 -371.590062)
		(width 0.508)
		(layer "F.Cu")
		(net "GND")
	)
	(segment
		(start 39.63924 -141.4145)
		(end 39.63924 -140.80236)
		(width 0.3556)
		(layer "F.Cu")
		(net "GND")
	)
	(segment
		(start 30.8864 -13.0429)
		(end 30.8864 -13.8938)
		(width 0.508)
		(layer "F.Cu")
		(net "GND")
	)
	(segment
		(start 39.200074 -73.789794)
		(end 37.61613 -73.789794)
		(width 0.508)
		(layer "F.Cu")
		(net "GND")
	)
	(segment
		(start 20.025106 -227.88499)
		(end 18.415 -227.88499)
		(width 0.508)
		(layer "F.Cu")
		(net "GND")
	)
	(segment
		(start 77.4954 -102.6287)
		(end 77.4954 -103.5558)
		(width 0.508)
		(layer "F.Cu")
		(net "GND")
	)
	(segment
		(start 3.81508 -203.142088)
		(end 4.191 -202.766168)
		(width 0.508)
		(layer "F.Cu")
		(net "GND")
	)
	(segment
		(start 93.22943 -97.17659)
		(end 93.22943 -98.552)
		(width 0.3048)
		(layer "F.Cu")
		(net "GND")
	)
	(segment
		(start 98.9965 -437.769)
		(end 98.9965 -436.9435)
		(width 0.3048)
		(layer "F.Cu")
		(net "GND")
	)
	(segment
		(start 40.384222 -34.516822)
		(end 40.2082 -34.3408)
		(width 0.3556)
		(layer "F.Cu")
		(net "GND")
	)
	(segment
		(start 2.249932 -351.542096)
		(end 3.81508 -351.542096)
		(width 0.508)
		(layer "F.Cu")
		(net "GND")
	)
	(segment
		(start 224.199958 -472.190064)
		(end 222.616014 -472.190064)
		(width 0.508)
		(layer "F.Cu")
		(net "GND")
	)
	(segment
		(start 3.81508 -183.142128)
		(end 4.191 -182.766208)
		(width 0.508)
		(layer "F.Cu")
		(net "GND")
	)
	(segment
		(start 226.3775 -343.262712)
		(end 226.3775 -342.519)
		(width 0.381)
		(layer "F.Cu")
		(net "GND")
	)
	(segment
		(start 39.0398 -413.87395)
		(end 39.0398 -414.9344)
		(width 0.508)
		(layer "F.Cu")
		(net "GND")
	)
	(segment
		(start 3.81508 -280.342086)
		(end 4.191 -279.966166)
		(width 0.508)
		(layer "F.Cu")
		(net "GND")
	)
	(segment
		(start 24.160988 -136.809988)
		(end 24.384 -137.033)
		(width 0.508)
		(layer "F.Cu")
		(net "GND")
	)
	(segment
		(start 51.02225 -9.8425)
		(end 52.22875 -9.8425)
		(width 0.508)
		(layer "F.Cu")
		(net "GND")
	)
	(segment
		(start 41.975024 -154.794966)
		(end 43.58513 -154.794966)
		(width 0.508)
		(layer "F.Cu")
		(net "GND")
	)
	(segment
		(start 231.267 -435.229)
		(end 230.124 -435.229)
		(width 0.508)
		(layer "F.Cu")
		(net "GND")
	)
	(segment
		(start 2.249932 -388.74192)
		(end 3.81508 -388.74192)
		(width 0.508)
		(layer "F.Cu")
		(net "GND")
	)
	(segment
		(start 99.949 -310.3245)
		(end 99.949 -310.007)
		(width 0.508)
		(layer "F.Cu")
		(net "GND")
	)
	(segment
		(start 2.249932 -179.941982)
		(end 3.81508 -179.941982)
		(width 0.508)
		(layer "F.Cu")
		(net "GND")
	)
	(segment
		(start 39.200074 -478.590102)
		(end 37.61613 -478.590102)
		(width 0.508)
		(layer "F.Cu")
		(net "GND")
	)
	(segment
		(start 88.4555 -418.846)
		(end 88.4555 -419.735)
		(width 0.508)
		(layer "F.Cu")
		(net "GND")
	)
	(segment
		(start 208.534 -299.7835)
		(end 209.38109 -298.93641)
		(width 0.508)
		(layer "F.Cu")
		(net "GND")
	)
	(segment
		(start 93.22943 -104.50957)
		(end 93.345 -104.394)
		(width 0.3048)
		(layer "F.Cu")
		(net "GND")
	)
	(segment
		(start 98.017584 -112.84331)
		(end 98.3615 -113.187226)
		(width 0.508)
		(layer "F.Cu")
		(net "GND")
	)
	(segment
		(start 2.249932 -327.542144)
		(end 3.84302 -327.542144)
		(width 0.508)
		(layer "F.Cu")
		(net "GND")
	)
	(segment
		(start 30.6832 -112.0267)
		(end 30.6832 -111.252)
		(width 0.508)
		(layer "F.Cu")
		(net "GND")
	)
	(segment
		(start 88.011 -309.3085)
		(end 88.011 -309.4355)
		(width 0.3048)
		(layer "F.Cu")
		(net "GND")
	)
	(segment
		(start 105.246424 -208.4705)
		(end 106.045 -208.4705)
		(width 0.508)
		(layer "F.Cu")
		(net "GND")
	)
	(segment
		(start 22.800056 -130.40995)
		(end 24.384 -130.40995)
		(width 0.508)
		(layer "F.Cu")
		(net "GND")
	)
	(segment
		(start 20.025106 -446.585086)
		(end 18.415 -446.585086)
		(width 0.508)
		(layer "F.Cu")
		(net "GND")
	)
	(segment
		(start 99.949 -97.4725)
		(end 100.838 -97.4725)
		(width 0.508)
		(layer "F.Cu")
		(net "GND")
	)
	(segment
		(start 92.3925 -17.399)
		(end 92.3925 -16.5735)
		(width 0.508)
		(layer "F.Cu")
		(net "GND")
	)
	(segment
		(start 22.5425 -298.2341)
		(end 23.32355 -298.2341)
		(width 0.508)
		(layer "F.Cu")
		(net "GND")
	)
	(segment
		(start 39.4335 -144.653)
		(end 40.259 -144.653)
		(width 0.508)
		(layer "F.Cu")
		(net "GND")
	)
	(segment
		(start 224.199958 -371.590062)
		(end 222.616014 -371.590062)
		(width 0.508)
		(layer "F.Cu")
		(net "GND")
	)
	(segment
		(start 87.80907 -306.7685)
		(end 87.503 -306.7685)
		(width 0.3048)
		(layer "F.Cu")
		(net "GND")
	)
	(segment
		(start 224.199958 -268.590014)
		(end 222.616014 -268.590014)
		(width 0.508)
		(layer "F.Cu")
		(net "GND")
	)
	(segment
		(start 41.975024 -379.845062)
		(end 43.58513 -379.845062)
		(width 0.508)
		(layer "F.Cu")
		(net "GND")
	)
	(segment
		(start 89.55659 -305.93157)
		(end 88.646 -305.93157)
		(width 0.3048)
		(layer "F.Cu")
		(net "GND")
	)
	(segment
		(start 3.822954 -447.941954)
		(end 4.191 -448.31)
		(width 0.508)
		(layer "F.Cu")
		(net "GND")
	)
	(segment
		(start 89.3445 -444.754)
		(end 89.3445 -443.865)
		(width 0.508)
		(layer "F.Cu")
		(net "GND")
	)
	(segment
		(start 2.249932 -191.942212)
		(end 3.84302 -191.942212)
		(width 0.508)
		(layer "F.Cu")
		(net "GND")
	)
	(segment
		(start 88.88857 -308.43093)
		(end 88.011 -309.3085)
		(width 0.3048)
		(layer "F.Cu")
		(net "GND")
	)
	(segment
		(start 39.200074 -286.990028)
		(end 37.61613 -286.990028)
		(width 0.508)
		(layer "F.Cu")
		(net "GND")
	)
	(segment
		(start 214.9475 -299.98035)
		(end 216.0524 -299.98035)
		(width 0.508)
		(layer "F.Cu")
		(net "GND")
	)
	(segment
		(start 37.3634 -206.8068)
		(end 37.973 -206.1972)
		(width 0.508)
		(layer "F.Cu")
		(net "GND")
	)
	(segment
		(start 224.199958 -476.990156)
		(end 222.616014 -476.990156)
		(width 0.508)
		(layer "F.Cu")
		(net "GND")
	)
	(segment
		(start 20.025106 -332.155038)
		(end 18.415 -332.155038)
		(width 0.508)
		(layer "F.Cu")
		(net "GND")
	)
	(segment
		(start 3.84302 -195.142104)
		(end 4.191 -195.490084)
		(width 0.508)
		(layer "F.Cu")
		(net "GND")
	)
	(segment
		(start 22.800056 -439.410094)
		(end 24.384 -439.410094)
		(width 0.508)
		(layer "F.Cu")
		(net "GND")
	)
	(segment
		(start 37.211 -103.759)
		(end 37.0586 -103.759)
		(width 0.508)
		(layer "F.Cu")
		(net "GND")
	)
	(segment
		(start 99.5045 -204.851)
		(end 99.5045 -205.5495)
		(width 0.3048)
		(layer "F.Cu")
		(net "GND")
	)
	(segment
		(start 98.530918 -426.847)
		(end 98.530918 -428.04969)
		(width 0.3048)
		(layer "F.Cu")
		(net "GND")
	)
	(segment
		(start 2.249932 -228.741986)
		(end 3.81508 -228.741986)
		(width 0.508)
		(layer "F.Cu")
		(net "GND")
	)
	(segment
		(start 96.0374 -21.5011)
		(end 96.0374 -20.701)
		(width 0.508)
		(layer "F.Cu")
		(net "GND")
	)
	(segment
		(start 39.200074 -382.789938)
		(end 37.61613 -382.789938)
		(width 0.508)
		(layer "F.Cu")
		(net "GND")
	)
	(segment
		(start 2.249932 -348.342204)
		(end 3.81508 -348.342204)
		(width 0.508)
		(layer "F.Cu")
		(net "GND")
	)
	(segment
		(start 4.191 -446.037208)
		(end 3.6957 -445.541908)
		(width 0.508)
		(layer "F.Cu")
		(net "GND")
	)
	(segment
		(start 217.4748 -84.8995)
		(end 217.4748 -85.6742)
		(width 0.508)
		(layer "F.Cu")
		(net "GND")
	)
	(segment
		(start 48.91024 -241.2365)
		(end 49.657 -241.2365)
		(width 0.3556)
		(layer "F.Cu")
		(net "GND")
	)
	(segment
		(start 106.045 -310.7055)
		(end 105.226612 -310.7055)
		(width 0.508)
		(layer "F.Cu")
		(net "GND")
	)
	(segment
		(start 2.249932 -280.342086)
		(end 3.81508 -280.342086)
		(width 0.508)
		(layer "F.Cu")
		(net "GND")
	)
	(segment
		(start 98.530918 -301.011082)
		(end 98.530918 -301.43069)
		(width 0.3048)
		(layer "F.Cu")
		(net "GND")
	)
	(segment
		(start 3.927602 -167.942006)
		(end 2.249932 -167.942006)
		(width 0.508)
		(layer "F.Cu")
		(net "GND")
	)
	(segment
		(start 20.025106 -248.20499)
		(end 18.415 -248.20499)
		(width 0.508)
		(layer "F.Cu")
		(net "GND")
	)
	(segment
		(start 99.94519 -214.57031)
		(end 99.949 -214.5665)
		(width 0.3048)
		(layer "F.Cu")
		(net "GND")
	)
	(segment
		(start 41.975024 -467.60511)
		(end 43.58513 -467.60511)
		(width 0.508)
		(layer "F.Cu")
		(net "GND")
	)
	(segment
		(start 73.152 -443.484)
		(end 73.152 -442.595)
		(width 0.508)
		(layer "F.Cu")
		(net "GND")
	)
	(segment
		(start 22.800056 -37.809932)
		(end 24.384 -37.809932)
		(width 0.508)
		(layer "F.Cu")
		(net "GND")
	)
	(segment
		(start 39.200074 -78.589886)
		(end 37.61613 -78.589886)
		(width 0.508)
		(layer "F.Cu")
		(net "GND")
	)
	(segment
		(start 224.199958 -377.9901)
		(end 222.616014 -377.9901)
		(width 0.508)
		(layer "F.Cu")
		(net "GND")
	)
	(segment
		(start 2.249932 -173.542198)
		(end 3.81508 -173.542198)
		(width 0.508)
		(layer "F.Cu")
		(net "GND")
	)
	(segment
		(start 75.5904 -354.457)
		(end 75.5904 -353.568)
		(width 0.508)
		(layer "F.Cu")
		(net "GND")
	)
	(segment
		(start 39.200074 -53.789834)
		(end 37.61613 -53.789834)
		(width 0.508)
		(layer "F.Cu")
		(net "GND")
	)
	(segment
		(start 98.530918 -309.604918)
		(end 99.2505 -310.3245)
		(width 0.3048)
		(layer "F.Cu")
		(net "GND")
	)
	(segment
		(start 208.407 -44.2595)
		(end 208.407 -43.434)
		(width 0.508)
		(layer "F.Cu")
		(net "GND")
	)
	(segment
		(start 2.249932 -174.342044)
		(end 3.842766 -174.342044)
		(width 0.508)
		(layer "F.Cu")
		(net "GND")
	)
	(segment
		(start 41.975024 -381.115062)
		(end 43.58513 -381.115062)
		(width 0.508)
		(layer "F.Cu")
		(net "GND")
	)
	(segment
		(start 209.38109 -92.94241)
		(end 209.9945 -93.55582)
		(width 0.508)
		(layer "F.Cu")
		(net "GND")
	)
	(segment
		(start 41.975024 -276.845014)
		(end 43.58513 -276.845014)
		(width 0.508)
		(layer "F.Cu")
		(net "GND")
	)
	(segment
		(start 22.800056 -342.810084)
		(end 24.167084 -342.810084)
		(width 0.508)
		(layer "F.Cu")
		(net "GND")
	)
	(segment
		(start 224.199958 -53.789834)
		(end 222.616014 -53.789834)
		(width 0.508)
		(layer "F.Cu")
		(net "GND")
	)
	(segment
		(start 2.249932 -154.342084)
		(end 3.81508 -154.342084)
		(width 0.508)
		(layer "F.Cu")
		(net "GND")
	)
	(segment
		(start 55.14975 -447.9925)
		(end 56.0832 -447.9925)
		(width 0.508)
		(layer "F.Cu")
		(net "GND")
	)
	(segment
		(start 13.208 -478.5995)
		(end 13.208 -479.425)
		(width 0.508)
		(layer "F.Cu")
		(net "GND")
	)
	(segment
		(start 97.4725 -88.646)
		(end 97.4725 -89.535)
		(width 0.508)
		(layer "F.Cu")
		(net "GND")
	)
	(segment
		(start 50.546 -136.8425)
		(end 49.657 -136.8425)
		(width 0.508)
		(layer "F.Cu")
		(net "GND")
	)
	(segment
		(start 39.200074 -387.59003)
		(end 37.61613 -387.59003)
		(width 0.508)
		(layer "F.Cu")
		(net "GND")
	)
	(segment
		(start 211.1375 -461.518)
		(end 210.185 -461.518)
		(width 0.508)
		(layer "F.Cu")
		(net "GND")
	)
	(segment
		(start 3.6957 -445.541908)
		(end 2.249932 -445.541908)
		(width 0.508)
		(layer "F.Cu")
		(net "GND")
	)
	(segment
		(start 99.57181 -97.84969)
		(end 99.949 -97.4725)
		(width 0.3048)
		(layer "F.Cu")
		(net "GND")
	)
	(segment
		(start 88.961214 -112.871758)
		(end 89.3445 -113.255044)
		(width 0.508)
		(layer "F.Cu")
		(net "GND")
	)
	(segment
		(start 106.868722 -308.677564)
		(end 106.864658 -308.6735)
		(width 0.508)
		(layer "F.Cu")
		(net "GND")
	)
	(segment
		(start 31.5595 -205.98765)
		(end 30.361636 -205.98765)
		(width 0.508)
		(layer "F.Cu")
		(net "GND")
	)
	(segment
		(start 22.800056 -22.60981)
		(end 24.384 -22.60981)
		(width 0.508)
		(layer "F.Cu")
		(net "GND")
	)
	(segment
		(start 39.200074 -163.18992)
		(end 37.61613 -163.18992)
		(width 0.508)
		(layer "F.Cu")
		(net "GND")
	)
	(segment
		(start 2.249932 -309.94223)
		(end 3.84302 -309.94223)
		(width 0.508)
		(layer "F.Cu")
		(net "GND")
	)
	(segment
		(start 21.30425 -401.35175)
		(end 22.371304 -400.284696)
		(width 0.508)
		(layer "F.Cu")
		(net "GND")
	)
	(segment
		(start 22.800056 -243.810028)
		(end 24.384 -243.810028)
		(width 0.508)
		(layer "F.Cu")
		(net "GND")
	)
	(segment
		(start 226.198938 -435.890924)
		(end 226.198938 -436.764938)
		(width 0.3048)
		(layer "F.Cu")
		(net "GND")
	)
	(segment
		(start 100.44811 -432.05019)
		(end 100.5078 -431.9905)
		(width 0.3048)
		(layer "F.Cu")
		(net "GND")
	)
	(segment
		(start 39.200074 -183.98998)
		(end 37.61613 -183.98998)
		(width 0.508)
		(layer "F.Cu")
		(net "GND")
	)
	(segment
		(start 208.4451 -458.024738)
		(end 207.834738 -458.024738)
		(width 0.3556)
		(layer "F.Cu")
		(net "GND")
	)
	(segment
		(start 2.249932 -293.142162)
		(end 3.81508 -293.142162)
		(width 0.508)
		(layer "F.Cu")
		(net "GND")
	)
	(segment
		(start 36.70935 -412.1785)
		(end 36.5125 -411.98165)
		(width 0.508)
		(layer "F.Cu")
		(net "GND")
	)
	(segment
		(start 224.199958 -277.390098)
		(end 222.616014 -277.390098)
		(width 0.508)
		(layer "F.Cu")
		(net "GND")
	)
	(segment
		(start 2.249932 -206.342234)
		(end 3.81508 -206.342234)
		(width 0.508)
		(layer "F.Cu")
		(net "GND")
	)
	(segment
		(start 41.945052 -137.024618)
		(end 41.945052 -136.271)
		(width 0.3556)
		(layer "F.Cu")
		(net "GND")
	)
	(segment
		(start 39.200074 -480.990148)
		(end 37.61613 -480.990148)
		(width 0.508)
		(layer "F.Cu")
		(net "GND")
	)
	(segment
		(start 2.249932 -324.341998)
		(end 3.842766 -324.341998)
		(width 0.508)
		(layer "F.Cu")
		(net "GND")
	)
	(segment
		(start 2.249932 -357.942134)
		(end 3.81508 -357.942134)
		(width 0.508)
		(layer "F.Cu")
		(net "GND")
	)
	(segment
		(start 81.661 -104.902)
		(end 82.4865 -104.902)
		(width 0.508)
		(layer "F.Cu")
		(net "GND")
	)
	(segment
		(start 224.199958 -474.59011)
		(end 222.616014 -474.59011)
		(width 0.508)
		(layer "F.Cu")
		(net "GND")
	)
	(segment
		(start 22.800056 -143.210026)
		(end 24.384 -143.210026)
		(width 0.508)
		(layer "F.Cu")
		(net "GND")
	)
	(segment
		(start 87.122 -309.4355)
		(end 86.233 -309.4355)
		(width 0.508)
		(layer "F.Cu")
		(net "GND")
	)
	(segment
		(start 224.199958 -161.589974)
		(end 222.616014 -161.589974)
		(width 0.508)
		(layer "F.Cu")
		(net "GND")
	)
	(segment
		(start 101.9429 -102.0191)
		(end 101.981 -101.981)
		(width 0.508)
		(layer "F.Cu")
		(net "GND")
	)
	(segment
		(start 87.3125 -316.41288)
		(end 87.312246 -316.412626)
		(width 0.508)
		(layer "F.Cu")
		(net "GND")
	)
	(segment
		(start 87.3125 -222.071946)
		(end 87.312246 -222.071692)
		(width 0.508)
		(layer "F.Cu")
		(net "GND")
	)
	(segment
		(start 22.800056 -29.009848)
		(end 24.384 -29.009848)
		(width 0.508)
		(layer "F.Cu")
		(net "GND")
	)
	(segment
		(start 31.46425 -102.8954)
		(end 30.266386 -102.8954)
		(width 0.508)
		(layer "F.Cu")
		(net "GND")
	)
	(segment
		(start 41.975024 -261.605014)
		(end 43.58513 -261.605014)
		(width 0.508)
		(layer "F.Cu")
		(net "GND")
	)
	(segment
		(start 88.011 -436.0545)
		(end 87.122 -436.0545)
		(width 0.508)
		(layer "F.Cu")
		(net "GND")
	)
	(segment
		(start 39.200074 -365.190024)
		(end 37.61613 -365.190024)
		(width 0.508)
		(layer "F.Cu")
		(net "GND")
	)
	(segment
		(start 88.4555 -89.976198)
		(end 88.4555 -89.535)
		(width 0.508)
		(layer "F.Cu")
		(net "GND")
	)
	(segment
		(start 214.9475 -196.98335)
		(end 216.145364 -196.98335)
		(width 0.508)
		(layer "F.Cu")
		(net "GND")
	)
	(segment
		(start 50.546 -138.7475)
		(end 49.657 -138.7475)
		(width 0.508)
		(layer "F.Cu")
		(net "GND")
	)
	(segment
		(start 3.81508 -296.342054)
		(end 4.191 -295.966134)
		(width 0.508)
		(layer "F.Cu")
		(net "GND")
	)
	(segment
		(start 29.718 -421.0685)
		(end 29.718 -420.2684)
		(width 0.508)
		(layer "F.Cu")
		(net "GND")
	)
	(segment
		(start 39.200074 -66.58991)
		(end 37.61613 -66.58991)
		(width 0.508)
		(layer "F.Cu")
		(net "GND")
	)
	(segment
		(start 3.781806 -226.342194)
		(end 4.191 -225.933)
		(width 0.508)
		(layer "F.Cu")
		(net "GND")
	)
	(segment
		(start 10.6172 -497.9797)
		(end 10.6172 -497.6749)
		(width 0.508)
		(layer "F.Cu")
		(net "GND")
	)
	(segment
		(start 22.800056 -338.009992)
		(end 24.384 -338.009992)
		(width 0.508)
		(layer "F.Cu")
		(net "GND")
	)
	(segment
		(start 2.249932 -317.942214)
		(end 3.84302 -317.942214)
		(width 0.508)
		(layer "F.Cu")
		(net "GND")
	)
	(segment
		(start 226.974908 -173.844966)
		(end 228.585014 -173.844966)
		(width 0.508)
		(layer "F.Cu")
		(net "GND")
	)
	(segment
		(start 90.4875 -89.535)
		(end 90.4875 -88.646)
		(width 0.508)
		(layer "F.Cu")
		(net "GND")
	)
	(segment
		(start 3.81 -450.342)
		(end 4.191 -450.723)
		(width 0.508)
		(layer "F.Cu")
		(net "GND")
	)
	(segment
		(start 77.343 -211.7217)
		(end 77.343 -212.5218)
		(width 0.508)
		(layer "F.Cu")
		(net "GND")
	)
	(segment
		(start 226.974908 -278.115014)
		(end 228.585014 -278.115014)
		(width 0.508)
		(layer "F.Cu")
		(net "GND")
	)
	(segment
		(start 3.720084 -441.541916)
		(end 4.191 -441.071)
		(width 0.508)
		(layer "F.Cu")
		(net "GND")
	)
	(segment
		(start 39.200074 -367.59007)
		(end 37.61613 -367.59007)
		(width 0.508)
		(layer "F.Cu")
		(net "GND")
	)
	(segment
		(start 2.249932 -207.14208)
		(end 3.842766 -207.14208)
		(width 0.508)
		(layer "F.Cu")
		(net "GND")
	)
	(segment
		(start 93.22943 -427.37659)
		(end 93.22943 -428.752)
		(width 0.3048)
		(layer "F.Cu")
		(net "GND")
	)
	(segment
		(start 41.975024 -285.735014)
		(end 43.575986 -285.735014)
		(width 0.508)
		(layer "F.Cu")
		(net "GND")
	)
	(segment
		(start 22.800056 -429.810164)
		(end 24.384 -429.810164)
		(width 0.508)
		(layer "F.Cu")
		(net "GND")
	)
	(segment
		(start 2.249932 -429.54194)
		(end 3.78206 -429.54194)
		(width 0.508)
		(layer "F.Cu")
		(net "GND")
	)
	(segment
		(start 2.249932 -407.94178)
		(end 3.82778 -407.94178)
		(width 0.508)
		(layer "F.Cu")
		(net "GND")
	)
	(segment
		(start 39.200074 -165.589966)
		(end 37.61613 -165.589966)
		(width 0.508)
		(layer "F.Cu")
		(net "GND")
	)
	(segment
		(start 89.55659 -432.55057)
		(end 88.646 -432.55057)
		(width 0.3048)
		(layer "F.Cu")
		(net "GND")
	)
	(segment
		(start 3.842766 -200.742042)
		(end 4.191 -201.090276)
		(width 0.508)
		(layer "F.Cu")
		(net "GND")
	)
	(segment
		(start 20.025106 -347.395038)
		(end 18.884646 -347.395038)
		(width 0.508)
		(layer "F.Cu")
		(net "GND")
	)
	(segment
		(start 3.81508 -170.342052)
		(end 4.191 -169.966132)
		(width 0.508)
		(layer "F.Cu")
		(net "GND")
	)
	(segment
		(start 41.975024 -368.415062)
		(end 43.66133 -368.415062)
		(width 0.508)
		(layer "F.Cu")
		(net "GND")
	)
	(segment
		(start 25.4635 -93.98635)
		(end 25.4635 -93.8403)
		(width 0.508)
		(layer "F.Cu")
		(net "GND")
	)
	(segment
		(start 22.770592 -400.683984)
		(end 22.770592 -401.542758)
		(width 0.508)
		(layer "F.Cu")
		(net "GND")
	)
	(segment
		(start 3.777996 -401.541996)
		(end 4.191 -401.955)
		(width 0.508)
		(layer "F.Cu")
		(net "GND")
	)
	(segment
		(start 22.800056 -447.410078)
		(end 24.384 -447.410078)
		(width 0.508)
		(layer "F.Cu")
		(net "GND")
	)
	(segment
		(start 24.167084 -342.810084)
		(end 24.384 -343.027)
		(width 0.508)
		(layer "F.Cu")
		(net "GND")
	)
	(segment
		(start 22.800056 -432.21021)
		(end 24.384 -432.21021)
		(width 0.508)
		(layer "F.Cu")
		(net "GND")
	)
	(segment
		(start 39.200074 -377.9901)
		(end 37.61613 -377.9901)
		(width 0.508)
		(layer "F.Cu")
		(net "GND")
	)
	(segment
		(start 87.122 -215.0745)
		(end 88.011 -215.0745)
		(width 0.508)
		(layer "F.Cu")
		(net "GND")
	)
	(segment
		(start 41.975024 -72.114918)
		(end 43.58513 -72.114918)
		(width 0.508)
		(layer "F.Cu")
		(net "GND")
	)
	(segment
		(start 224.199958 -478.590102)
		(end 222.616014 -478.590102)
		(width 0.508)
		(layer "F.Cu")
		(net "GND")
	)
	(segment
		(start 25.4635 -93.8403)
		(end 24.7396 -93.1164)
		(width 0.508)
		(layer "F.Cu")
		(net "GND")
	)
	(segment
		(start 93.22943 -436.22341)
		(end 93.22943 -434.70957)
		(width 0.3048)
		(layer "F.Cu")
		(net "GND")
	)
	(segment
		(start 2.249932 -455.141838)
		(end 3.836162 -455.141838)
		(width 0.508)
		(layer "F.Cu")
		(net "GND")
	)
	(segment
		(start 39.200074 -492.990124)
		(end 37.61613 -492.990124)
		(width 0.508)
		(layer "F.Cu")
		(net "GND")
	)
	(segment
		(start 89.3445 -223.657414)
		(end 89.3445 -222.885)
		(width 0.508)
		(layer "F.Cu")
		(net "GND")
	)
	(segment
		(start 2.249932 -209.542126)
		(end 3.81508 -209.542126)
		(width 0.508)
		(layer "F.Cu")
		(net "GND")
	)
	(segment
		(start 39.200074 -80.989932)
		(end 37.61613 -80.989932)
		(width 0.508)
		(layer "F.Cu")
		(net "GND")
	)
	(segment
		(start 31.369 -381.8255)
		(end 31.369 -382.3208)
		(width 0.508)
		(layer "F.Cu")
		(net "GND")
	)
	(segment
		(start 4.191 -439.587132)
		(end 3.745738 -439.14187)
		(width 0.508)
		(layer "F.Cu")
		(net "GND")
	)
	(segment
		(start 23.05304 -469.1761)
		(end 23.5077 -469.1761)
		(width 0.381)
		(layer "F.Cu")
		(net "GND")
	)
	(segment
		(start 93.22943 -215.24341)
		(end 93.22943 -213.72957)
		(width 0.3048)
		(layer "F.Cu")
		(net "GND")
	)
	(segment
		(start 24.2316 -443.410086)
		(end 24.384 -443.257686)
		(width 0.508)
		(layer "F.Cu")
		(net "GND")
	)
	(segment
		(start 43.579034 -182.734966)
		(end 43.942 -182.372)
		(width 0.508)
		(layer "F.Cu")
		(net "GND")
	)
	(segment
		(start 3.842766 -349.14205)
		(end 4.191 -349.490284)
		(width 0.508)
		(layer "F.Cu")
		(net "GND")
	)
	(segment
		(start 221.615 -62.23)
		(end 221.615 -61.341)
		(width 0.508)
		(layer "F.Cu")
		(net "GND")
	)
	(segment
		(start 228.614986 -285.735014)
		(end 228.981 -285.369)
		(width 0.508)
		(layer "F.Cu")
		(net "GND")
	)
	(segment
		(start 32.131 -494.6015)
		(end 31.2928 -494.6015)
		(width 0.508)
		(layer "F.Cu")
		(net "GND")
	)
	(segment
		(start 99.7585 -211.6455)
		(end 99.949 -211.6455)
		(width 0.3048)
		(layer "F.Cu")
		(net "GND")
	)
	(segment
		(start 23.32355 -195.1355)
		(end 22.11705 -195.1355)
		(width 0.508)
		(layer "F.Cu")
		(net "GND")
	)
	(segment
		(start 226.198938 -436.764938)
		(end 226.314 -436.88)
		(width 0.3048)
		(layer "F.Cu")
		(net "GND")
	)
	(segment
		(start 86.614 -103.1875)
		(end 85.725 -103.1875)
		(width 0.508)
		(layer "F.Cu")
		(net "GND")
	)
	(segment
		(start 22.800056 -226.210114)
		(end 24.384 -226.210114)
		(width 0.508)
		(layer "F.Cu")
		(net "GND")
	)
	(segment
		(start 52.729384 -451.483984)
		(end 52.7304 -451.485)
		(width 0.381)
		(layer "F.Cu")
		(net "GND")
	)
	(segment
		(start 18.49501 -220.26499)
		(end 18.034 -220.726)
		(width 0.508)
		(layer "F.Cu")
		(net "GND")
	)
	(segment
		(start 226.974908 -154.794966)
		(end 228.585014 -154.794966)
		(width 0.508)
		(layer "F.Cu")
		(net "GND")
	)
	(segment
		(start 226.6315 -34.262822)
		(end 225.042222 -34.262822)
		(width 0.381)
		(layer "F.Cu")
		(net "GND")
	)
	(segment
		(start 95.8215 -197.866)
		(end 95.8215 -198.755)
		(width 0.508)
		(layer "F.Cu")
		(net "GND")
	)
	(segment
		(start 2.249932 -430.341786)
		(end 3.748786 -430.341786)
		(width 0.508)
		(layer "F.Cu")
		(net "GND")
	)
	(segment
		(start 22.800056 -452.21017)
		(end 24.384 -452.21017)
		(width 0.508)
		(layer "F.Cu")
		(net "GND")
	)
	(segment
		(start 226.974908 -381.115062)
		(end 228.585014 -381.115062)
		(width 0.508)
		(layer "F.Cu")
		(net "GND")
	)
	(segment
		(start 64.144652 -378.498608)
		(end 68.50126 -378.498608)
		(width 0.508)
		(layer "F.Cu")
		(net "GND")
	)
	(segment
		(start 252.704092 -414.299908)
		(end 252.704092 -414.934908)
		(width 0.8128)
		(layer "F.Cu")
		(net "GND")
	)
	(segment
		(start 106.864658 -308.6735)
		(end 106.045 -308.6735)
		(width 0.508)
		(layer "F.Cu")
		(net "GND")
	)
	(segment
		(start 39.200074 -174.39005)
		(end 37.61613 -174.39005)
		(width 0.508)
		(layer "F.Cu")
		(net "GND")
	)
	(segment
		(start 24.7396 -93.1164)
		(end 24.6761 -93.1164)
		(width 0.508)
		(layer "F.Cu")
		(net "GND")
	)
	(segment
		(start 39.200074 -465.790026)
		(end 37.61613 -465.790026)
		(width 0.508)
		(layer "F.Cu")
		(net "GND")
	)
	(segment
		(start 79.121 -353.6315)
		(end 79.121 -352.806)
		(width 0.508)
		(layer "F.Cu")
		(net "GND")
	)
	(segment
		(start 3.84302 -177.54219)
		(end 4.191 -177.89017)
		(width 0.508)
		(layer "F.Cu")
		(net "GND")
	)
	(segment
		(start 22.800056 -228.609906)
		(end 24.384 -228.609906)
		(width 0.508)
		(layer "F.Cu")
		(net "GND")
	)
	(segment
		(start 2.249932 -326.742044)
		(end 3.81508 -326.742044)
		(width 0.508)
		(layer "F.Cu")
		(net "GND")
	)
	(segment
		(start 100.4824 -305.3715)
		(end 102.0445 -305.3715)
		(width 0.508)
		(layer "F.Cu")
		(net "GND")
	)
	(segment
		(start 88.88857 -104.84993)
		(end 89.55659 -104.84993)
		(width 0.3048)
		(layer "F.Cu")
		(net "GND")
	)
	(segment
		(start 52.729384 -450.73824)
		(end 52.729384 -451.483984)
		(width 0.381)
		(layer "F.Cu")
		(net "GND")
	)
	(segment
		(start 98.7425 -425.831)
		(end 98.7425 -424.942)
		(width 0.508)
		(layer "F.Cu")
		(net "GND")
	)
	(segment
		(start 41.975024 -482.84511)
		(end 43.58513 -482.84511)
		(width 0.508)
		(layer "F.Cu")
		(net "GND")
	)
	(segment
		(start 88.88857 -214.06993)
		(end 89.55659 -214.06993)
		(width 0.3048)
		(layer "F.Cu")
		(net "GND")
	)
	(segment
		(start 18.488914 -426.265086)
		(end 18.034 -426.72)
		(width 0.508)
		(layer "F.Cu")
		(net "GND")
	)
	(segment
		(start 212.725 -454.2155)
		(end 212.725 -453.39)
		(width 0.508)
		(layer "F.Cu")
		(net "GND")
	)
	(segment
		(start 99.949 -105.3465)
		(end 100.838 -105.3465)
		(width 0.508)
		(layer "F.Cu")
		(net "GND")
	)
	(segment
		(start 3.84302 -339.54212)
		(end 4.191 -339.8901)
		(width 0.508)
		(layer "F.Cu")
		(net "GND")
	)
	(segment
		(start 2.249932 -338.74202)
		(end 3.81508 -338.74202)
		(width 0.508)
		(layer "F.Cu")
		(net "GND")
	)
	(segment
		(start 3.81508 -388.74192)
		(end 4.191 -388.366)
		(width 0.508)
		(layer "F.Cu")
		(net "GND")
	)
	(segment
		(start 224.199958 -66.58991)
		(end 222.616014 -66.58991)
		(width 0.508)
		(layer "F.Cu")
		(net "GND")
	)
	(segment
		(start 98.350832 -317.256668)
		(end 98.3615 -317.246)
		(width 0.508)
		(layer "F.Cu")
		(net "GND")
	)
	(via
		(at 50.8 -167.64)
		(size 0.508)
		(drill 0.254)
		(layers "F.Cu" "B.Cu")
		(net "GND")
	)
	(via
		(at 152.4 -284.48)
		(size 0.508)
		(drill 0.254)
		(layers "F.Cu" "B.Cu")
		(net "GND")
	)
	(via
		(at 147.32 -320.04)
		(size 0.508)
		(drill 0.254)
		(layers "F.Cu" "B.Cu")
		(net "GND")
	)
	(via
		(at 132.08 -238.76)
		(size 0.508)
		(drill 0.254)
		(layers "F.Cu" "B.Cu")
		(net "GND")
	)
	(via
		(at 219.290138 -387.131052)
		(size 0.508)
		(drill 0.254)
		(layers "F.Cu" "B.Cu")
		(net "GND")
	)
	(via
		(at 116.84 -106.68)
		(size 0.508)
		(drill 0.254)
		(layers "F.Cu" "B.Cu")
		(net "GND")
	)
	(via
		(at 233.68 -304.8)
		(size 0.508)
		(drill 0.254)
		(layers "F.Cu" "B.Cu")
		(net "GND")
	)
	(via
		(at 95.377 -429.006)
		(size 0.508)
		(drill 0.254)
		(layers "F.Cu" "B.Cu")
		(net "GND")
	)
	(via
		(at 177.8 -81.28)
		(size 0.508)
		(drill 0.254)
		(layers "F.Cu" "B.Cu")
		(net "GND")
	)
	(via
		(at 94.488 -219.71)
		(size 0.508)
		(drill 0.254)
		(layers "F.Cu" "B.Cu")
		(net "GND")
	)
	(via
		(at 6.223 -386.689854)
		(size 0.508)
		(drill 0.254)
		(layers "F.Cu" "B.Cu")
		(net "GND")
	)
	(via
		(at 262.103108 -351.438464)
		(size 0.508)
		(drill 0.254)
		(layers "F.Cu" "B.Cu")
		(net "GND")
	)
	(via
		(at 40.64 -457.2)
		(size 0.508)
		(drill 0.254)
		(layers "F.Cu" "B.Cu")
		(net "GND")
	)
	(via
		(at 33.4518 -15.5702)
		(size 0.508)
		(drill 0.254)
		(layers "F.Cu" "B.Cu")
		(net "GND")
	)
	(via
		(at 34.275014 -170.10126)
		(size 0.508)
		(drill 0.254)
		(layers "F.Cu" "B.Cu")
		(net "GND")
	)
	(via
		(at 10.16 -55.88)
		(size 0.508)
		(drill 0.254)
		(layers "F.Cu" "B.Cu")
		(net "GND")
	)
	(via
		(at 152.4 -233.68)
		(size 0.508)
		(drill 0.254)
		(layers "F.Cu" "B.Cu")
		(net "GND")
	)
	(via
		(at 96.52 -381)
		(size 0.508)
		(drill 0.254)
		(layers "F.Cu" "B.Cu")
		(net "GND")
	)
	(via
		(at 233.68 -86.36)
		(size 0.508)
		(drill 0.254)
		(layers "F.Cu" "B.Cu")
		(net "GND")
	)
	(via
		(at 233.68 -71.12)
		(size 0.508)
		(drill 0.254)
		(layers "F.Cu" "B.Cu")
		(net "GND")
	)
	(via
		(at 25.0952 -501.4214)
		(size 0.508)
		(drill 0.254)
		(layers "F.Cu" "B.Cu")
		(net "GND")
	)
	(via
		(at 87.312246 -316.412626)
		(size 0.508)
		(drill 0.254)
		(layers "F.Cu" "B.Cu")
		(net "GND")
	)
	(via
		(at 55.88 -40.64)
		(size 0.508)
		(drill 0.254)
		(layers "F.Cu" "B.Cu")
		(net "GND")
	)
	(via
		(at 137.16 -193.04)
		(size 0.508)
		(drill 0.254)
		(layers "F.Cu" "B.Cu")
		(net "GND")
	)
	(via
		(at 221.986348 -425.831)
		(size 0.508)
		(drill 0.254)
		(layers "F.Cu" "B.Cu")
		(net "GND")
	)
	(via
		(at 50.8 -228.6)
		(size 0.508)
		(drill 0.254)
		(layers "F.Cu" "B.Cu")
		(net "GND")
	)
	(via
		(at 193.04 -152.4)
		(size 0.508)
		(drill 0.254)
		(layers "F.Cu" "B.Cu")
		(net "GND")
	)
	(via
		(at 101.6 -350.52)
		(size 0.508)
		(drill 0.254)
		(layers "F.Cu" "B.Cu")
		(net "GND")
	)
	(via
		(at 248.92 -187.96)
		(size 0.508)
		(drill 0.254)
		(layers "F.Cu" "B.Cu")
		(net "GND")
	)
	(via
		(at 252.755908 -425.729908)
		(size 0.508)
		(drill 0.254)
		(layers "F.Cu" "B.Cu")
		(net "GND")
	)
	(via
		(at 213.36 -248.92)
		(size 0.508)
		(drill 0.254)
		(layers "F.Cu" "B.Cu")
		(net "GND")
	)
	(via
		(at 243.84 -233.68)
		(size 0.508)
		(drill 0.254)
		(layers "F.Cu" "B.Cu")
		(net "GND")
	)
	(via
		(at 240.03 -405.13)
		(size 0.7112)
		(drill 0.4064)
		(layers "F.Cu" "B.Cu")
		(net "GND")
	)
	(via
		(at 4.191 -279.966166)
		(size 0.508)
		(drill 0.254)
		(layers "F.Cu" "B.Cu")
		(net "GND")
	)
	(via
		(at 248.92 -71.12)
		(size 0.508)
		(drill 0.254)
		(layers "F.Cu" "B.Cu")
		(net "GND")
	)
	(via
		(at 25.3492 -49.3268)
		(size 0.508)
		(drill 0.254)
		(layers "F.Cu" "B.Cu")
		(net "GND")
	)
	(via
		(at 167.64 -243.84)
		(size 0.508)
		(drill 0.254)
		(layers "F.Cu" "B.Cu")
		(net "GND")
	)
	(via
		(at 177.8 -30.48)
		(size 0.508)
		(drill 0.254)
		(layers "F.Cu" "B.Cu")
		(net "GND")
	)
	(via
		(at 193.04 -30.48)
		(size 0.508)
		(drill 0.254)
		(layers "F.Cu" "B.Cu")
		(net "GND")
	)
	(via
		(at 101.6 -269.24)
		(size 0.508)
		(drill 0.254)
		(layers "F.Cu" "B.Cu")
		(net "GND")
	)
	(via
		(at 187.96 -426.72)
		(size 0.508)
		(drill 0.254)
		(layers "F.Cu" "B.Cu")
		(net "GND")
	)
	(via
		(at 233.68 -96.52)
		(size 0.508)
		(drill 0.254)
		(layers "F.Cu" "B.Cu")
		(net "GND")
	)
	(via
		(at 93.98 -307.975)
		(size 0.508)
		(drill 0.254)
		(layers "F.Cu" "B.Cu")
		(net "GND")
	)
	(via
		(at 50.8 -502.92)
		(size 0.508)
		(drill 0.254)
		(layers "F.Cu" "B.Cu")
		(net "GND")
	)
	(via
		(at 157.48 -355.6)
		(size 0.508)
		(drill 0.254)
		(layers "F.Cu" "B.Cu")
		(net "GND")
	)
	(via
		(at 71.12 -325.12)
		(size 0.508)
		(drill 0.254)
		(layers "F.Cu" "B.Cu")
		(net "GND")
	)
	(via
		(at 182.88 -127)
		(size 0.508)
		(drill 0.254)
		(layers "F.Cu" "B.Cu")
		(net "GND")
	)
	(via
		(at 147.32 -218.44)
		(size 0.508)
		(drill 0.254)
		(layers "F.Cu" "B.Cu")
		(net "GND")
	)
	(via
		(at 147.32 -457.2)
		(size 0.508)
		(drill 0.254)
		(layers "F.Cu" "B.Cu")
		(net "GND")
	)
	(via
		(at 40.64 -111.76)
		(size 0.508)
		(drill 0.254)
		(layers "F.Cu" "B.Cu")
		(net "GND")
	)
	(via
		(at 6.223 -177.923952)
		(size 0.508)
		(drill 0.254)
		(layers "F.Cu" "B.Cu")
		(net "GND")
	)
	(via
		(at 187.96 -30.48)
		(size 0.508)
		(drill 0.254)
		(layers "F.Cu" "B.Cu")
		(net "GND")
	)
	(via
		(at 121.92 -320.04)
		(size 0.508)
		(drill 0.254)
		(layers "F.Cu" "B.Cu")
		(net "GND")
	)
	(via
		(at 75.565 -361.696)
		(size 0.508)
		(drill 0.254)
		(layers "F.Cu" "B.Cu")
		(net "GND")
	)
	(via
		(at 4.191 -408.305)
		(size 0.508)
		(drill 0.254)
		(layers "F.Cu" "B.Cu")
		(net "GND")
	)
	(via
		(at 111.76 -345.44)
		(size 0.508)
		(drill 0.254)
		(layers "F.Cu" "B.Cu")
		(net "GND")
	)
	(via
		(at 187.96 -431.8)
		(size 0.508)
		(drill 0.254)
		(layers "F.Cu" "B.Cu")
		(net "GND")
	)
	(via
		(at 172.72 -497.84)
		(size 0.508)
		(drill 0.254)
		(layers "F.Cu" "B.Cu")
		(net "GND")
	)
	(via
		(at 259.08 -218.44)
		(size 0.508)
		(drill 0.254)
		(layers "F.Cu" "B.Cu")
		(net "GND")
	)
	(via
		(at 16.891 -430.276)
		(size 0.508)
		(drill 0.254)
		(layers "F.Cu" "B.Cu")
		(net "GND")
	)
	(via
		(at 75.5904 -353.568)
		(size 0.508)
		(drill 0.254)
		(layers "F.Cu" "B.Cu")
		(net "GND")
	)
	(via
		(at 74.422 -442.595)
		(size 0.508)
		(drill 0.254)
		(layers "F.Cu" "B.Cu")
		(net "GND")
	)
	(via
		(at 259.08 -462.28)
		(size 0.508)
		(drill 0.254)
		(layers "F.Cu" "B.Cu")
		(net "GND")
	)
	(via
		(at 99.5172 -90.3732)
		(size 0.508)
		(drill 0.254)
		(layers "F.Cu" "B.Cu")
		(net "GND")
	)
	(via
		(at 182.88 -142.24)
		(size 0.508)
		(drill 0.254)
		(layers "F.Cu" "B.Cu")
		(net "GND")
	)
	(via
		(at 24.384 -25.009856)
		(size 0.508)
		(drill 0.254)
		(layers "F.Cu" "B.Cu")
		(net "GND")
	)
	(via
		(at 18.415 -145.204942)
		(size 0.508)
		(drill 0.254)
		(layers "F.Cu" "B.Cu")
		(net "GND")
	)
	(via
		(at 233.68 -228.6)
		(size 0.508)
		(drill 0.254)
		(layers "F.Cu" "B.Cu")
		(net "GND")
	)
	(via
		(at 142.24 -45.72)
		(size 0.508)
		(drill 0.254)
		(layers "F.Cu" "B.Cu")
		(net "GND")
	)
	(via
		(at 31.0896 -291.8968)
		(size 0.508)
		(drill 0.254)
		(layers "F.Cu" "B.Cu")
		(net "GND")
	)
	(via
		(at 55.88 -238.76)
		(size 0.508)
		(drill 0.254)
		(layers "F.Cu" "B.Cu")
		(net "GND")
	)
	(via
		(at 248.92 -223.52)
		(size 0.508)
		(drill 0.254)
		(layers "F.Cu" "B.Cu")
		(net "GND")
	)
	(via
		(at 121.92 -20.32)
		(size 0.508)
		(drill 0.254)
		(layers "F.Cu" "B.Cu")
		(net "GND")
	)
	(via
		(at 24.384 -240.03)
		(size 0.508)
		(drill 0.254)
		(layers "F.Cu" "B.Cu")
		(net "GND")
	)
	(via
		(at 111.76 -10.16)
		(size 0.508)
		(drill 0.254)
		(layers "F.Cu" "B.Cu")
		(net "GND")
	)
	(via
		(at 71.12 -238.76)
		(size 0.508)
		(drill 0.254)
		(layers "F.Cu" "B.Cu")
		(net "GND")
	)
	(via
		(at 76.2 -457.2)
		(size 0.508)
		(drill 0.254)
		(layers "F.Cu" "B.Cu")
		(net "GND")
	)
	(via
		(at 24.6634 -206.0702)
		(size 0.508)
		(drill 0.254)
		(layers "F.Cu" "B.Cu")
		(net "GND")
	)
	(via
		(at 24.384 -449.810124)
		(size 0.508)
		(drill 0.254)
		(layers "F.Cu" "B.Cu")
		(net "GND")
	)
	(via
		(at 243.84 -472.44)
		(size 0.508)
		(drill 0.254)
		(layers "F.Cu" "B.Cu")
		(net "GND")
	)
	(via
		(at 193.04 -340.36)
		(size 0.508)
		(drill 0.254)
		(layers "F.Cu" "B.Cu")
		(net "GND")
	)
	(via
		(at 4.191 -289.566096)
		(size 0.508)
		(drill 0.254)
		(layers "F.Cu" "B.Cu")
		(net "GND")
	)
	(via
		(at 193.04 -441.96)
		(size 0.508)
		(drill 0.254)
		(layers "F.Cu" "B.Cu")
		(net "GND")
	)
	(via
		(at 4.191 -338.3661)
		(size 0.508)
		(drill 0.254)
		(layers "F.Cu" "B.Cu")
		(net "GND")
	)
	(via
		(at 37.61613 -53.789834)
		(size 0.508)
		(drill 0.254)
		(layers "F.Cu" "B.Cu")
		(net "GND")
	)
	(via
		(at 137.16 -340.36)
		(size 0.508)
		(drill 0.254)
		(layers "F.Cu" "B.Cu")
		(net "GND")
	)
	(via
		(at 202.057 -445.77)
		(size 0.508)
		(drill 0.254)
		(layers "F.Cu" "B.Cu")
		(net "GND")
	)
	(via
		(at 162.56 -320.04)
		(size 0.508)
		(drill 0.254)
		(layers "F.Cu" "B.Cu")
		(net "GND")
	)
	(via
		(at 152.4 -355.6)
		(size 0.508)
		(drill 0.254)
		(layers "F.Cu" "B.Cu")
		(net "GND")
	)
	(via
		(at 55.88 -218.44)
		(size 0.508)
		(drill 0.254)
		(layers "F.Cu" "B.Cu")
		(net "GND")
	)
	(via
		(at 218.44 -335.28)
		(size 0.508)
		(drill 0.254)
		(layers "F.Cu" "B.Cu")
		(net "GND")
	)
	(via
		(at 152.4 -365.76)
		(size 0.508)
		(drill 0.254)
		(layers "F.Cu" "B.Cu")
		(net "GND")
	)
	(via
		(at 216.549986 -504.603004)
		(size 0.508)
		(drill 0.254)
		(layers "F.Cu" "B.Cu")
		(net "GND")
	)
	(via
		(at 34.26333 -480.4791)
		(size 0.508)
		(drill 0.254)
		(layers "F.Cu" "B.Cu")
		(net "GND")
	)
	(via
		(at 212.696552 -441.833)
		(size 0.508)
		(drill 0.254)
		(layers "F.Cu" "B.Cu")
		(net "GND")
	)
	(via
		(at 96.774 -210.82)
		(size 0.508)
		(drill 0.254)
		(layers "F.Cu" "B.Cu")
		(net "GND")
	)
	(via
		(at 5.08 -106.68)
		(size 0.508)
		(drill 0.254)
		(layers "F.Cu" "B.Cu")
		(net "GND")
	)
	(via
		(at 213.36 -264.16)
		(size 0.508)
		(drill 0.254)
		(layers "F.Cu" "B.Cu")
		(net "GND")
	)
	(via
		(at 198.12 -228.6)
		(size 0.508)
		(drill 0.254)
		(layers "F.Cu" "B.Cu")
		(net "GND")
	)
	(via
		(at 94.869 -24.892)
		(size 0.508)
		(drill 0.254)
		(layers "F.Cu" "B.Cu")
		(net "GND")
	)
	(via
		(at 27.686 -331.219048)
		(size 0.508)
		(drill 0.254)
		(layers "F.Cu" "B.Cu")
		(net "GND")
	)
	(via
		(at 208.28 -177.8)
		(size 0.508)
		(drill 0.254)
		(layers "F.Cu" "B.Cu")
		(net "GND")
	)
	(via
		(at 34.31413 -261.852156)
		(size 0.508)
		(drill 0.254)
		(layers "F.Cu" "B.Cu")
		(net "GND")
	)
	(via
		(at 127 -193.04)
		(size 0.508)
		(drill 0.254)
		(layers "F.Cu" "B.Cu")
		(net "GND")
	)
	(via
		(at 162.56 -299.72)
		(size 0.508)
		(drill 0.254)
		(layers "F.Cu" "B.Cu")
		(net "GND")
	)
	(via
		(at 157.48 -203.2)
		(size 0.508)
		(drill 0.254)
		(layers "F.Cu" "B.Cu")
		(net "GND")
	)
	(via
		(at 55.88 -264.16)
		(size 0.508)
		(drill 0.254)
		(layers "F.Cu" "B.Cu")
		(net "GND")
	)
	(via
		(at 127 -218.44)
		(size 0.508)
		(drill 0.254)
		(layers "F.Cu" "B.Cu")
		(net "GND")
	)
	(via
		(at 216.145364 -196.98335)
		(size 0.508)
		(drill 0.254)
		(layers "F.Cu" "B.Cu")
		(net "GND")
	)
	(via
		(at 90.327988 -233.643678)
		(size 0.508)
		(drill 0.254)
		(layers "F.Cu" "B.Cu")
		(net "GND")
	)
	(via
		(at 27.315922 -482.098096)
		(size 0.508)
		(drill 0.254)
		(layers "F.Cu" "B.Cu")
		(net "GND")
	)
	(via
		(at 198.12 -223.52)
		(size 0.508)
		(drill 0.254)
		(layers "F.Cu" "B.Cu")
		(net "GND")
	)
	(via
		(at 193.04 -264.16)
		(size 0.508)
		(drill 0.254)
		(layers "F.Cu" "B.Cu")
		(net "GND")
	)
	(via
		(at 247.65 -402.59)
		(size 0.7112)
		(drill 0.4064)
		(layers "F.Cu" "B.Cu")
		(net "GND")
	)
	(via
		(at 147.32 -309.88)
		(size 0.508)
		(drill 0.254)
		(layers "F.Cu" "B.Cu")
		(net "GND")
	)
	(via
		(at 203.2 -142.24)
		(size 0.508)
		(drill 0.254)
		(layers "F.Cu" "B.Cu")
		(net "GND")
	)
	(via
		(at 5.08 -111.76)
		(size 0.508)
		(drill 0.254)
		(layers "F.Cu" "B.Cu")
		(net "GND")
	)
	(via
		(at 71.12 -340.36)
		(size 0.508)
		(drill 0.254)
		(layers "F.Cu" "B.Cu")
		(net "GND")
	)
	(via
		(at 34.28873 -488.6071)
		(size 0.508)
		(drill 0.254)
		(layers "F.Cu" "B.Cu")
		(net "GND")
	)
	(via
		(at 5.08 -243.84)
		(size 0.508)
		(drill 0.254)
		(layers "F.Cu" "B.Cu")
		(net "GND")
	)
	(via
		(at 248.92 -259.08)
		(size 0.508)
		(drill 0.254)
		(layers "F.Cu" "B.Cu")
		(net "GND")
	)
	(via
		(at 162.56 -213.36)
		(size 0.508)
		(drill 0.254)
		(layers "F.Cu" "B.Cu")
		(net "GND")
	)
	(via
		(at 76.2 -10.16)
		(size 0.508)
		(drill 0.254)
		(layers "F.Cu" "B.Cu")
		(net "GND")
	)
	(via
		(at 92.583 -213.614)
		(size 0.508)
		(drill 0.254)
		(layers "F.Cu" "B.Cu")
		(net "GND")
	)
	(via
		(at 142.24 -304.8)
		(size 0.508)
		(drill 0.254)
		(layers "F.Cu" "B.Cu")
		(net "GND")
	)
	(via
		(at 37.61613 -183.98998)
		(size 0.508)
		(drill 0.254)
		(layers "F.Cu" "B.Cu")
		(net "GND")
	)
	(via
		(at 24.384 -441.01004)
		(size 0.508)
		(drill 0.254)
		(layers "F.Cu" "B.Cu")
		(net "GND")
	)
	(via
		(at 50.8 -370.84)
		(size 0.508)
		(drill 0.254)
		(layers "F.Cu" "B.Cu")
		(net "GND")
	)
	(via
		(at 4.191 -204.290168)
		(size 0.508)
		(drill 0.254)
		(layers "F.Cu" "B.Cu")
		(net "GND")
	)
	(via
		(at 147.32 -335.28)
		(size 0.508)
		(drill 0.254)
		(layers "F.Cu" "B.Cu")
		(net "GND")
	)
	(via
		(at 127 -15.24)
		(size 0.508)
		(drill 0.254)
		(layers "F.Cu" "B.Cu")
		(net "GND")
	)
	(via
		(at 262.103108 -87.278464)
		(size 0.508)
		(drill 0.254)
		(layers "F.Cu" "B.Cu")
		(net "GND")
	)
	(via
		(at 6.223 -202.81138)
		(size 0.508)
		(drill 0.254)
		(layers "F.Cu" "B.Cu")
		(net "GND")
	)
	(via
		(at 34.31413 -157.127956)
		(size 0.508)
		(drill 0.254)
		(layers "F.Cu" "B.Cu")
		(net "GND")
	)
	(via
		(at 222.616014 -64.989964)
		(size 0.508)
		(drill 0.254)
		(layers "F.Cu" "B.Cu")
		(net "GND")
	)
	(via
		(at 152.4 -248.92)
		(size 0.508)
		(drill 0.254)
		(layers "F.Cu" "B.Cu")
		(net "GND")
	)
	(via
		(at 9.8552 -459.7654)
		(size 0.7112)
		(drill 0.4064)
		(layers "F.Cu" "B.Cu")
		(net "GND")
	)
	(via
		(at 5.08 -5.08)
		(size 0.508)
		(drill 0.254)
		(layers "F.Cu" "B.Cu")
		(net "GND")
	)
	(via
		(at 18.415 -240.58499)
		(size 0.508)
		(drill 0.254)
		(layers "F.Cu" "B.Cu")
		(net "GND")
	)
	(via
		(at 157.48 -66.04)
		(size 0.508)
		(drill 0.254)
		(layers "F.Cu" "B.Cu")
		(net "GND")
	)
	(via
		(at 254 -86.36)
		(size 0.508)
		(drill 0.254)
		(layers "F.Cu" "B.Cu")
		(net "GND")
	)
	(via
		(at 121.92 -274.32)
		(size 0.508)
		(drill 0.254)
		(layers "F.Cu" "B.Cu")
		(net "GND")
	)
	(via
		(at 246.384572 -1.397)
		(size 0.508)
		(drill 0.254)
		(layers "F.Cu" "B.Cu")
		(net "GND")
	)
	(via
		(at 198.12 -91.44)
		(size 0.508)
		(drill 0.254)
		(layers "F.Cu" "B.Cu")
		(net "GND")
	)
	(via
		(at 43.58513 -257.795014)
		(size 0.508)
		(drill 0.254)
		(layers "F.Cu" "B.Cu")
		(net "GND")
	)
	(via
		(at 248.92 -198.12)
		(size 0.508)
		(drill 0.254)
		(layers "F.Cu" "B.Cu")
		(net "GND")
	)
	(via
		(at 221.986348 -424.688)
		(size 0.508)
		(drill 0.254)
		(layers "F.Cu" "B.Cu")
		(net "GND")
	)
	(via
		(at 248.92 -101.6)
		(size 0.508)
		(drill 0.254)
		(layers "F.Cu" "B.Cu")
		(net "GND")
	)
	(via
		(at 198.12 -330.2)
		(size 0.508)
		(drill 0.254)
		(layers "F.Cu" "B.Cu")
		(net "GND")
	)
	(via
		(at 18.415 -343.585038)
		(size 0.508)
		(drill 0.254)
		(layers "F.Cu" "B.Cu")
		(net "GND")
	)
	(via
		(at 127 -182.88)
		(size 0.508)
		(drill 0.254)
		(layers "F.Cu" "B.Cu")
		(net "GND")
	)
	(via
		(at 213.712552 -430.657)
		(size 0.508)
		(drill 0.254)
		(layers "F.Cu" "B.Cu")
		(net "GND")
	)
	(via
		(at 45.72 -289.56)
		(size 0.508)
		(drill 0.254)
		(layers "F.Cu" "B.Cu")
		(net "GND")
	)
	(via
		(at 177.8 -223.52)
		(size 0.508)
		(drill 0.254)
		(layers "F.Cu" "B.Cu")
		(net "GND")
	)
	(via
		(at 142.24 -284.48)
		(size 0.508)
		(drill 0.254)
		(layers "F.Cu" "B.Cu")
		(net "GND")
	)
	(via
		(at 116.84 -193.04)
		(size 0.508)
		(drill 0.254)
		(layers "F.Cu" "B.Cu")
		(net "GND")
	)
	(via
		(at 243.84 -106.68)
		(size 0.508)
		(drill 0.254)
		(layers "F.Cu" "B.Cu")
		(net "GND")
	)
	(via
		(at 79.629 -91.948)
		(size 0.508)
		(drill 0.254)
		(layers "F.Cu" "B.Cu")
		(net "GND")
	)
	(via
		(at 27.4066 -103.124)
		(size 0.508)
		(drill 0.254)
		(layers "F.Cu" "B.Cu")
		(net "GND")
	)
	(via
		(at 50.8 -121.92)
		(size 0.508)
		(drill 0.254)
		(layers "F.Cu" "B.Cu")
		(net "GND")
	)
	(via
		(at 27.72664 -25.520904)
		(size 0.508)
		(drill 0.254)
		(layers "F.Cu" "B.Cu")
		(net "GND")
	)
	(via
		(at 147.32 -477.52)
		(size 0.508)
		(drill 0.254)
		(layers "F.Cu" "B.Cu")
		(net "GND")
	)
	(via
		(at 12.400788 -100.054664)
		(size 0.508)
		(drill 0.254)
		(layers "F.Cu" "B.Cu")
		(net "GND")
	)
	(via
		(at 219.314014 -380.781052)
		(size 0.508)
		(drill 0.254)
		(layers "F.Cu" "B.Cu")
		(net "GND")
	)
	(via
		(at 172.72 -320.04)
		(size 0.508)
		(drill 0.254)
		(layers "F.Cu" "B.Cu")
		(net "GND")
	)
	(via
		(at 92.583 -305.181)
		(size 0.508)
		(drill 0.254)
		(layers "F.Cu" "B.Cu")
		(net "GND")
	)
	(via
		(at 4.191 -403.479)
		(size 0.508)
		(drill 0.254)
		(layers "F.Cu" "B.Cu")
		(net "GND")
	)
	(via
		(at 233.68 -284.48)
		(size 0.508)
		(drill 0.254)
		(layers "F.Cu" "B.Cu")
		(net "GND")
	)
	(via
		(at 6.223 -396.290038)
		(size 0.508)
		(drill 0.254)
		(layers "F.Cu" "B.Cu")
		(net "GND")
	)
	(via
		(at 162.56 -71.12)
		(size 0.508)
		(drill 0.254)
		(layers "F.Cu" "B.Cu")
		(net "GND")
	)
	(via
		(at 121.92 -452.12)
		(size 0.508)
		(drill 0.254)
		(layers "F.Cu" "B.Cu")
		(net "GND")
	)
	(via
		(at 167.64 -182.88)
		(size 0.508)
		(drill 0.254)
		(layers "F.Cu" "B.Cu")
		(net "GND")
	)
	(via
		(at 203.2 -375.92)
		(size 0.508)
		(drill 0.254)
		(layers "F.Cu" "B.Cu")
		(net "GND")
	)
	(via
		(at 248.92 -96.52)
		(size 0.508)
		(drill 0.254)
		(layers "F.Cu" "B.Cu")
		(net "GND")
	)
	(via
		(at 48.387 -165.484302)
		(size 0.508)
		(drill 0.254)
		(layers "F.Cu" "B.Cu")
		(net "GND")
	)
	(via
		(at 218.44 -106.68)
		(size 0.508)
		(drill 0.254)
		(layers "F.Cu" "B.Cu")
		(net "GND")
	)
	(via
		(at 198.12 -294.64)
		(size 0.508)
		(drill 0.254)
		(layers "F.Cu" "B.Cu")
		(net "GND")
	)
	(via
		(at 48.387 -162.487102)
		(size 0.508)
		(drill 0.254)
		(layers "F.Cu" "B.Cu")
		(net "GND")
	)
	(via
		(at 121.92 -25.4)
		(size 0.508)
		(drill 0.254)
		(layers "F.Cu" "B.Cu")
		(net "GND")
	)
	(via
		(at 86.36 -25.4)
		(size 0.508)
		(drill 0.254)
		(layers "F.Cu" "B.Cu")
		(net "GND")
	)
	(via
		(at 116.84 -502.92)
		(size 0.508)
		(drill 0.254)
		(layers "F.Cu" "B.Cu")
		(net "GND")
	)
	(via
		(at 225.175318 -240.262918)
		(size 0.508)
		(drill 0.254)
		(layers "F.Cu" "B.Cu")
		(net "GND")
	)
	(via
		(at 218.44 -147.32)
		(size 0.508)
		(drill 0.254)
		(layers "F.Cu" "B.Cu")
		(net "GND")
	)
	(via
		(at 1.397 -112.009428)
		(size 0.508)
		(drill 0.254)
		(layers "F.Cu" "B.Cu")
		(net "GND")
	)
	(via
		(at 81.28 -406.4)
		(size 0.508)
		(drill 0.254)
		(layers "F.Cu" "B.Cu")
		(net "GND")
	)
	(via
		(at 91.186 -303.784)
		(size 0.508)
		(drill 0.254)
		(layers "F.Cu" "B.Cu")
		(net "GND")
	)
	(via
		(at 44.828968 -367.699036)
		(size 0.508)
		(drill 0.254)
		(layers "F.Cu" "B.Cu")
		(net "GND")
	)
	(via
		(at 96.774 -209.423)
		(size 0.508)
		(drill 0.254)
		(layers "F.Cu" "B.Cu")
		(net "GND")
	)
	(via
		(at 233.68 -365.76)
		(size 0.508)
		(drill 0.254)
		(layers "F.Cu" "B.Cu")
		(net "GND")
	)
	(via
		(at 132.08 -502.92)
		(size 0.508)
		(drill 0.254)
		(layers "F.Cu" "B.Cu")
		(net "GND")
	)
	(via
		(at 137.16 -472.44)
		(size 0.508)
		(drill 0.254)
		(layers "F.Cu" "B.Cu")
		(net "GND")
	)
	(via
		(at 203.2 -228.6)
		(size 0.508)
		(drill 0.254)
		(layers "F.Cu" "B.Cu")
		(net "GND")
	)
	(via
		(at 66.04 -386.08)
		(size 0.508)
		(drill 0.254)
		(layers "F.Cu" "B.Cu")
		(net "GND")
	)
	(via
		(at 91.186 -213.614)
		(size 0.508)
		(drill 0.254)
		(layers "F.Cu" "B.Cu")
		(net "GND")
	)
	(via
		(at 218.44 -502.92)
		(size 0.508)
		(drill 0.254)
		(layers "F.Cu" "B.Cu")
		(net "GND")
	)
	(via
		(at 218.44 -111.76)
		(size 0.508)
		(drill 0.254)
		(layers "F.Cu" "B.Cu")
		(net "GND")
	)
	(via
		(at 121.92 -228.6)
		(size 0.508)
		(drill 0.254)
		(layers "F.Cu" "B.Cu")
		(net "GND")
	)
	(via
		(at 191.149986 -504.603004)
		(size 0.508)
		(drill 0.254)
		(layers "F.Cu" "B.Cu")
		(net "GND")
	)
	(via
		(at 262.103108 -244.758464)
		(size 0.508)
		(drill 0.254)
		(layers "F.Cu" "B.Cu")
		(net "GND")
	)
	(via
		(at 96.52 -345.44)
		(size 0.508)
		(drill 0.254)
		(layers "F.Cu" "B.Cu")
		(net "GND")
	)
	(via
		(at 203.2 -365.76)
		(size 0.508)
		(drill 0.254)
		(layers "F.Cu" "B.Cu")
		(net "GND")
	)
	(via
		(at 95.377 -431.8)
		(size 0.508)
		(drill 0.254)
		(layers "F.Cu" "B.Cu")
		(net "GND")
	)
	(via
		(at 157.48 -10.16)
		(size 0.508)
		(drill 0.254)
		(layers "F.Cu" "B.Cu")
		(net "GND")
	)
	(via
		(at 241.808 -426.212)
		(size 0.508)
		(drill 0.254)
		(layers "F.Cu" "B.Cu")
		(net "GND")
	)
	(via
		(at 243.84 -218.44)
		(size 0.508)
		(drill 0.254)
		(layers "F.Cu" "B.Cu")
		(net "GND")
	)
	(via
		(at 66.04 -365.76)
		(size 0.508)
		(drill 0.254)
		(layers "F.Cu" "B.Cu")
		(net "GND")
	)
	(via
		(at 162.56 -76.2)
		(size 0.508)
		(drill 0.254)
		(layers "F.Cu" "B.Cu")
		(net "GND")
	)
	(via
		(at 4.191 -292.766242)
		(size 0.508)
		(drill 0.254)
		(layers "F.Cu" "B.Cu")
		(net "GND")
	)
	(via
		(at 211.680552 -430.657)
		(size 0.508)
		(drill 0.254)
		(layers "F.Cu" "B.Cu")
		(net "GND")
	)
	(via
		(at 91.44 -10.16)
		(size 0.508)
		(drill 0.254)
		(layers "F.Cu" "B.Cu")
		(net "GND")
	)
	(via
		(at 50.8 -284.48)
		(size 0.508)
		(drill 0.254)
		(layers "F.Cu" "B.Cu")
		(net "GND")
	)
	(via
		(at 24.384 -40.209978)
		(size 0.508)
		(drill 0.254)
		(layers "F.Cu" "B.Cu")
		(net "GND")
	)
	(via
		(at 182.88 -172.72)
		(size 0.508)
		(drill 0.254)
		(layers "F.Cu" "B.Cu")
		(net "GND")
	)
	(via
		(at 27.719782 -334.501744)
		(size 0.508)
		(drill 0.254)
		(layers "F.Cu" "B.Cu")
		(net "GND")
	)
	(via
		(at 254 -147.32)
		(size 0.508)
		(drill 0.254)
		(layers "F.Cu" "B.Cu")
		(net "GND")
	)
	(via
		(at 86.36 -167.64)
		(size 0.508)
		(drill 0.254)
		(layers "F.Cu" "B.Cu")
		(net "GND")
	)
	(via
		(at 242.57 -400.05)
		(size 0.7112)
		(drill 0.4064)
		(layers "F.Cu" "B.Cu")
		(net "GND")
	)
	(via
		(at 238.76 -45.72)
		(size 0.508)
		(drill 0.254)
		(layers "F.Cu" "B.Cu")
		(net "GND")
	)
	(via
		(at 55.88 -20.32)
		(size 0.508)
		(drill 0.254)
		(layers "F.Cu" "B.Cu")
		(net "GND")
	)
	(via
		(at 4.191 -287.909)
		(size 0.508)
		(drill 0.254)
		(layers "F.Cu" "B.Cu")
		(net "GND")
	)
	(via
		(at 6.223 -215.560656)
		(size 0.508)
		(drill 0.254)
		(layers "F.Cu" "B.Cu")
		(net "GND")
	)
	(via
		(at 111.76 -304.8)
		(size 0.508)
		(drill 0.254)
		(layers "F.Cu" "B.Cu")
		(net "GND")
	)
	(via
		(at 60.96 -10.16)
		(size 0.508)
		(drill 0.254)
		(layers "F.Cu" "B.Cu")
		(net "GND")
	)
	(via
		(at 37.61613 -161.589974)
		(size 0.508)
		(drill 0.254)
		(layers "F.Cu" "B.Cu")
		(net "GND")
	)
	(via
		(at 243.84 -35.56)
		(size 0.508)
		(drill 0.254)
		(layers "F.Cu" "B.Cu")
		(net "GND")
	)
	(via
		(at 162.56 -436.88)
		(size 0.508)
		(drill 0.254)
		(layers "F.Cu" "B.Cu")
		(net "GND")
	)
	(via
		(at 26.543 -309.118)
		(size 0.508)
		(drill 0.254)
		(layers "F.Cu" "B.Cu")
		(net "GND")
	)
	(via
		(at 93.599 -449.072)
		(size 0.508)
		(drill 0.254)
		(layers "F.Cu" "B.Cu")
		(net "GND")
	)
	(via
		(at 89.349834 -318.062102)
		(size 0.508)
		(drill 0.254)
		(layers "F.Cu" "B.Cu")
		(net "GND")
	)
	(via
		(at 238.76 -167.64)
		(size 0.508)
		(drill 0.254)
		(layers "F.Cu" "B.Cu")
		(net "GND")
	)
	(via
		(at 121.92 -248.92)
		(size 0.508)
		(drill 0.254)
		(layers "F.Cu" "B.Cu")
		(net "GND")
	)
	(via
		(at 81.28 -55.88)
		(size 0.508)
		(drill 0.254)
		(layers "F.Cu" "B.Cu")
		(net "GND")
	)
	(via
		(at 142.24 -314.96)
		(size 0.508)
		(drill 0.254)
		(layers "F.Cu" "B.Cu")
		(net "GND")
	)
	(via
		(at 219.289884 -488.649264)
		(size 0.508)
		(drill 0.254)
		(layers "F.Cu" "B.Cu")
		(net "GND")
	)
	(via
		(at 9.144 -243.84)
		(size 0.508)
		(drill 0.254)
		(layers "F.Cu" "B.Cu")
		(net "GND")
	)
	(via
		(at 157.48 -177.8)
		(size 0.508)
		(drill 0.254)
		(layers "F.Cu" "B.Cu")
		(net "GND")
	)
	(via
		(at 177.8 -462.28)
		(size 0.508)
		(drill 0.254)
		(layers "F.Cu" "B.Cu")
		(net "GND")
	)
	(via
		(at 243.84 -10.16)
		(size 0.508)
		(drill 0.254)
		(layers "F.Cu" "B.Cu")
		(net "GND")
	)
	(via
		(at 111.76 -299.72)
		(size 0.508)
		(drill 0.254)
		(layers "F.Cu" "B.Cu")
		(net "GND")
	)
	(via
		(at 101.6 -482.6)
		(size 0.508)
		(drill 0.254)
		(layers "F.Cu" "B.Cu")
		(net "GND")
	)
	(via
		(at 60.96 -147.32)
		(size 0.508)
		(drill 0.254)
		(layers "F.Cu" "B.Cu")
		(net "GND")
	)
	(via
		(at 219.274644 -376.101356)
		(size 0.508)
		(drill 0.254)
		(layers "F.Cu" "B.Cu")
		(net "GND")
	)
	(via
		(at 243.84 -243.84)
		(size 0.508)
		(drill 0.254)
		(layers "F.Cu" "B.Cu")
		(net "GND")
	)
	(via
		(at 193.04 -162.56)
		(size 0.508)
		(drill 0.254)
		(layers "F.Cu" "B.Cu")
		(net "GND")
	)
	(via
		(at 127 -335.28)
		(size 0.508)
		(drill 0.254)
		(layers "F.Cu" "B.Cu")
		(net "GND")
	)
	(via
		(at 142.24 -340.36)
		(size 0.508)
		(drill 0.254)
		(layers "F.Cu" "B.Cu")
		(net "GND")
	)
	(via
		(at 142.24 -30.48)
		(size 0.508)
		(drill 0.254)
		(layers "F.Cu" "B.Cu")
		(net "GND")
	)
	(via
		(at 77.7748 -429.1076)
		(size 0.508)
		(drill 0.254)
		(layers "F.Cu" "B.Cu")
		(net "GND")
	)
	(via
		(at 91.44 -335.28)
		(size 0.508)
		(drill 0.254)
		(layers "F.Cu" "B.Cu")
		(net "GND")
	)
	(via
		(at 162.56 -218.44)
		(size 0.508)
		(drill 0.254)
		(layers "F.Cu" "B.Cu")
		(net "GND")
	)
	(via
		(at 116.84 -238.76)
		(size 0.508)
		(drill 0.254)
		(layers "F.Cu" "B.Cu")
		(net "GND")
	)
	(via
		(at 8.9154 -460.502)
		(size 0.7112)
		(drill 0.4064)
		(layers "F.Cu" "B.Cu")
		(net "GND")
	)
	(via
		(at 248.92 -299.72)
		(size 0.508)
		(drill 0.254)
		(layers "F.Cu" "B.Cu")
		(net "GND")
	)
	(via
		(at 203.2 -350.52)
		(size 0.508)
		(drill 0.254)
		(layers "F.Cu" "B.Cu")
		(net "GND")
	)
	(via
		(at 76.2 -472.44)
		(size 0.508)
		(drill 0.254)
		(layers "F.Cu" "B.Cu")
		(net "GND")
	)
	(via
		(at 45.72 -284.48)
		(size 0.508)
		(drill 0.254)
		(layers "F.Cu" "B.Cu")
		(net "GND")
	)
	(via
		(at 208.28 -208.28)
		(size 0.508)
		(drill 0.254)
		(layers "F.Cu" "B.Cu")
		(net "GND")
	)
	(via
		(at 137.16 -213.36)
		(size 0.508)
		(drill 0.254)
		(layers "F.Cu" "B.Cu")
		(net "GND")
	)
	(via
		(at 76.2 -487.68)
		(size 0.508)
		(drill 0.254)
		(layers "F.Cu" "B.Cu")
		(net "GND")
	)
	(via
		(at 242.57 -402.59)
		(size 0.7112)
		(drill 0.4064)
		(layers "F.Cu" "B.Cu")
		(net "GND")
	)
	(via
		(at 187.96 -330.2)
		(size 0.508)
		(drill 0.254)
		(layers "F.Cu" "B.Cu")
		(net "GND")
	)
	(via
		(at 142.24 -457.2)
		(size 0.508)
		(drill 0.254)
		(layers "F.Cu" "B.Cu")
		(net "GND")
	)
	(via
		(at 130.189986 -504.603004)
		(size 0.508)
		(drill 0.254)
		(layers "F.Cu" "B.Cu")
		(net "GND")
	)
	(via
		(at 182.88 -81.28)
		(size 0.508)
		(drill 0.254)
		(layers "F.Cu" "B.Cu")
		(net "GND")
	)
	(via
		(at 243.84 -223.52)
		(size 0.508)
		(drill 0.254)
		(layers "F.Cu" "B.Cu")
		(net "GND")
	)
	(via
		(at 111.76 -360.68)
		(size 0.508)
		(drill 0.254)
		(layers "F.Cu" "B.Cu")
		(net "GND")
	)
	(via
		(at 24.384 -143.210026)
		(size 0.508)
		(drill 0.254)
		(layers "F.Cu" "B.Cu")
		(net "GND")
	)
	(via
		(at 6.223 -281.525472)
		(size 0.508)
		(drill 0.254)
		(layers "F.Cu" "B.Cu")
		(net "GND")
	)
	(via
		(at 34.7218 -436.9054)
		(size 0.508)
		(drill 0.254)
		(layers "F.Cu" "B.Cu")
		(net "GND")
	)
	(via
		(at 55.88 -401.32)
		(size 0.508)
		(drill 0.254)
		(layers "F.Cu" "B.Cu")
		(net "GND")
	)
	(via
		(at 95.377 -208.026)
		(size 0.508)
		(drill 0.254)
		(layers "F.Cu" "B.Cu")
		(net "GND")
	)
	(via
		(at 116.84 -147.32)
		(size 0.508)
		(drill 0.254)
		(layers "F.Cu" "B.Cu")
		(net "GND")
	)
	(via
		(at 45.72 -426.72)
		(size 0.508)
		(drill 0.254)
		(layers "F.Cu" "B.Cu")
		(net "GND")
	)
	(via
		(at 182.88 -35.56)
		(size 0.508)
		(drill 0.254)
		(layers "F.Cu" "B.Cu")
		(net "GND")
	)
	(via
		(at 116.84 -35.56)
		(size 0.508)
		(drill 0.254)
		(layers "F.Cu" "B.Cu")
		(net "GND")
	)
	(via
		(at 248.92 -340.36)
		(size 0.508)
		(drill 0.254)
		(layers "F.Cu" "B.Cu")
		(net "GND")
	)
	(via
		(at 213.36 -218.44)
		(size 0.508)
		(drill 0.254)
		(layers "F.Cu" "B.Cu")
		(net "GND")
	)
	(via
		(at 193.04 -233.68)
		(size 0.508)
		(drill 0.254)
		(layers "F.Cu" "B.Cu")
		(net "GND")
	)
	(via
		(at 76.2 -50.8)
		(size 0.508)
		(drill 0.254)
		(layers "F.Cu" "B.Cu")
		(net "GND")
	)
	(via
		(at 75.1332 -428.9806)
		(size 0.508)
		(drill 0.254)
		(layers "F.Cu" "B.Cu")
		(net "GND")
	)
	(via
		(at 248.92 -167.64)
		(size 0.508)
		(drill 0.254)
		(layers "F.Cu" "B.Cu")
		(net "GND")
	)
	(via
		(at 55.88 -76.2)
		(size 0.508)
		(drill 0.254)
		(layers "F.Cu" "B.Cu")
		(net "GND")
	)
	(via
		(at 121.92 -208.28)
		(size 0.508)
		(drill 0.254)
		(layers "F.Cu" "B.Cu")
		(net "GND")
	)
	(via
		(at 177.8 -60.96)
		(size 0.508)
		(drill 0.254)
		(layers "F.Cu" "B.Cu")
		(net "GND")
	)
	(via
		(at 152.4 -40.64)
		(size 0.508)
		(drill 0.254)
		(layers "F.Cu" "B.Cu")
		(net "GND")
	)
	(via
		(at 100.838 -214.5665)
		(size 0.508)
		(drill 0.254)
		(layers "F.Cu" "B.Cu")
		(net "GND")
	)
	(via
		(at 24.384 -437.010048)
		(size 0.508)
		(drill 0.254)
		(layers "F.Cu" "B.Cu")
		(net "GND")
	)
	(via
		(at 37.61613 -66.58991)
		(size 0.508)
		(drill 0.254)
		(layers "F.Cu" "B.Cu")
		(net "GND")
	)
	(via
		(at 252.73 -423.189908)
		(size 0.508)
		(drill 0.254)
		(layers "F.Cu" "B.Cu")
		(net "GND")
	)
	(via
		(at 252.109986 -504.603004)
		(size 0.508)
		(drill 0.254)
		(layers "F.Cu" "B.Cu")
		(net "GND")
	)
	(via
		(at 34.31413 -364.852204)
		(size 0.508)
		(drill 0.254)
		(layers "F.Cu" "B.Cu")
		(net "GND")
	)
	(via
		(at 121.92 -335.28)
		(size 0.508)
		(drill 0.254)
		(layers "F.Cu" "B.Cu")
		(net "GND")
	)
	(via
		(at 218.44 -132.08)
		(size 0.508)
		(drill 0.254)
		(layers "F.Cu" "B.Cu")
		(net "GND")
	)
	(via
		(at 157.48 -467.36)
		(size 0.508)
		(drill 0.254)
		(layers "F.Cu" "B.Cu")
		(net "GND")
	)
	(via
		(at 254 -492.76)
		(size 0.508)
		(drill 0.254)
		(layers "F.Cu" "B.Cu")
		(net "GND")
	)
	(via
		(at 111.76 -91.44)
		(size 0.508)
		(drill 0.254)
		(layers "F.Cu" "B.Cu")
		(net "GND")
	)
	(via
		(at 4.191 -299.16628)
		(size 0.508)
		(drill 0.254)
		(layers "F.Cu" "B.Cu")
		(net "GND")
	)
	(via
		(at 34.544 -93.98)
		(size 0.508)
		(drill 0.254)
		(layers "F.Cu" "B.Cu")
		(net "GND")
	)
	(via
		(at 233.68 -187.96)
		(size 0.508)
		(drill 0.254)
		(layers "F.Cu" "B.Cu")
		(net "GND")
	)
	(via
		(at 24.4094 -13.2842)
		(size 0.508)
		(drill 0.254)
		(layers "F.Cu" "B.Cu")
		(net "GND")
	)
	(via
		(at 198.12 -20.32)
		(size 0.508)
		(drill 0.254)
		(layers "F.Cu" "B.Cu")
		(net "GND")
	)
	(via
		(at 238.76 -228.6)
		(size 0.508)
		(drill 0.254)
		(layers "F.Cu" "B.Cu")
		(net "GND")
	)
	(via
		(at 221.8182 -393.4714)
		(size 0.508)
		(drill 0.254)
		(layers "F.Cu" "B.Cu")
		(net "GND")
	)
	(via
		(at 2.544572 -1.397)
		(size 0.508)
		(drill 0.254)
		(layers "F.Cu" "B.Cu")
		(net "GND")
	)
	(via
		(at 43.58513 -175.114966)
		(size 0.508)
		(drill 0.254)
		(layers "F.Cu" "B.Cu")
		(net "GND")
	)
	(via
		(at 127 -320.04)
		(size 0.508)
		(drill 0.254)
		(layers "F.Cu" "B.Cu")
		(net "GND")
	)
	(via
		(at 5.073396 -493.768126)
		(size 0.508)
		(drill 0.254)
		(layers "F.Cu" "B.Cu")
		(net "GND")
	)
	(via
		(at 121.92 -436.88)
		(size 0.508)
		(drill 0.254)
		(layers "F.Cu" "B.Cu")
		(net "GND")
	)
	(via
		(at 45.72 -157.48)
		(size 0.508)
		(drill 0.254)
		(layers "F.Cu" "B.Cu")
		(net "GND")
	)
	(via
		(at 167.64 -147.32)
		(size 0.508)
		(drill 0.254)
		(layers "F.Cu" "B.Cu")
		(net "GND")
	)
	(via
		(at 116.84 -50.8)
		(size 0.508)
		(drill 0.254)
		(layers "F.Cu" "B.Cu")
		(net "GND")
	)
	(via
		(at 147.32 -71.12)
		(size 0.508)
		(drill 0.254)
		(layers "F.Cu" "B.Cu")
		(net "GND")
	)
	(via
		(at 6.223 -218.760802)
		(size 0.508)
		(drill 0.254)
		(layers "F.Cu" "B.Cu")
		(net "GND")
	)
	(via
		(at 111.76 -330.2)
		(size 0.508)
		(drill 0.254)
		(layers "F.Cu" "B.Cu")
		(net "GND")
	)
	(via
		(at 228.6 -20.32)
		(size 0.508)
		(drill 0.254)
		(layers "F.Cu" "B.Cu")
		(net "GND")
	)
	(via
		(at 243.84 -96.52)
		(size 0.508)
		(drill 0.254)
		(layers "F.Cu" "B.Cu")
		(net "GND")
	)
	(via
		(at 203.2 -441.96)
		(size 0.508)
		(drill 0.254)
		(layers "F.Cu" "B.Cu")
		(net "GND")
	)
	(via
		(at 193.04 -71.12)
		(size 0.508)
		(drill 0.254)
		(layers "F.Cu" "B.Cu")
		(net "GND")
	)
	(via
		(at 101.6 -497.84)
		(size 0.508)
		(drill 0.254)
		(layers "F.Cu" "B.Cu")
		(net "GND")
	)
	(via
		(at 26.2382 -501.4214)
		(size 0.508)
		(drill 0.254)
		(layers "F.Cu" "B.Cu")
		(net "GND")
	)
	(via
		(at 8.123174 -449.154042)
		(size 0.508)
		(drill 0.254)
		(layers "F.Cu" "B.Cu")
		(net "GND")
	)
	(via
		(at 65.786 -432.435)
		(size 0.508)
		(drill 0.254)
		(layers "F.Cu" "B.Cu")
		(net "GND")
	)
	(via
		(at 96.0374 -20.701)
		(size 0.508)
		(drill 0.254)
		(layers "F.Cu" "B.Cu")
		(net "GND")
	)
	(via
		(at 37.0332 -187.2234)
		(size 0.508)
		(drill 0.254)
		(layers "F.Cu" "B.Cu")
		(net "GND")
	)
	(via
		(at 45.72 -248.92)
		(size 0.508)
		(drill 0.254)
		(layers "F.Cu" "B.Cu")
		(net "GND")
	)
	(via
		(at 6.223 -155.511246)
		(size 0.508)
		(drill 0.254)
		(layers "F.Cu" "B.Cu")
		(net "GND")
	)
	(via
		(at 66.04 -76.2)
		(size 0.508)
		(drill 0.254)
		(layers "F.Cu" "B.Cu")
		(net "GND")
	)
	(via
		(at 116.84 -421.64)
		(size 0.508)
		(drill 0.254)
		(layers "F.Cu" "B.Cu")
		(net "GND")
	)
	(via
		(at 132.08 -55.88)
		(size 0.508)
		(drill 0.254)
		(layers "F.Cu" "B.Cu")
		(net "GND")
	)
	(via
		(at 248.92 -314.96)
		(size 0.508)
		(drill 0.254)
		(layers "F.Cu" "B.Cu")
		(net "GND")
	)
	(via
		(at 248.92 -452.12)
		(size 0.508)
		(drill 0.254)
		(layers "F.Cu" "B.Cu")
		(net "GND")
	)
	(via
		(at 27.664918 -39.871904)
		(size 0.508)
		(drill 0.254)
		(layers "F.Cu" "B.Cu")
		(net "GND")
	)
	(via
		(at 207.42275 -401.1295)
		(size 0.508)
		(drill 0.254)
		(layers "F.Cu" "B.Cu")
		(net "GND")
	)
	(via
		(at 45.72 -360.68)
		(size 0.508)
		(drill 0.254)
		(layers "F.Cu" "B.Cu")
		(net "GND")
	)
	(via
		(at 34.27349 -377.479052)
		(size 0.508)
		(drill 0.254)
		(layers "F.Cu" "B.Cu")
		(net "GND")
	)
	(via
		(at 121.92 -462.28)
		(size 0.508)
		(drill 0.254)
		(layers "F.Cu" "B.Cu")
		(net "GND")
	)
	(via
		(at 237.49 -405.13)
		(size 0.7112)
		(drill 0.4064)
		(layers "F.Cu" "B.Cu")
		(net "GND")
	)
	(via
		(at 177.8 -40.64)
		(size 0.508)
		(drill 0.254)
		(layers "F.Cu" "B.Cu")
		(net "GND")
	)
	(via
		(at 35.2552 -402.6154)
		(size 0.508)
		(drill 0.254)
		(layers "F.Cu" "B.Cu")
		(net "GND")
	)
	(via
		(at 213.36 -406.4)
		(size 0.508)
		(drill 0.254)
		(layers "F.Cu" "B.Cu")
		(net "GND")
	)
	(via
		(at 208.28 -167.64)
		(size 0.508)
		(drill 0.254)
		(layers "F.Cu" "B.Cu")
		(net "GND")
	)
	(via
		(at 68.961 -455.93)
		(size 0.508)
		(drill 0.254)
		(layers "F.Cu" "B.Cu")
		(net "GND")
	)
	(via
		(at 101.6 -391.16)
		(size 0.508)
		(drill 0.254)
		(layers "F.Cu" "B.Cu")
		(net "GND")
	)
	(via
		(at 222.616014 -470.590118)
		(size 0.508)
		(drill 0.254)
		(layers "F.Cu" "B.Cu")
		(net "GND")
	)
	(via
		(at 259.08 -299.72)
		(size 0.508)
		(drill 0.254)
		(layers "F.Cu" "B.Cu")
		(net "GND")
	)
	(via
		(at 101.6 -472.44)
		(size 0.508)
		(drill 0.254)
		(layers "F.Cu" "B.Cu")
		(net "GND")
	)
	(via
		(at 31.496 -134.511542)
		(size 0.508)
		(drill 0.254)
		(layers "F.Cu" "B.Cu")
		(net "GND")
	)
	(via
		(at 21.1328 -195.1482)
		(size 0.508)
		(drill 0.254)
		(layers "F.Cu" "B.Cu")
		(net "GND")
	)
	(via
		(at 17.145 -340.518496)
		(size 0.508)
		(drill 0.254)
		(layers "F.Cu" "B.Cu")
		(net "GND")
	)
	(via
		(at 177.8 -330.2)
		(size 0.508)
		(drill 0.254)
		(layers "F.Cu" "B.Cu")
		(net "GND")
	)
	(via
		(at 93.98 -102.997)
		(size 0.508)
		(drill 0.254)
		(layers "F.Cu" "B.Cu")
		(net "GND")
	)
	(via
		(at 262.103108 -239.678464)
		(size 0.508)
		(drill 0.254)
		(layers "F.Cu" "B.Cu")
		(net "GND")
	)
	(via
		(at 96.774 -434.594)
		(size 0.508)
		(drill 0.254)
		(layers "F.Cu" "B.Cu")
		(net "GND")
	)
	(via
		(at 127 -284.48)
		(size 0.508)
		(drill 0.254)
		(layers "F.Cu" "B.Cu")
		(net "GND")
	)
	(via
		(at 127 -431.8)
		(size 0.508)
		(drill 0.254)
		(layers "F.Cu" "B.Cu")
		(net "GND")
	)
	(via
		(at 203.2 -157.48)
		(size 0.508)
		(drill 0.254)
		(layers "F.Cu" "B.Cu")
		(net "GND")
	)
	(via
		(at 66.04 -502.92)
		(size 0.508)
		(drill 0.254)
		(layers "F.Cu" "B.Cu")
		(net "GND")
	)
	(via
		(at 157.48 -472.44)
		(size 0.508)
		(drill 0.254)
		(layers "F.Cu" "B.Cu")
		(net "GND")
	)
	(via
		(at 71.12 -218.44)
		(size 0.508)
		(drill 0.254)
		(layers "F.Cu" "B.Cu")
		(net "GND")
	)
	(via
		(at 167.64 -304.8)
		(size 0.508)
		(drill 0.254)
		(layers "F.Cu" "B.Cu")
		(net "GND")
	)
	(via
		(at 220.599 -269.113)
		(size 0.508)
		(drill 0.254)
		(layers "F.Cu" "B.Cu")
		(net "GND")
	)
	(via
		(at 157.48 -457.2)
		(size 0.508)
		(drill 0.254)
		(layers "F.Cu" "B.Cu")
		(net "GND")
	)
	(via
		(at 208.28 -350.52)
		(size 0.508)
		(drill 0.254)
		(layers "F.Cu" "B.Cu")
		(net "GND")
	)
	(via
		(at 4.191 -217.090244)
		(size 0.508)
		(drill 0.254)
		(layers "F.Cu" "B.Cu")
		(net "GND")
	)
	(via
		(at 187.96 -137.16)
		(size 0.508)
		(drill 0.254)
		(layers "F.Cu" "B.Cu")
		(net "GND")
	)
	(via
		(at 106.68 -487.68)
		(size 0.508)
		(drill 0.254)
		(layers "F.Cu" "B.Cu")
		(net "GND")
	)
	(via
		(at 218.44 -116.84)
		(size 0.508)
		(drill 0.254)
		(layers "F.Cu" "B.Cu")
		(net "GND")
	)
	(via
		(at 222.616014 -485.789986)
		(size 0.508)
		(drill 0.254)
		(layers "F.Cu" "B.Cu")
		(net "GND")
	)
	(via
		(at 167.64 -15.24)
		(size 0.508)
		(drill 0.254)
		(layers "F.Cu" "B.Cu")
		(net "GND")
	)
	(via
		(at 111.76 -375.92)
		(size 0.508)
		(drill 0.254)
		(layers "F.Cu" "B.Cu")
		(net "GND")
	)
	(via
		(at 203.2 -30.48)
		(size 0.508)
		(drill 0.254)
		(layers "F.Cu" "B.Cu")
		(net "GND")
	)
	(via
		(at 142.24 -269.24)
		(size 0.508)
		(drill 0.254)
		(layers "F.Cu" "B.Cu")
		(net "GND")
	)
	(via
		(at 203.2 -15.24)
		(size 0.508)
		(drill 0.254)
		(layers "F.Cu" "B.Cu")
		(net "GND")
	)
	(via
		(at 193.04 -5.08)
		(size 0.508)
		(drill 0.254)
		(layers "F.Cu" "B.Cu")
		(net "GND")
	)
	(via
		(at 91.186 -434.594)
		(size 0.508)
		(drill 0.254)
		(layers "F.Cu" "B.Cu")
		(net "GND")
	)
	(via
		(at 50.8 -426.72)
		(size 0.508)
		(drill 0.254)
		(layers "F.Cu" "B.Cu")
		(net "GND")
	)
	(via
		(at 213.36 -137.16)
		(size 0.508)
		(drill 0.254)
		(layers "F.Cu" "B.Cu")
		(net "GND")
	)
	(via
		(at 37.61613 -264.590022)
		(size 0.508)
		(drill 0.254)
		(layers "F.Cu" "B.Cu")
		(net "GND")
	)
	(via
		(at 223.52 -5.08)
		(size 0.508)
		(drill 0.254)
		(layers "F.Cu" "B.Cu")
		(net "GND")
	)
	(via
		(at 228.585014 -70.844918)
		(size 0.508)
		(drill 0.254)
		(layers "F.Cu" "B.Cu")
		(net "GND")
	)
	(via
		(at 24.384 -116.009928)
		(size 0.508)
		(drill 0.254)
		(layers "F.Cu" "B.Cu")
		(net "GND")
	)
	(via
		(at 221.71025 -135.95985)
		(size 0.508)
		(drill 0.254)
		(layers "F.Cu" "B.Cu")
		(net "GND")
	)
	(via
		(at 116.84 -132.08)
		(size 0.508)
		(drill 0.254)
		(layers "F.Cu" "B.Cu")
		(net "GND")
	)
	(via
		(at 228.585014 -482.84511)
		(size 0.508)
		(drill 0.254)
		(layers "F.Cu" "B.Cu")
		(net "GND")
	)
	(via
		(at 223.52 -314.96)
		(size 0.508)
		(drill 0.254)
		(layers "F.Cu" "B.Cu")
		(net "GND")
	)
	(via
		(at 66.04 -238.76)
		(size 0.508)
		(drill 0.254)
		(layers "F.Cu" "B.Cu")
		(net "GND")
	)
	(via
		(at 71.12 -157.48)
		(size 0.508)
		(drill 0.254)
		(layers "F.Cu" "B.Cu")
		(net "GND")
	)
	(via
		(at 116.84 -76.2)
		(size 0.508)
		(drill 0.254)
		(layers "F.Cu" "B.Cu")
		(net "GND")
	)
	(via
		(at 50.8 -340.36)
		(size 0.508)
		(drill 0.254)
		(layers "F.Cu" "B.Cu")
		(net "GND")
	)
	(via
		(at 213.36 -325.12)
		(size 0.508)
		(drill 0.254)
		(layers "F.Cu" "B.Cu")
		(net "GND")
	)
	(via
		(at 106.68 -294.64)
		(size 0.508)
		(drill 0.254)
		(layers "F.Cu" "B.Cu")
		(net "GND")
	)
	(via
		(at 132.08 -50.8)
		(size 0.508)
		(drill 0.254)
		(layers "F.Cu" "B.Cu")
		(net "GND")
	)
	(via
		(at 6.223 -413.194246)
		(size 0.508)
		(drill 0.254)
		(layers "F.Cu" "B.Cu")
		(net "GND")
	)
	(via
		(at 248.92 -50.8)
		(size 0.508)
		(drill 0.254)
		(layers "F.Cu" "B.Cu")
		(net "GND")
	)
	(via
		(at 27.432 -309.118)
		(size 0.508)
		(drill 0.254)
		(layers "F.Cu" "B.Cu")
		(net "GND")
	)
	(via
		(at 187.96 -213.36)
		(size 0.508)
		(drill 0.254)
		(layers "F.Cu" "B.Cu")
		(net "GND")
	)
	(via
		(at 245.11 -405.13)
		(size 0.7112)
		(drill 0.4064)
		(layers "F.Cu" "B.Cu")
		(net "GND")
	)
	(via
		(at 228.6 -264.16)
		(size 0.508)
		(drill 0.254)
		(layers "F.Cu" "B.Cu")
		(net "GND")
	)
	(via
		(at 127 -345.44)
		(size 0.508)
		(drill 0.254)
		(layers "F.Cu" "B.Cu")
		(net "GND")
	)
	(via
		(at 91.186 -429.006)
		(size 0.508)
		(drill 0.254)
		(layers "F.Cu" "B.Cu")
		(net "GND")
	)
	(via
		(at 228.585014 -55.604918)
		(size 0.508)
		(drill 0.254)
		(layers "F.Cu" "B.Cu")
		(net "GND")
	)
	(via
		(at 254 -304.8)
		(size 0.508)
		(drill 0.254)
		(layers "F.Cu" "B.Cu")
		(net "GND")
	)
	(via
		(at 132.08 -96.52)
		(size 0.508)
		(drill 0.254)
		(layers "F.Cu" "B.Cu")
		(net "GND")
	)
	(via
		(at 152.4 -472.44)
		(size 0.508)
		(drill 0.254)
		(layers "F.Cu" "B.Cu")
		(net "GND")
	)
	(via
		(at 106.68 -137.16)
		(size 0.508)
		(drill 0.254)
		(layers "F.Cu" "B.Cu")
		(net "GND")
	)
	(via
		(at 26.416 -340.614)
		(size 0.508)
		(drill 0.254)
		(layers "F.Cu" "B.Cu")
		(net "GND")
	)
	(via
		(at 219.314014 -466.1281)
		(size 0.508)
		(drill 0.254)
		(layers "F.Cu" "B.Cu")
		(net "GND")
	)
	(via
		(at 34.26333 -485.3051)
		(size 0.508)
		(drill 0.254)
		(layers "F.Cu" "B.Cu")
		(net "GND")
	)
	(via
		(at 5.08 -502.92)
		(size 0.508)
		(drill 0.254)
		(layers "F.Cu" "B.Cu")
		(net "GND")
	)
	(via
		(at 100.838 -97.4725)
		(size 0.508)
		(drill 0.254)
		(layers "F.Cu" "B.Cu")
		(net "GND")
	)
	(via
		(at 238.76 -304.8)
		(size 0.508)
		(drill 0.254)
		(layers "F.Cu" "B.Cu")
		(net "GND")
	)
	(via
		(at 233.68 -314.96)
		(size 0.508)
		(drill 0.254)
		(layers "F.Cu" "B.Cu")
		(net "GND")
	)
	(via
		(at 27.686 -22.218904)
		(size 0.508)
		(drill 0.254)
		(layers "F.Cu" "B.Cu")
		(net "GND")
	)
	(via
		(at 4.191 -205.966314)
		(size 0.508)
		(drill 0.254)
		(layers "F.Cu" "B.Cu")
		(net "GND")
	)
	(via
		(at 91.186 -433.197)
		(size 0.508)
		(drill 0.254)
		(layers "F.Cu" "B.Cu")
		(net "GND")
	)
	(via
		(at 152.4 -162.56)
		(size 0.508)
		(drill 0.254)
		(layers "F.Cu" "B.Cu")
		(net "GND")
	)
	(via
		(at 137.16 -228.6)
		(size 0.508)
		(drill 0.254)
		(layers "F.Cu" "B.Cu")
		(net "GND")
	)
	(via
		(at 238.76 -320.04)
		(size 0.508)
		(drill 0.254)
		(layers "F.Cu" "B.Cu")
		(net "GND")
	)
	(via
		(at 152.4 -50.8)
		(size 0.508)
		(drill 0.254)
		(layers "F.Cu" "B.Cu")
		(net "GND")
	)
	(via
		(at 1.397 -10.409428)
		(size 0.508)
		(drill 0.254)
		(layers "F.Cu" "B.Cu")
		(net "GND")
	)
	(via
		(at 137.16 -238.76)
		(size 0.508)
		(drill 0.254)
		(layers "F.Cu" "B.Cu")
		(net "GND")
	)
	(via
		(at 95.377 -213.614)
		(size 0.508)
		(drill 0.254)
		(layers "F.Cu" "B.Cu")
		(net "GND")
	)
	(via
		(at 203.2 -340.36)
		(size 0.508)
		(drill 0.254)
		(layers "F.Cu" "B.Cu")
		(net "GND")
	)
	(via
		(at 24.384 -125.609858)
		(size 0.508)
		(drill 0.254)
		(layers "F.Cu" "B.Cu")
		(net "GND")
	)
	(via
		(at 76.2 -284.48)
		(size 0.508)
		(drill 0.254)
		(layers "F.Cu" "B.Cu")
		(net "GND")
	)
	(via
		(at 111.76 -5.08)
		(size 0.508)
		(drill 0.254)
		(layers "F.Cu" "B.Cu")
		(net "GND")
	)
	(via
		(at 9.245854 -386.492242)
		(size 0.508)
		(drill 0.254)
		(layers "F.Cu" "B.Cu")
		(net "GND")
	)
	(via
		(at 96.52 -274.32)
		(size 0.508)
		(drill 0.254)
		(layers "F.Cu" "B.Cu")
		(net "GND")
	)
	(via
		(at 213.36 -127)
		(size 0.508)
		(drill 0.254)
		(layers "F.Cu" "B.Cu")
		(net "GND")
	)
	(via
		(at 129.544572 -1.397)
		(size 0.508)
		(drill 0.254)
		(layers "F.Cu" "B.Cu")
		(net "GND")
	)
	(via
		(at 248.92 -350.52)
		(size 0.508)
		(drill 0.254)
		(layers "F.Cu" "B.Cu")
		(net "GND")
	)
	(via
		(at 213.36 -345.44)
		(size 0.508)
		(drill 0.254)
		(layers "F.Cu" "B.Cu")
		(net "GND")
	)
	(via
		(at 86.36 -487.68)
		(size 0.508)
		(drill 0.254)
		(layers "F.Cu" "B.Cu")
		(net "GND")
	)
	(via
		(at 60.96 -370.84)
		(size 0.508)
		(drill 0.254)
		(layers "F.Cu" "B.Cu")
		(net "GND")
	)
	(via
		(at 4.191 -157.16631)
		(size 0.508)
		(drill 0.254)
		(layers "F.Cu" "B.Cu")
		(net "GND")
	)
	(via
		(at 222.616014 -181.589934)
		(size 0.508)
		(drill 0.254)
		(layers "F.Cu" "B.Cu")
		(net "GND")
	)
	(via
		(at 81.28 -10.16)
		(size 0.508)
		(drill 0.254)
		(layers "F.Cu" "B.Cu")
		(net "GND")
	)
	(via
		(at 4.191 -174.690278)
		(size 0.508)
		(drill 0.254)
		(layers "F.Cu" "B.Cu")
		(net "GND")
	)
	(via
		(at 177.8 -106.68)
		(size 0.508)
		(drill 0.254)
		(layers "F.Cu" "B.Cu")
		(net "GND")
	)
	(via
		(at 4.191 -442.812424)
		(size 0.508)
		(drill 0.254)
		(layers "F.Cu" "B.Cu")
		(net "GND")
	)
	(via
		(at 132.08 -426.72)
		(size 0.508)
		(drill 0.254)
		(layers "F.Cu" "B.Cu")
		(net "GND")
	)
	(via
		(at 55.88 -259.08)
		(size 0.508)
		(drill 0.254)
		(layers "F.Cu" "B.Cu")
		(net "GND")
	)
	(via
		(at 152.4 -132.08)
		(size 0.508)
		(drill 0.254)
		(layers "F.Cu" "B.Cu")
		(net "GND")
	)
	(via
		(at 66.04 -106.68)
		(size 0.508)
		(drill 0.254)
		(layers "F.Cu" "B.Cu")
		(net "GND")
	)
	(via
		(at 218.44 -233.68)
		(size 0.508)
		(drill 0.254)
		(layers "F.Cu" "B.Cu")
		(net "GND")
	)
	(via
		(at 209.1436 -501.2436)
		(size 0.508)
		(drill 0.254)
		(layers "F.Cu" "B.Cu")
		(net "GND")
	)
	(via
		(at 4.445 -458.9526)
		(size 0.7112)
		(drill 0.4064)
		(layers "F.Cu" "B.Cu")
		(net "GND")
	)
	(via
		(at 254 -320.04)
		(size 0.508)
		(drill 0.254)
		(layers "F.Cu" "B.Cu")
		(net "GND")
	)
	(via
		(at 35.56 -111.76)
		(size 0.508)
		(drill 0.254)
		(layers "F.Cu" "B.Cu")
		(net "GND")
	)
	(via
		(at 254 -350.52)
		(size 0.508)
		(drill 0.254)
		(layers "F.Cu" "B.Cu")
		(net "GND")
	)
	(via
		(at 101.6 -10.16)
		(size 0.508)
		(drill 0.254)
		(layers "F.Cu" "B.Cu")
		(net "GND")
	)
	(via
		(at 162.56 -421.64)
		(size 0.508)
		(drill 0.254)
		(layers "F.Cu" "B.Cu")
		(net "GND")
	)
	(via
		(at 132.08 -81.28)
		(size 0.508)
		(drill 0.254)
		(layers "F.Cu" "B.Cu")
		(net "GND")
	)
	(via
		(at 18.415 -34.584894)
		(size 0.508)
		(drill 0.254)
		(layers "F.Cu" "B.Cu")
		(net "GND")
	)
	(via
		(at 132.08 -355.6)
		(size 0.508)
		(drill 0.254)
		(layers "F.Cu" "B.Cu")
		(net "GND")
	)
	(via
		(at 218.44 -218.44)
		(size 0.508)
		(drill 0.254)
		(layers "F.Cu" "B.Cu")
		(net "GND")
	)
	(via
		(at 147.32 -96.52)
		(size 0.508)
		(drill 0.254)
		(layers "F.Cu" "B.Cu")
		(net "GND")
	)
	(via
		(at 147.32 -381)
		(size 0.508)
		(drill 0.254)
		(layers "F.Cu" "B.Cu")
		(net "GND")
	)
	(via
		(at 116.84 -81.28)
		(size 0.508)
		(drill 0.254)
		(layers "F.Cu" "B.Cu")
		(net "GND")
	)
	(via
		(at 218.44 -5.08)
		(size 0.508)
		(drill 0.254)
		(layers "F.Cu" "B.Cu")
		(net "GND")
	)
	(via
		(at 259.08 -457.2)
		(size 0.508)
		(drill 0.254)
		(layers "F.Cu" "B.Cu")
		(net "GND")
	)
	(via
		(at 24.384 -137.033)
		(size 0.508)
		(drill 0.254)
		(layers "F.Cu" "B.Cu")
		(net "GND")
	)
	(via
		(at 31.75 -443.492636)
		(size 0.508)
		(drill 0.254)
		(layers "F.Cu" "B.Cu")
		(net "GND")
	)
	(via
		(at 27.686 -347.147896)
		(size 0.508)
		(drill 0.254)
		(layers "F.Cu" "B.Cu")
		(net "GND")
	)
	(via
		(at 238.76 -203.2)
		(size 0.508)
		(drill 0.254)
		(layers "F.Cu" "B.Cu")
		(net "GND")
	)
	(via
		(at 172.72 -5.08)
		(size 0.508)
		(drill 0.254)
		(layers "F.Cu" "B.Cu")
		(net "GND")
	)
	(via
		(at 172.72 -223.52)
		(size 0.508)
		(drill 0.254)
		(layers "F.Cu" "B.Cu")
		(net "GND")
	)
	(via
		(at 27.4574 -206.0702)
		(size 0.508)
		(drill 0.254)
		(layers "F.Cu" "B.Cu")
		(net "GND")
	)
	(via
		(at 49.3268 -250.4186)
		(size 0.508)
		(drill 0.254)
		(layers "F.Cu" "B.Cu")
		(net "GND")
	)
	(via
		(at 198.12 -248.92)
		(size 0.508)
		(drill 0.254)
		(layers "F.Cu" "B.Cu")
		(net "GND")
	)
	(via
		(at 243.84 -309.88)
		(size 0.508)
		(drill 0.254)
		(layers "F.Cu" "B.Cu")
		(net "GND")
	)
	(via
		(at 91.44 -264.16)
		(size 0.508)
		(drill 0.254)
		(layers "F.Cu" "B.Cu")
		(net "GND")
	)
	(via
		(at 233.68 -20.32)
		(size 0.508)
		(drill 0.254)
		(layers "F.Cu" "B.Cu")
		(net "GND")
	)
	(via
		(at 182.88 -284.48)
		(size 0.508)
		(drill 0.254)
		(layers "F.Cu" "B.Cu")
		(net "GND")
	)
	(via
		(at 182.88 -187.96)
		(size 0.508)
		(drill 0.254)
		(layers "F.Cu" "B.Cu")
		(net "GND")
	)
	(via
		(at 6.223 -300.674532)
		(size 0.508)
		(drill 0.254)
		(layers "F.Cu" "B.Cu")
		(net "GND")
	)
	(via
		(at 219.71 -94.234)
		(size 0.508)
		(drill 0.254)
		(layers "F.Cu" "B.Cu")
		(net "GND")
	)
	(via
		(at 213.36 -10.16)
		(size 0.508)
		(drill 0.254)
		(layers "F.Cu" "B.Cu")
		(net "GND")
	)
	(via
		(at 127 -71.12)
		(size 0.508)
		(drill 0.254)
		(layers "F.Cu" "B.Cu")
		(net "GND")
	)
	(via
		(at 172.72 -142.24)
		(size 0.508)
		(drill 0.254)
		(layers "F.Cu" "B.Cu")
		(net "GND")
	)
	(via
		(at 24.7396 -93.1164)
		(size 0.508)
		(drill 0.254)
		(layers "F.Cu" "B.Cu")
		(net "GND")
	)
	(via
		(at 33.401 -290.3728)
		(size 0.508)
		(drill 0.254)
		(layers "F.Cu" "B.Cu")
		(net "GND")
	)
	(via
		(at 186.069986 -504.603004)
		(size 0.508)
		(drill 0.254)
		(layers "F.Cu" "B.Cu")
		(net "GND")
	)
	(via
		(at 55.88 -172.72)
		(size 0.508)
		(drill 0.254)
		(layers "F.Cu" "B.Cu")
		(net "GND")
	)
	(via
		(at 132.08 -467.36)
		(size 0.508)
		(drill 0.254)
		(layers "F.Cu" "B.Cu")
		(net "GND")
	)
	(via
		(at 71.12 -467.36)
		(size 0.508)
		(drill 0.254)
		(layers "F.Cu" "B.Cu")
		(net "GND")
	)
	(via
		(at 223.52 -147.32)
		(size 0.508)
		(drill 0.254)
		(layers "F.Cu" "B.Cu")
		(net "GND")
	)
	(via
		(at 76.2 -497.84)
		(size 0.508)
		(drill 0.254)
		(layers "F.Cu" "B.Cu")
		(net "GND")
	)
	(via
		(at 233.68 -152.4)
		(size 0.508)
		(drill 0.254)
		(layers "F.Cu" "B.Cu")
		(net "GND")
	)
	(via
		(at 86.36 -294.64)
		(size 0.508)
		(drill 0.254)
		(layers "F.Cu" "B.Cu")
		(net "GND")
	)
	(via
		(at 177.8 -76.2)
		(size 0.508)
		(drill 0.254)
		(layers "F.Cu" "B.Cu")
		(net "GND")
	)
	(via
		(at 4.191 -425.958)
		(size 0.508)
		(drill 0.254)
		(layers "F.Cu" "B.Cu")
		(net "GND")
	)
	(via
		(at 6.223 -186.011566)
		(size 0.508)
		(drill 0.254)
		(layers "F.Cu" "B.Cu")
		(net "GND")
	)
	(via
		(at 60.96 -502.92)
		(size 0.508)
		(drill 0.254)
		(layers "F.Cu" "B.Cu")
		(net "GND")
	)
	(via
		(at 259.08 -198.12)
		(size 0.508)
		(drill 0.254)
		(layers "F.Cu" "B.Cu")
		(net "GND")
	)
	(via
		(at 6.223 -352.674682)
		(size 0.508)
		(drill 0.254)
		(layers "F.Cu" "B.Cu")
		(net "GND")
	)
	(via
		(at 106.68 -187.96)
		(size 0.508)
		(drill 0.254)
		(layers "F.Cu" "B.Cu")
		(net "GND")
	)
	(via
		(at 121.92 -193.04)
		(size 0.508)
		(drill 0.254)
		(layers "F.Cu" "B.Cu")
		(net "GND")
	)
	(via
		(at 19.55165 -473.456)
		(size 0.508)
		(drill 0.254)
		(layers "F.Cu" "B.Cu")
		(net "GND")
	)
	(via
		(at 4.191 -316.921134)
		(size 0.508)
		(drill 0.254)
		(layers "F.Cu" "B.Cu")
		(net "GND")
	)
	(via
		(at 187.96 -314.96)
		(size 0.508)
		(drill 0.254)
		(layers "F.Cu" "B.Cu")
		(net "GND")
	)
	(via
		(at 238.76 -482.6)
		(size 0.508)
		(drill 0.254)
		(layers "F.Cu" "B.Cu")
		(net "GND")
	)
	(via
		(at 43.58513 -261.605014)
		(size 0.508)
		(drill 0.254)
		(layers "F.Cu" "B.Cu")
		(net "GND")
	)
	(via
		(at 32.236664 -367.630456)
		(size 0.508)
		(drill 0.254)
		(layers "F.Cu" "B.Cu")
		(net "GND")
	)
	(via
		(at 137.16 -386.08)
		(size 0.508)
		(drill 0.254)
		(layers "F.Cu" "B.Cu")
		(net "GND")
	)
	(via
		(at 203.2 -325.12)
		(size 0.508)
		(drill 0.254)
		(layers "F.Cu" "B.Cu")
		(net "GND")
	)
	(via
		(at 10.287 -408.559)
		(size 0.508)
		(drill 0.254)
		(layers "F.Cu" "B.Cu")
		(net "GND")
	)
	(via
		(at 147.32 -142.24)
		(size 0.508)
		(drill 0.254)
		(layers "F.Cu" "B.Cu")
		(net "GND")
	)
	(via
		(at 218.44 -10.16)
		(size 0.508)
		(drill 0.254)
		(layers "F.Cu" "B.Cu")
		(net "GND")
	)
	(via
		(at 94.615 -423.418)
		(size 0.508)
		(drill 0.254)
		(layers "F.Cu" "B.Cu")
		(net "GND")
	)
	(via
		(at 167.64 -487.68)
		(size 0.508)
		(drill 0.254)
		(layers "F.Cu" "B.Cu")
		(net "GND")
	)
	(via
		(at 24.384 -429.810164)
		(size 0.508)
		(drill 0.254)
		(layers "F.Cu" "B.Cu")
		(net "GND")
	)
	(via
		(at 228.585014 -162.414966)
		(size 0.508)
		(drill 0.254)
		(layers "F.Cu" "B.Cu")
		(net "GND")
	)
	(via
		(at 254 -325.12)
		(size 0.508)
		(drill 0.254)
		(layers "F.Cu" "B.Cu")
		(net "GND")
	)
	(via
		(at 23.7744 -469.4428)
		(size 0.508)
		(drill 0.254)
		(layers "F.Cu" "B.Cu")
		(net "GND")
	)
	(via
		(at 45.72 -477.52)
		(size 0.508)
		(drill 0.254)
		(layers "F.Cu" "B.Cu")
		(net "GND")
	)
	(via
		(at 98.350832 -318.061848)
		(size 0.508)
		(drill 0.254)
		(layers "F.Cu" "B.Cu")
		(net "GND")
	)
	(via
		(at 6.223 -403.594316)
		(size 0.508)
		(drill 0.254)
		(layers "F.Cu" "B.Cu")
		(net "GND")
	)
	(via
		(at 233.68 -25.4)
		(size 0.508)
		(drill 0.254)
		(layers "F.Cu" "B.Cu")
		(net "GND")
	)
	(via
		(at 132.08 -243.84)
		(size 0.508)
		(drill 0.254)
		(layers "F.Cu" "B.Cu")
		(net "GND")
	)
	(via
		(at 27.697176 -120.392952)
		(size 0.508)
		(drill 0.254)
		(layers "F.Cu" "B.Cu")
		(net "GND")
	)
	(via
		(at 222.616014 -382.789938)
		(size 0.508)
		(drill 0.254)
		(layers "F.Cu" "B.Cu")
		(net "GND")
	)
	(via
		(at 243.84 -172.72)
		(size 0.508)
		(drill 0.254)
		(layers "F.Cu" "B.Cu")
		(net "GND")
	)
	(via
		(at 254 -193.04)
		(size 0.508)
		(drill 0.254)
		(layers "F.Cu" "B.Cu")
		(net "GND")
	)
	(via
		(at 177.8 -208.28)
		(size 0.508)
		(drill 0.254)
		(layers "F.Cu" "B.Cu")
		(net "GND")
	)
	(via
		(at 223.52 -25.4)
		(size 0.508)
		(drill 0.254)
		(layers "F.Cu" "B.Cu")
		(net "GND")
	)
	(via
		(at 137.16 -81.28)
		(size 0.508)
		(drill 0.254)
		(layers "F.Cu" "B.Cu")
		(net "GND")
	)
	(via
		(at 208.28 -132.08)
		(size 0.508)
		(drill 0.254)
		(layers "F.Cu" "B.Cu")
		(net "GND")
	)
	(via
		(at 71.12 -406.4)
		(size 0.508)
		(drill 0.254)
		(layers "F.Cu" "B.Cu")
		(net "GND")
	)
	(via
		(at 234.4166 -267.7668)
		(size 0.508)
		(drill 0.254)
		(layers "F.Cu" "B.Cu")
		(net "GND")
	)
	(via
		(at 121.92 -350.52)
		(size 0.508)
		(drill 0.254)
		(layers "F.Cu" "B.Cu")
		(net "GND")
	)
	(via
		(at 50.8 -132.08)
		(size 0.508)
		(drill 0.254)
		(layers "F.Cu" "B.Cu")
		(net "GND")
	)
	(via
		(at 182.88 -111.76)
		(size 0.508)
		(drill 0.254)
		(layers "F.Cu" "B.Cu")
		(net "GND")
	)
	(via
		(at 152.4 -193.04)
		(size 0.508)
		(drill 0.254)
		(layers "F.Cu" "B.Cu")
		(net "GND")
	)
	(via
		(at 24.384 -17.809972)
		(size 0.508)
		(drill 0.254)
		(layers "F.Cu" "B.Cu")
		(net "GND")
	)
	(via
		(at 116.84 -386.08)
		(size 0.508)
		(drill 0.254)
		(layers "F.Cu" "B.Cu")
		(net "GND")
	)
	(via
		(at 228.6 -111.76)
		(size 0.508)
		(drill 0.254)
		(layers "F.Cu" "B.Cu")
		(net "GND")
	)
	(via
		(at 8.053578 -275.844)
		(size 0.508)
		(drill 0.254)
		(layers "F.Cu" "B.Cu")
		(net "GND")
	)
	(via
		(at 213.36 -25.4)
		(size 0.508)
		(drill 0.254)
		(layers "F.Cu" "B.Cu")
		(net "GND")
	)
	(via
		(at 152.4 -426.72)
		(size 0.508)
		(drill 0.254)
		(layers "F.Cu" "B.Cu")
		(net "GND")
	)
	(via
		(at 24.384 -331.609954)
		(size 0.508)
		(drill 0.254)
		(layers "F.Cu" "B.Cu")
		(net "GND")
	)
	(via
		(at 142.24 -142.24)
		(size 0.508)
		(drill 0.254)
		(layers "F.Cu" "B.Cu")
		(net "GND")
	)
	(via
		(at 162.56 -314.96)
		(size 0.508)
		(drill 0.254)
		(layers "F.Cu" "B.Cu")
		(net "GND")
	)
	(via
		(at 222.504 -94.234)
		(size 0.508)
		(drill 0.254)
		(layers "F.Cu" "B.Cu")
		(net "GND")
	)
	(via
		(at 213.36 -228.6)
		(size 0.508)
		(drill 0.254)
		(layers "F.Cu" "B.Cu")
		(net "GND")
	)
	(via
		(at 34.31413 -277.781004)
		(size 0.508)
		(drill 0.254)
		(layers "F.Cu" "B.Cu")
		(net "GND")
	)
	(via
		(at 259.08 -228.6)
		(size 0.508)
		(drill 0.254)
		(layers "F.Cu" "B.Cu")
		(net "GND")
	)
	(via
		(at 66.04 -5.08)
		(size 0.508)
		(drill 0.254)
		(layers "F.Cu" "B.Cu")
		(net "GND")
	)
	(via
		(at 259.08 -304.8)
		(size 0.508)
		(drill 0.254)
		(layers "F.Cu" "B.Cu")
		(net "GND")
	)
	(via
		(at 137.16 -10.16)
		(size 0.508)
		(drill 0.254)
		(layers "F.Cu" "B.Cu")
		(net "GND")
	)
	(via
		(at 34.28873 -387.131052)
		(size 0.508)
		(drill 0.254)
		(layers "F.Cu" "B.Cu")
		(net "GND")
	)
	(via
		(at 35.56 -330.2)
		(size 0.508)
		(drill 0.254)
		(layers "F.Cu" "B.Cu")
		(net "GND")
	)
	(via
		(at 121.92 -365.76)
		(size 0.508)
		(drill 0.254)
		(layers "F.Cu" "B.Cu")
		(net "GND")
	)
	(via
		(at 213.36 -15.24)
		(size 0.508)
		(drill 0.254)
		(layers "F.Cu" "B.Cu")
		(net "GND")
	)
	(via
		(at 208.28 -218.44)
		(size 0.508)
		(drill 0.254)
		(layers "F.Cu" "B.Cu")
		(net "GND")
	)
	(via
		(at 96.52 -259.08)
		(size 0.508)
		(drill 0.254)
		(layers "F.Cu" "B.Cu")
		(net "GND")
	)
	(via
		(at 248.92 -81.28)
		(size 0.508)
		(drill 0.254)
		(layers "F.Cu" "B.Cu")
		(net "GND")
	)
	(via
		(at 4.191 -391.541)
		(size 0.508)
		(drill 0.254)
		(layers "F.Cu" "B.Cu")
		(net "GND")
	)
	(via
		(at 96.52 -502.92)
		(size 0.508)
		(drill 0.254)
		(layers "F.Cu" "B.Cu")
		(net "GND")
	)
	(via
		(at 157.48 -436.88)
		(size 0.508)
		(drill 0.254)
		(layers "F.Cu" "B.Cu")
		(net "GND")
	)
	(via
		(at 208.28 -66.04)
		(size 0.508)
		(drill 0.254)
		(layers "F.Cu" "B.Cu")
		(net "GND")
	)
	(via
		(at 91.44 -386.08)
		(size 0.508)
		(drill 0.254)
		(layers "F.Cu" "B.Cu")
		(net "GND")
	)
	(via
		(at 238.76 -218.44)
		(size 0.508)
		(drill 0.254)
		(layers "F.Cu" "B.Cu")
		(net "GND")
	)
	(via
		(at 37.61613 -478.590102)
		(size 0.508)
		(drill 0.254)
		(layers "F.Cu" "B.Cu")
		(net "GND")
	)
	(via
		(at 76.835 -149.352)
		(size 0.508)
		(drill 0.254)
		(layers "F.Cu" "B.Cu")
		(net "GND")
	)
	(via
		(at 96.52 -50.8)
		(size 0.508)
		(drill 0.254)
		(layers "F.Cu" "B.Cu")
		(net "GND")
	)
	(via
		(at 213.36 -309.88)
		(size 0.508)
		(drill 0.254)
		(layers "F.Cu" "B.Cu")
		(net "GND")
	)
	(via
		(at 34.26333 -479.0821)
		(size 0.508)
		(drill 0.254)
		(layers "F.Cu" "B.Cu")
		(net "GND")
	)
	(via
		(at 182.88 -452.12)
		(size 0.508)
		(drill 0.254)
		(layers "F.Cu" "B.Cu")
		(net "GND")
	)
	(via
		(at 106.68 -223.52)
		(size 0.508)
		(drill 0.254)
		(layers "F.Cu" "B.Cu")
		(net "GND")
	)
	(via
		(at 66.04 -81.28)
		(size 0.508)
		(drill 0.254)
		(layers "F.Cu" "B.Cu")
		(net "GND")
	)
	(via
		(at 33.02 -373.38)
		(size 0.508)
		(drill 0.254)
		(layers "F.Cu" "B.Cu")
		(net "GND")
	)
	(via
		(at 81.28 -30.48)
		(size 0.508)
		(drill 0.254)
		(layers "F.Cu" "B.Cu")
		(net "GND")
	)
	(via
		(at 37.61613 -380.390146)
		(size 0.508)
		(drill 0.254)
		(layers "F.Cu" "B.Cu")
		(net "GND")
	)
	(via
		(at 4.191 -161.890202)
		(size 0.508)
		(drill 0.254)
		(layers "F.Cu" "B.Cu")
		(net "GND")
	)
	(via
		(at 142.24 -502.92)
		(size 0.508)
		(drill 0.254)
		(layers "F.Cu" "B.Cu")
		(net "GND")
	)
	(via
		(at 16.129 -228.346)
		(size 0.508)
		(drill 0.254)
		(layers "F.Cu" "B.Cu")
		(net "GND")
	)
	(via
		(at 219.280232 -273.082004)
		(size 0.508)
		(drill 0.254)
		(layers "F.Cu" "B.Cu")
		(net "GND")
	)
	(via
		(at 192.532 -446.024)
		(size 0.508)
		(drill 0.254)
		(layers "F.Cu" "B.Cu")
		(net "GND")
	)
	(via
		(at 101.6 -177.8)
		(size 0.508)
		(drill 0.254)
		(layers "F.Cu" "B.Cu")
		(net "GND")
	)
	(via
		(at 26.010362 -268.785086)
		(size 0.508)
		(drill 0.254)
		(layers "F.Cu" "B.Cu")
		(net "GND")
	)
	(via
		(at 203.2 -284.48)
		(size 0.508)
		(drill 0.254)
		(layers "F.Cu" "B.Cu")
		(net "GND")
	)
	(via
		(at 27.695652 -15.82674)
		(size 0.508)
		(drill 0.254)
		(layers "F.Cu" "B.Cu")
		(net "GND")
	)
	(via
		(at 218.44 -142.24)
		(size 0.508)
		(drill 0.254)
		(layers "F.Cu" "B.Cu")
		(net "GND")
	)
	(via
		(at 221.615 -94.234)
		(size 0.508)
		(drill 0.254)
		(layers "F.Cu" "B.Cu")
		(net "GND")
	)
	(via
		(at 228.585014 -257.795014)
		(size 0.508)
		(drill 0.254)
		(layers "F.Cu" "B.Cu")
		(net "GND")
	)
	(via
		(at 162.56 -116.84)
		(size 0.508)
		(drill 0.254)
		(layers "F.Cu" "B.Cu")
		(net "GND")
	)
	(via
		(at 243.84 -269.24)
		(size 0.508)
		(drill 0.254)
		(layers "F.Cu" "B.Cu")
		(net "GND")
	)
	(via
		(at 111.76 -502.92)
		(size 0.508)
		(drill 0.254)
		(layers "F.Cu" "B.Cu")
		(net "GND")
	)
	(via
		(at 4.191 -355.890068)
		(size 0.508)
		(drill 0.254)
		(layers "F.Cu" "B.Cu")
		(net "GND")
	)
	(via
		(at 193.04 -96.52)
		(size 0.508)
		(drill 0.254)
		(layers "F.Cu" "B.Cu")
		(net "GND")
	)
	(via
		(at 147.32 -467.36)
		(size 0.508)
		(drill 0.254)
		(layers "F.Cu" "B.Cu")
		(net "GND")
	)
	(via
		(at 147.32 -5.08)
		(size 0.508)
		(drill 0.254)
		(layers "F.Cu" "B.Cu")
		(net "GND")
	)
	(via
		(at 50.8 -172.72)
		(size 0.508)
		(drill 0.254)
		(layers "F.Cu" "B.Cu")
		(net "GND")
	)
	(via
		(at 217.4494 -188.7982)
		(size 0.508)
		(drill 0.254)
		(layers "F.Cu" "B.Cu")
		(net "GND")
	)
	(via
		(at 26.035 -187.325)
		(size 0.508)
		(drill 0.254)
		(layers "F.Cu" "B.Cu")
		(net "GND")
	)
	(via
		(at 127 -233.68)
		(size 0.508)
		(drill 0.254)
		(layers "F.Cu" "B.Cu")
		(net "GND")
	)
	(via
		(at 152.4 -35.56)
		(size 0.508)
		(drill 0.254)
		(layers "F.Cu" "B.Cu")
		(net "GND")
	)
	(via
		(at 207.10525 -298.1325)
		(size 0.508)
		(drill 0.254)
		(layers "F.Cu" "B.Cu")
		(net "GND")
	)
	(via
		(at 262.103108 -117.758464)
		(size 0.508)
		(drill 0.254)
		(layers "F.Cu" "B.Cu")
		(net "GND")
	)
	(via
		(at 42.418 -240.260886)
		(size 0.508)
		(drill 0.254)
		(layers "F.Cu" "B.Cu")
		(net "GND")
	)
	(via
		(at 187.96 -482.6)
		(size 0.508)
		(drill 0.254)
		(layers "F.Cu" "B.Cu")
		(net "GND")
	)
	(via
		(at 111.76 -243.84)
		(size 0.508)
		(drill 0.254)
		(layers "F.Cu" "B.Cu")
		(net "GND")
	)
	(via
		(at 162.56 -96.52)
		(size 0.508)
		(drill 0.254)
		(layers "F.Cu" "B.Cu")
		(net "GND")
	)
	(via
		(at 219.314014 -54.127908)
		(size 0.508)
		(drill 0.254)
		(layers "F.Cu" "B.Cu")
		(net "GND")
	)
	(via
		(at 167.64 -264.16)
		(size 0.508)
		(drill 0.254)
		(layers "F.Cu" "B.Cu")
		(net "GND")
	)
	(via
		(at 6.223 -192.273174)
		(size 0.508)
		(drill 0.254)
		(layers "F.Cu" "B.Cu")
		(net "GND")
	)
	(via
		(at 177.8 -248.92)
		(size 0.508)
		(drill 0.254)
		(layers "F.Cu" "B.Cu")
		(net "GND")
	)
	(via
		(at 127 -477.52)
		(size 0.508)
		(drill 0.254)
		(layers "F.Cu" "B.Cu")
		(net "GND")
	)
	(via
		(at 155.589986 -504.603004)
		(size 0.508)
		(drill 0.254)
		(layers "F.Cu" "B.Cu")
		(net "GND")
	)
	(via
		(at 242.57 -389.89)
		(size 0.7112)
		(drill 0.4064)
		(layers "F.Cu" "B.Cu")
		(net "GND")
	)
	(via
		(at 162.56 -177.8)
		(size 0.508)
		(drill 0.254)
		(layers "F.Cu" "B.Cu")
		(net "GND")
	)
	(via
		(at 243.84 -294.64)
		(size 0.508)
		(drill 0.254)
		(layers "F.Cu" "B.Cu")
		(net "GND")
	)
	(via
		(at 96.3295 -114.554)
		(size 0.508)
		(drill 0.254)
		(layers "F.Cu" "B.Cu")
		(net "GND")
	)
	(via
		(at 4.191 -327.890124)
		(size 0.508)
		(drill 0.254)
		(layers "F.Cu" "B.Cu")
		(net "GND")
	)
	(via
		(at 254 -462.28)
		(size 0.508)
		(drill 0.254)
		(layers "F.Cu" "B.Cu")
		(net "GND")
	)
	(via
		(at 127 -350.52)
		(size 0.508)
		(drill 0.254)
		(layers "F.Cu" "B.Cu")
		(net "GND")
	)
	(via
		(at 238.76 -76.2)
		(size 0.508)
		(drill 0.254)
		(layers "F.Cu" "B.Cu")
		(net "GND")
	)
	(via
		(at 235.077 -441.452)
		(size 0.508)
		(drill 0.254)
		(layers "F.Cu" "B.Cu")
		(net "GND")
	)
	(via
		(at 137.16 -477.52)
		(size 0.508)
		(drill 0.254)
		(layers "F.Cu" "B.Cu")
		(net "GND")
	)
	(via
		(at 137.16 -96.52)
		(size 0.508)
		(drill 0.254)
		(layers "F.Cu" "B.Cu")
		(net "GND")
	)
	(via
		(at 106.68 -472.44)
		(size 0.508)
		(drill 0.254)
		(layers "F.Cu" "B.Cu")
		(net "GND")
	)
	(via
		(at 28.956 -373.38)
		(size 0.508)
		(drill 0.254)
		(layers "F.Cu" "B.Cu")
		(net "GND")
	)
	(via
		(at 259.08 -325.12)
		(size 0.508)
		(drill 0.254)
		(layers "F.Cu" "B.Cu")
		(net "GND")
	)
	(via
		(at 18.415 -244.39499)
		(size 0.508)
		(drill 0.254)
		(layers "F.Cu" "B.Cu")
		(net "GND")
	)
	(via
		(at 228.6 -233.68)
		(size 0.508)
		(drill 0.254)
		(layers "F.Cu" "B.Cu")
		(net "GND")
	)
	(via
		(at 208.28 -426.72)
		(size 0.508)
		(drill 0.254)
		(layers "F.Cu" "B.Cu")
		(net "GND")
	)
	(via
		(at 24.384 -340.410038)
		(size 0.508)
		(drill 0.254)
		(layers "F.Cu" "B.Cu")
		(net "GND")
	)
	(via
		(at 32.004 -74.422)
		(size 0.508)
		(drill 0.254)
		(layers "F.Cu" "B.Cu")
		(net "GND")
	)
	(via
		(at 60.96 -492.76)
		(size 0.508)
		(drill 0.254)
		(layers "F.Cu" "B.Cu")
		(net "GND")
	)
	(via
		(at 6.223 -217.022426)
		(size 0.508)
		(drill 0.254)
		(layers "F.Cu" "B.Cu")
		(net "GND")
	)
	(via
		(at 93.599 -92.583)
		(size 0.508)
		(drill 0.254)
		(layers "F.Cu" "B.Cu")
		(net "GND")
	)
	(via
		(at 106.68 -182.88)
		(size 0.508)
		(drill 0.254)
		(layers "F.Cu" "B.Cu")
		(net "GND")
	)
	(via
		(at 177.8 -5.08)
		(size 0.508)
		(drill 0.254)
		(layers "F.Cu" "B.Cu")
		(net "GND")
	)
	(via
		(at 96.52 -45.72)
		(size 0.508)
		(drill 0.254)
		(layers "F.Cu" "B.Cu")
		(net "GND")
	)
	(via
		(at 182.88 -20.32)
		(size 0.508)
		(drill 0.254)
		(layers "F.Cu" "B.Cu")
		(net "GND")
	)
	(via
		(at 238.76 -233.68)
		(size 0.508)
		(drill 0.254)
		(layers "F.Cu" "B.Cu")
		(net "GND")
	)
	(via
		(at 142.24 -452.12)
		(size 0.508)
		(drill 0.254)
		(layers "F.Cu" "B.Cu")
		(net "GND")
	)
	(via
		(at 44.828968 -470.699084)
		(size 0.508)
		(drill 0.254)
		(layers "F.Cu" "B.Cu")
		(net "GND")
	)
	(via
		(at 259.08 -35.56)
		(size 0.508)
		(drill 0.254)
		(layers "F.Cu" "B.Cu")
		(net "GND")
	)
	(via
		(at 193.04 -172.72)
		(size 0.508)
		(drill 0.254)
		(layers "F.Cu" "B.Cu")
		(net "GND")
	)
	(via
		(at 187.96 -35.56)
		(size 0.508)
		(drill 0.254)
		(layers "F.Cu" "B.Cu")
		(net "GND")
	)
	(via
		(at 44.828968 -161.700718)
		(size 0.508)
		(drill 0.254)
		(layers "F.Cu" "B.Cu")
		(net "GND")
	)
	(via
		(at 17.145 -31.518352)
		(size 0.508)
		(drill 0.254)
		(layers "F.Cu" "B.Cu")
		(net "GND")
	)
	(via
		(at 4.191 -424.162982)
		(size 0.508)
		(drill 0.254)
		(layers "F.Cu" "B.Cu")
		(net "GND")
	)
	(via
		(at 244.729 -420.878)
		(size 0.508)
		(drill 0.254)
		(layers "F.Cu" "B.Cu")
		(net "GND")
	)
	(via
		(at 157.48 -96.52)
		(size 0.508)
		(drill 0.254)
		(layers "F.Cu" "B.Cu")
		(net "GND")
	)
	(via
		(at 203.2 -5.08)
		(size 0.508)
		(drill 0.254)
		(layers "F.Cu" "B.Cu")
		(net "GND")
	)
	(via
		(at 162.56 -40.64)
		(size 0.508)
		(drill 0.254)
		(layers "F.Cu" "B.Cu")
		(net "GND")
	)
	(via
		(at 18.415 -227.88499)
		(size 0.508)
		(drill 0.254)
		(layers "F.Cu" "B.Cu")
		(net "GND")
	)
	(via
		(at 223.52 -101.6)
		(size 0.508)
		(drill 0.254)
		(layers "F.Cu" "B.Cu")
		(net "GND")
	)
	(via
		(at 254 -340.36)
		(size 0.508)
		(drill 0.254)
		(layers "F.Cu" "B.Cu")
		(net "GND")
	)
	(via
		(at 247.65 -407.67)
		(size 0.7112)
		(drill 0.4064)
		(layers "F.Cu" "B.Cu")
		(net "GND")
	)
	(via
		(at 37.61613 -56.18988)
		(size 0.508)
		(drill 0.254)
		(layers "F.Cu" "B.Cu")
		(net "GND")
	)
	(via
		(at 4.191 -303.890172)
		(size 0.508)
		(drill 0.254)
		(layers "F.Cu" "B.Cu")
		(net "GND")
	)
	(via
		(at 132.08 -40.64)
		(size 0.508)
		(drill 0.254)
		(layers "F.Cu" "B.Cu")
		(net "GND")
	)
	(via
		(at 50.8 -330.2)
		(size 0.508)
		(drill 0.254)
		(layers "F.Cu" "B.Cu")
		(net "GND")
	)
	(via
		(at 132.08 -447.04)
		(size 0.508)
		(drill 0.254)
		(layers "F.Cu" "B.Cu")
		(net "GND")
	)
	(via
		(at 37.61613 -159.189928)
		(size 0.508)
		(drill 0.254)
		(layers "F.Cu" "B.Cu")
		(net "GND")
	)
	(via
		(at 198.12 -213.36)
		(size 0.508)
		(drill 0.254)
		(layers "F.Cu" "B.Cu")
		(net "GND")
	)
	(via
		(at 243.84 -497.84)
		(size 0.508)
		(drill 0.254)
		(layers "F.Cu" "B.Cu")
		(net "GND")
	)
	(via
		(at 55.88 -284.48)
		(size 0.508)
		(drill 0.254)
		(layers "F.Cu" "B.Cu")
		(net "GND")
	)
	(via
		(at 228.585014 -175.114966)
		(size 0.508)
		(drill 0.254)
		(layers "F.Cu" "B.Cu")
		(net "GND")
	)
	(via
		(at 101.6 -467.36)
		(size 0.508)
		(drill 0.254)
		(layers "F.Cu" "B.Cu")
		(net "GND")
	)
	(via
		(at 81.28 -502.92)
		(size 0.508)
		(drill 0.254)
		(layers "F.Cu" "B.Cu")
		(net "GND")
	)
	(via
		(at 147.32 -30.48)
		(size 0.508)
		(drill 0.254)
		(layers "F.Cu" "B.Cu")
		(net "GND")
	)
	(via
		(at 198.12 -314.96)
		(size 0.508)
		(drill 0.254)
		(layers "F.Cu" "B.Cu")
		(net "GND")
	)
	(via
		(at 223.52 -132.08)
		(size 0.508)
		(drill 0.254)
		(layers "F.Cu" "B.Cu")
		(net "GND")
	)
	(via
		(at 218.44 -330.2)
		(size 0.508)
		(drill 0.254)
		(layers "F.Cu" "B.Cu")
		(net "GND")
	)
	(via
		(at 172.72 -441.96)
		(size 0.508)
		(drill 0.254)
		(layers "F.Cu" "B.Cu")
		(net "GND")
	)
	(via
		(at 4.191 -193.966084)
		(size 0.508)
		(drill 0.254)
		(layers "F.Cu" "B.Cu")
		(net "GND")
	)
	(via
		(at 27.720798 -438.918096)
		(size 0.508)
		(drill 0.254)
		(layers "F.Cu" "B.Cu")
		(net "GND")
	)
	(via
		(at 27.664918 -142.871952)
		(size 0.508)
		(drill 0.254)
		(layers "F.Cu" "B.Cu")
		(net "GND")
	)
	(via
		(at 10.16 -50.8)
		(size 0.508)
		(drill 0.254)
		(layers "F.Cu" "B.Cu")
		(net "GND")
	)
	(via
		(at 198.12 -10.16)
		(size 0.508)
		(drill 0.254)
		(layers "F.Cu" "B.Cu")
		(net "GND")
	)
	(via
		(at 96.774 -303.784)
		(size 0.508)
		(drill 0.254)
		(layers "F.Cu" "B.Cu")
		(net "GND")
	)
	(via
		(at 60.96 -254)
		(size 0.508)
		(drill 0.254)
		(layers "F.Cu" "B.Cu")
		(net "GND")
	)
	(via
		(at 106.68 -502.92)
		(size 0.508)
		(drill 0.254)
		(layers "F.Cu" "B.Cu")
		(net "GND")
	)
	(via
		(at 55.88 -386.08)
		(size 0.508)
		(drill 0.254)
		(layers "F.Cu" "B.Cu")
		(net "GND")
	)
	(via
		(at 18.415 -330.885038)
		(size 0.508)
		(drill 0.254)
		(layers "F.Cu" "B.Cu")
		(net "GND")
	)
	(via
		(at 95.377 -303.784)
		(size 0.508)
		(drill 0.254)
		(layers "F.Cu" "B.Cu")
		(net "GND")
	)
	(via
		(at 12.704572 -1.397)
		(size 0.508)
		(drill 0.254)
		(layers "F.Cu" "B.Cu")
		(net "GND")
	)
	(via
		(at 132.08 -340.36)
		(size 0.508)
		(drill 0.254)
		(layers "F.Cu" "B.Cu")
		(net "GND")
	)
	(via
		(at 238.76 -198.12)
		(size 0.508)
		(drill 0.254)
		(layers "F.Cu" "B.Cu")
		(net "GND")
	)
	(via
		(at 147.32 -441.96)
		(size 0.508)
		(drill 0.254)
		(layers "F.Cu" "B.Cu")
		(net "GND")
	)
	(via
		(at 132.08 -492.76)
		(size 0.508)
		(drill 0.254)
		(layers "F.Cu" "B.Cu")
		(net "GND")
	)
	(via
		(at 162.56 -5.08)
		(size 0.508)
		(drill 0.254)
		(layers "F.Cu" "B.Cu")
		(net "GND")
	)
	(via
		(at 13.208 -479.425)
		(size 0.508)
		(drill 0.254)
		(layers "F.Cu" "B.Cu")
		(net "GND")
	)
	(via
		(at 76.2 -238.76)
		(size 0.508)
		(drill 0.254)
		(layers "F.Cu" "B.Cu")
		(net "GND")
	)
	(via
		(at 78.486 -92.71)
		(size 0.508)
		(drill 0.254)
		(layers "F.Cu" "B.Cu")
		(net "GND")
	)
	(via
		(at 73.4822 -430.8348)
		(size 0.508)
		(drill 0.254)
		(layers "F.Cu" "B.Cu")
		(net "GND")
	)
	(via
		(at 132.08 -147.32)
		(size 0.508)
		(drill 0.254)
		(layers "F.Cu" "B.Cu")
		(net "GND")
	)
	(via
		(at 4.191 -416.52063)
		(size 0.508)
		(drill 0.254)
		(layers "F.Cu" "B.Cu")
		(net "GND")
	)
	(via
		(at 37.61613 -382.789938)
		(size 0.508)
		(drill 0.254)
		(layers "F.Cu" "B.Cu")
		(net "GND")
	)
	(via
		(at 86.36 -472.44)
		(size 0.508)
		(drill 0.254)
		(layers "F.Cu" "B.Cu")
		(net "GND")
	)
	(via
		(at 4.191 -168.205404)
		(size 0.508)
		(drill 0.254)
		(layers "F.Cu" "B.Cu")
		(net "GND")
	)
	(via
		(at 18.8722 -482.6)
		(size 0.508)
		(drill 0.254)
		(layers "F.Cu" "B.Cu")
		(net "GND")
	)
	(via
		(at 4.191 -405.13)
		(size 0.508)
		(drill 0.254)
		(layers "F.Cu" "B.Cu")
		(net "GND")
	)
	(via
		(at 198.12 -101.6)
		(size 0.508)
		(drill 0.254)
		(layers "F.Cu" "B.Cu")
		(net "GND")
	)
	(via
		(at 210.439 -43.434)
		(size 0.508)
		(drill 0.254)
		(layers "F.Cu" "B.Cu")
		(net "GND")
	)
	(via
		(at 243.84 -457.2)
		(size 0.508)
		(drill 0.254)
		(layers "F.Cu" "B.Cu")
		(net "GND")
	)
	(via
		(at 59.069986 -504.603004)
		(size 0.508)
		(drill 0.254)
		(layers "F.Cu" "B.Cu")
		(net "GND")
	)
	(via
		(at 157.48 -294.64)
		(size 0.508)
		(drill 0.254)
		(layers "F.Cu" "B.Cu")
		(net "GND")
	)
	(via
		(at 4.191 -319.966086)
		(size 0.508)
		(drill 0.254)
		(layers "F.Cu" "B.Cu")
		(net "GND")
	)
	(via
		(at 259.08 -157.48)
		(size 0.508)
		(drill 0.254)
		(layers "F.Cu" "B.Cu")
		(net "GND")
	)
	(via
		(at 238.76 -398.78)
		(size 0.7112)
		(drill 0.3556)
		(layers "F.Cu" "B.Cu")
		(net "GND")
	)
	(via
		(at 198.12 -182.88)
		(size 0.508)
		(drill 0.254)
		(layers "F.Cu" "B.Cu")
		(net "GND")
	)
	(via
		(at 137.16 -66.04)
		(size 0.508)
		(drill 0.254)
		(layers "F.Cu" "B.Cu")
		(net "GND")
	)
	(via
		(at 4.191 -190.921132)
		(size 0.508)
		(drill 0.254)
		(layers "F.Cu" "B.Cu")
		(net "GND")
	)
	(via
		(at 213.36 -426.72)
		(size 0.508)
		(drill 0.254)
		(layers "F.Cu" "B.Cu")
		(net "GND")
	)
	(via
		(at 6.223 -229.873048)
		(size 0.508)
		(drill 0.254)
		(layers "F.Cu" "B.Cu")
		(net "GND")
	)
	(via
		(at 6.223 -221.960694)
		(size 0.508)
		(drill 0.254)
		(layers "F.Cu" "B.Cu")
		(net "GND")
	)
	(via
		(at 121.92 -203.2)
		(size 0.508)
		(drill 0.254)
		(layers "F.Cu" "B.Cu")
		(net "GND")
	)
	(via
		(at 132.08 -472.44)
		(size 0.508)
		(drill 0.254)
		(layers "F.Cu" "B.Cu")
		(net "GND")
	)
	(via
		(at 182.88 -25.4)
		(size 0.508)
		(drill 0.254)
		(layers "F.Cu" "B.Cu")
		(net "GND")
	)
	(via
		(at 31.3436 -386.7404)
		(size 0.508)
		(drill 0.254)
		(layers "F.Cu" "B.Cu")
		(net "GND")
	)
	(via
		(at 123.536202 -236.92866)
		(size 0.7112)
		(drill 0.3556)
		(layers "F.Cu" "B.Cu")
		(net "GND")
	)
	(via
		(at 81.28 -137.16)
		(size 0.508)
		(drill 0.254)
		(layers "F.Cu" "B.Cu")
		(net "GND")
	)
	(via
		(at 218.44 -101.6)
		(size 0.508)
		(drill 0.254)
		(layers "F.Cu" "B.Cu")
		(net "GND")
	)
	(via
		(at 22.987 -386.461)
		(size 0.508)
		(drill 0.254)
		(layers "F.Cu" "B.Cu")
		(net "GND")
	)
	(via
		(at 4.191 -277.94204)
		(size 0.508)
		(drill 0.254)
		(layers "F.Cu" "B.Cu")
		(net "GND")
	)
	(via
		(at 66.04 -121.92)
		(size 0.508)
		(drill 0.254)
		(layers "F.Cu" "B.Cu")
		(net "GND")
	)
	(via
		(at 1.397 -76.449428)
		(size 0.508)
		(drill 0.254)
		(layers "F.Cu" "B.Cu")
		(net "GND")
	)
	(via
		(at 137.16 -172.72)
		(size 0.508)
		(drill 0.254)
		(layers "F.Cu" "B.Cu")
		(net "GND")
	)
	(via
		(at 76.2 -492.76)
		(size 0.508)
		(drill 0.254)
		(layers "F.Cu" "B.Cu")
		(net "GND")
	)
	(via
		(at 5.08 -248.92)
		(size 0.508)
		(drill 0.254)
		(layers "F.Cu" "B.Cu")
		(net "GND")
	)
	(via
		(at 55.88 -279.4)
		(size 0.508)
		(drill 0.254)
		(layers "F.Cu" "B.Cu")
		(net "GND")
	)
	(via
		(at 162.56 -431.8)
		(size 0.508)
		(drill 0.254)
		(layers "F.Cu" "B.Cu")
		(net "GND")
	)
	(via
		(at 55.88 -274.32)
		(size 0.508)
		(drill 0.254)
		(layers "F.Cu" "B.Cu")
		(net "GND")
	)
	(via
		(at 177.8 -497.84)
		(size 0.508)
		(drill 0.254)
		(layers "F.Cu" "B.Cu")
		(net "GND")
	)
	(via
		(at 223.52 -320.04)
		(size 0.508)
		(drill 0.254)
		(layers "F.Cu" "B.Cu")
		(net "GND")
	)
	(via
		(at 157.48 -71.12)
		(size 0.508)
		(drill 0.254)
		(layers "F.Cu" "B.Cu")
		(net "GND")
	)
	(via
		(at 222.616014 -176.789842)
		(size 0.508)
		(drill 0.254)
		(layers "F.Cu" "B.Cu")
		(net "GND")
	)
	(via
		(at 37.61613 -389.990076)
		(size 0.508)
		(drill 0.254)
		(layers "F.Cu" "B.Cu")
		(net "GND")
	)
	(via
		(at 55.88 -502.92)
		(size 0.508)
		(drill 0.254)
		(layers "F.Cu" "B.Cu")
		(net "GND")
	)
	(via
		(at 162.56 -370.84)
		(size 0.508)
		(drill 0.254)
		(layers "F.Cu" "B.Cu")
		(net "GND")
	)
	(via
		(at 157.48 -487.68)
		(size 0.508)
		(drill 0.254)
		(layers "F.Cu" "B.Cu")
		(net "GND")
	)
	(via
		(at 253.980188 -280.059892)
		(size 0.508)
		(drill 0.254)
		(layers "F.Cu" "B.Cu")
		(net "GND")
	)
	(via
		(at 37.61613 -272.590006)
		(size 0.508)
		(drill 0.254)
		(layers "F.Cu" "B.Cu")
		(net "GND")
	)
	(via
		(at 142.24 -431.8)
		(size 0.508)
		(drill 0.254)
		(layers "F.Cu" "B.Cu")
		(net "GND")
	)
	(via
		(at 116.84 -340.36)
		(size 0.508)
		(drill 0.254)
		(layers "F.Cu" "B.Cu")
		(net "GND")
	)
	(via
		(at 9.7536 -469.0745)
		(size 0.508)
		(drill 0.254)
		(layers "F.Cu" "B.Cu")
		(net "GND")
	)
	(via
		(at 220.599 -94.234)
		(size 0.508)
		(drill 0.254)
		(layers "F.Cu" "B.Cu")
		(net "GND")
	)
	(via
		(at 172.72 -243.84)
		(size 0.508)
		(drill 0.254)
		(layers "F.Cu" "B.Cu")
		(net "GND")
	)
	(via
		(at 76.2 -411.48)
		(size 0.508)
		(drill 0.254)
		(layers "F.Cu" "B.Cu")
		(net "GND")
	)
	(via
		(at 96.52 -477.52)
		(size 0.508)
		(drill 0.254)
		(layers "F.Cu" "B.Cu")
		(net "GND")
	)
	(via
		(at 193.04 -350.52)
		(size 0.508)
		(drill 0.254)
		(layers "F.Cu" "B.Cu")
		(net "GND")
	)
	(via
		(at 106.68 -40.64)
		(size 0.508)
		(drill 0.254)
		(layers "F.Cu" "B.Cu")
		(net "GND")
	)
	(via
		(at 121.92 -360.68)
		(size 0.508)
		(drill 0.254)
		(layers "F.Cu" "B.Cu")
		(net "GND")
	)
	(via
		(at 4.191 -349.490284)
		(size 0.508)
		(drill 0.254)
		(layers "F.Cu" "B.Cu")
		(net "GND")
	)
	(via
		(at 36.3982 -403.0726)
		(size 0.508)
		(drill 0.254)
		(layers "F.Cu" "B.Cu")
		(net "GND")
	)
	(via
		(at 96.52 -391.16)
		(size 0.508)
		(drill 0.254)
		(layers "F.Cu" "B.Cu")
		(net "GND")
	)
	(via
		(at 157.48 -20.32)
		(size 0.508)
		(drill 0.254)
		(layers "F.Cu" "B.Cu")
		(net "GND")
	)
	(via
		(at 36.4744 -197.0024)
		(size 0.508)
		(drill 0.254)
		(layers "F.Cu" "B.Cu")
		(net "GND")
	)
	(via
		(at 222.616014 -371.590062)
		(size 0.508)
		(drill 0.254)
		(layers "F.Cu" "B.Cu")
		(net "GND")
	)
	(via
		(at 121.92 -345.44)
		(size 0.508)
		(drill 0.254)
		(layers "F.Cu" "B.Cu")
		(net "GND")
	)
	(via
		(at 230.503222 -240.674398)
		(size 0.508)
		(drill 0.254)
		(layers "F.Cu" "B.Cu")
		(net "GND")
	)
	(via
		(at 4.191 -310.29021)
		(size 0.508)
		(drill 0.254)
		(layers "F.Cu" "B.Cu")
		(net "GND")
	)
	(via
		(at 230.503222 -343.674192)
		(size 0.508)
		(drill 0.254)
		(layers "F.Cu" "B.Cu")
		(net "GND")
	)
	(via
		(at 208.407 -43.434)
		(size 0.508)
		(drill 0.254)
		(layers "F.Cu" "B.Cu")
		(net "GND")
	)
	(via
		(at 182.88 -431.8)
		(size 0.508)
		(drill 0.254)
		(layers "F.Cu" "B.Cu")
		(net "GND")
	)
	(via
		(at 244.729 -357.886)
		(size 0.508)
		(drill 0.254)
		(layers "F.Cu" "B.Cu")
		(net "GND")
	)
	(via
		(at 84.963 -422.91)
		(size 0.508)
		(drill 0.254)
		(layers "F.Cu" "B.Cu")
		(net "GND")
	)
	(via
		(at 177.8 -457.2)
		(size 0.508)
		(drill 0.254)
		(layers "F.Cu" "B.Cu")
		(net "GND")
	)
	(via
		(at 95.377 -102.997)
		(size 0.508)
		(drill 0.254)
		(layers "F.Cu" "B.Cu")
		(net "GND")
	)
	(via
		(at 238.76 -259.08)
		(size 0.508)
		(drill 0.254)
		(layers "F.Cu" "B.Cu")
		(net "GND")
	)
	(via
		(at 248.92 -462.28)
		(size 0.508)
		(drill 0.254)
		(layers "F.Cu" "B.Cu")
		(net "GND")
	)
	(via
		(at 157.48 -81.28)
		(size 0.508)
		(drill 0.254)
		(layers "F.Cu" "B.Cu")
		(net "GND")
	)
	(via
		(at 132.08 -20.32)
		(size 0.508)
		(drill 0.254)
		(layers "F.Cu" "B.Cu")
		(net "GND")
	)
	(via
		(at 55.88 -440.563)
		(size 0.508)
		(drill 0.254)
		(layers "F.Cu" "B.Cu")
		(net "GND")
	)
	(via
		(at 147.32 -132.08)
		(size 0.508)
		(drill 0.254)
		(layers "F.Cu" "B.Cu")
		(net "GND")
	)
	(via
		(at 43.58513 -173.844966)
		(size 0.508)
		(drill 0.254)
		(layers "F.Cu" "B.Cu")
		(net "GND")
	)
	(via
		(at 55.88 -497.84)
		(size 0.508)
		(drill 0.254)
		(layers "F.Cu" "B.Cu")
		(net "GND")
	)
	(via
		(at 95.377 -307.975)
		(size 0.508)
		(drill 0.254)
		(layers "F.Cu" "B.Cu")
		(net "GND")
	)
	(via
		(at 238.76 -60.96)
		(size 0.508)
		(drill 0.254)
		(layers "F.Cu" "B.Cu")
		(net "GND")
	)
	(via
		(at 10.6934 -475.3229)
		(size 0.508)
		(drill 0.254)
		(layers "F.Cu" "B.Cu")
		(net "GND")
	)
	(via
		(at 10.3632 -465.4042)
		(size 0.508)
		(drill 0.254)
		(layers "F.Cu" "B.Cu")
		(net "GND")
	)
	(via
		(at 81.28 -487.68)
		(size 0.508)
		(drill 0.254)
		(layers "F.Cu" "B.Cu")
		(net "GND")
	)
	(via
		(at 236.982 -441.071)
		(size 0.508)
		(drill 0.254)
		(layers "F.Cu" "B.Cu")
		(net "GND")
	)
	(via
		(at 254 -355.6)
		(size 0.508)
		(drill 0.254)
		(layers "F.Cu" "B.Cu")
		(net "GND")
	)
	(via
		(at 121.92 -5.08)
		(size 0.508)
		(drill 0.254)
		(layers "F.Cu" "B.Cu")
		(net "GND")
	)
	(via
		(at 203.2 -330.2)
		(size 0.508)
		(drill 0.254)
		(layers "F.Cu" "B.Cu")
		(net "GND")
	)
	(via
		(at 157.48 -492.76)
		(size 0.508)
		(drill 0.254)
		(layers "F.Cu" "B.Cu")
		(net "GND")
	)
	(via
		(at 6.223 -335.260696)
		(size 0.508)
		(drill 0.254)
		(layers "F.Cu" "B.Cu")
		(net "GND")
	)
	(via
		(at 152.4 -15.24)
		(size 0.508)
		(drill 0.254)
		(layers "F.Cu" "B.Cu")
		(net "GND")
	)
	(via
		(at 4.191 -300.69028)
		(size 0.508)
		(drill 0.254)
		(layers "F.Cu" "B.Cu")
		(net "GND")
	)
	(via
		(at 196.847206 -496.749832)
		(size 0.508)
		(drill 0.254)
		(layers "F.Cu" "B.Cu")
		(net "GND")
	)
	(via
		(at 91.44 -66.04)
		(size 0.508)
		(drill 0.254)
		(layers "F.Cu" "B.Cu")
		(net "GND")
	)
	(via
		(at 8.8646 -459.0288)
		(size 0.7112)
		(drill 0.4064)
		(layers "F.Cu" "B.Cu")
		(net "GND")
	)
	(via
		(at 233.68 -91.44)
		(size 0.508)
		(drill 0.254)
		(layers "F.Cu" "B.Cu")
		(net "GND")
	)
	(via
		(at 127 -213.36)
		(size 0.508)
		(drill 0.254)
		(layers "F.Cu" "B.Cu")
		(net "GND")
	)
	(via
		(at 50.8 -381)
		(size 0.508)
		(drill 0.254)
		(layers "F.Cu" "B.Cu")
		(net "GND")
	)
	(via
		(at 218.44 -127)
		(size 0.508)
		(drill 0.254)
		(layers "F.Cu" "B.Cu")
		(net "GND")
	)
	(via
		(at 93.98 -210.82)
		(size 0.508)
		(drill 0.254)
		(layers "F.Cu" "B.Cu")
		(net "GND")
	)
	(via
		(at 37.0586 -103.759)
		(size 0.508)
		(drill 0.254)
		(layers "F.Cu" "B.Cu")
		(net "GND")
	)
	(via
		(at 91.186 -302.387)
		(size 0.508)
		(drill 0.254)
		(layers "F.Cu" "B.Cu")
		(net "GND")
	)
	(via
		(at 177.8 -198.12)
		(size 0.508)
		(drill 0.254)
		(layers "F.Cu" "B.Cu")
		(net "GND")
	)
	(via
		(at 221.8944 -84.3788)
		(size 0.508)
		(drill 0.254)
		(layers "F.Cu" "B.Cu")
		(net "GND")
	)
	(via
		(at 142.24 -233.68)
		(size 0.508)
		(drill 0.254)
		(layers "F.Cu" "B.Cu")
		(net "GND")
	)
	(via
		(at 60.96 -340.36)
		(size 0.508)
		(drill 0.254)
		(layers "F.Cu" "B.Cu")
		(net "GND")
	)
	(via
		(at 248.92 -228.6)
		(size 0.508)
		(drill 0.254)
		(layers "F.Cu" "B.Cu")
		(net "GND")
	)
	(via
		(at 152.4 -91.44)
		(size 0.508)
		(drill 0.254)
		(layers "F.Cu" "B.Cu")
		(net "GND")
	)
	(via
		(at 177.8 -320.04)
		(size 0.508)
		(drill 0.254)
		(layers "F.Cu" "B.Cu")
		(net "GND")
	)
	(via
		(at 6.223 -324.674738)
		(size 0.508)
		(drill 0.254)
		(layers "F.Cu" "B.Cu")
		(net "GND")
	)
	(via
		(at 152.4 -218.44)
		(size 0.508)
		(drill 0.254)
		(layers "F.Cu" "B.Cu")
		(net "GND")
	)
	(via
		(at 238.76 -289.56)
		(size 0.508)
		(drill 0.254)
		(layers "F.Cu" "B.Cu")
		(net "GND")
	)
	(via
		(at 43.58513 -364.605062)
		(size 0.508)
		(drill 0.254)
		(layers "F.Cu" "B.Cu")
		(net "GND")
	)
	(via
		(at 214.5792 -495.2238)
		(size 0.508)
		(drill 0.254)
		(layers "F.Cu" "B.Cu")
		(net "GND")
	)
	(via
		(at 243.84 -314.96)
		(size 0.508)
		(drill 0.254)
		(layers "F.Cu" "B.Cu")
		(net "GND")
	)
	(via
		(at 248.92 -182.88)
		(size 0.508)
		(drill 0.254)
		(layers "F.Cu" "B.Cu")
		(net "GND")
	)
	(via
		(at 58.424572 -1.397)
		(size 0.508)
		(drill 0.254)
		(layers "F.Cu" "B.Cu")
		(net "GND")
	)
	(via
		(at 65.68059 -383.130044)
		(size 0.508)
		(drill 0.254)
		(layers "F.Cu" "B.Cu")
		(net "GND")
	)
	(via
		(at 254 -111.76)
		(size 0.508)
		(drill 0.254)
		(layers "F.Cu" "B.Cu")
		(net "GND")
	)
	(via
		(at 170.184572 -1.397)
		(size 0.508)
		(drill 0.254)
		(layers "F.Cu" "B.Cu")
		(net "GND")
	)
	(via
		(at 238.76 -86.36)
		(size 0.508)
		(drill 0.254)
		(layers "F.Cu" "B.Cu")
		(net "GND")
	)
	(via
		(at 99.709986 -504.603004)
		(size 0.508)
		(drill 0.254)
		(layers "F.Cu" "B.Cu")
		(net "GND")
	)
	(via
		(at 20.32 -502.92)
		(size 0.508)
		(drill 0.254)
		(layers "F.Cu" "B.Cu")
		(net "GND")
	)
	(via
		(at 81.28 -462.28)
		(size 0.508)
		(drill 0.254)
		(layers "F.Cu" "B.Cu")
		(net "GND")
	)
	(via
		(at 203.2 -360.68)
		(size 0.508)
		(drill 0.254)
		(layers "F.Cu" "B.Cu")
		(net "GND")
	)
	(via
		(at 127 -497.84)
		(size 0.508)
		(drill 0.254)
		(layers "F.Cu" "B.Cu")
		(net "GND")
	)
	(via
		(at 116.84 -91.44)
		(size 0.508)
		(drill 0.254)
		(layers "F.Cu" "B.Cu")
		(net "GND")
	)
	(via
		(at 187.96 -497.84)
		(size 0.508)
		(drill 0.254)
		(layers "F.Cu" "B.Cu")
		(net "GND")
	)
	(via
		(at 99.441 -309.499)
		(size 0.508)
		(drill 0.254)
		(layers "F.Cu" "B.Cu")
		(net "GND")
	)
	(via
		(at 203.2 -279.4)
		(size 0.508)
		(drill 0.254)
		(layers "F.Cu" "B.Cu")
		(net "GND")
	)
	(via
		(at 254 -187.96)
		(size 0.508)
		(drill 0.254)
		(layers "F.Cu" "B.Cu")
		(net "GND")
	)
	(via
		(at 73.4822 -432.2572)
		(size 0.508)
		(drill 0.254)
		(layers "F.Cu" "B.Cu")
		(net "GND")
	)
	(via
		(at 147.32 -167.64)
		(size 0.508)
		(drill 0.254)
		(layers "F.Cu" "B.Cu")
		(net "GND")
	)
	(via
		(at 243.84 -50.8)
		(size 0.508)
		(drill 0.254)
		(layers "F.Cu" "B.Cu")
		(net "GND")
	)
	(via
		(at 210.693 -453.39)
		(size 0.508)
		(drill 0.254)
		(layers "F.Cu" "B.Cu")
		(net "GND")
	)
	(via
		(at 182.88 -248.92)
		(size 0.508)
		(drill 0.254)
		(layers "F.Cu" "B.Cu")
		(net "GND")
	)
	(via
		(at 116.84 -60.96)
		(size 0.508)
		(drill 0.254)
		(layers "F.Cu" "B.Cu")
		(net "GND")
	)
	(via
		(at 254 -213.36)
		(size 0.508)
		(drill 0.254)
		(layers "F.Cu" "B.Cu")
		(net "GND")
	)
	(via
		(at 4.191 -225.933)
		(size 0.508)
		(drill 0.254)
		(layers "F.Cu" "B.Cu")
		(net "GND")
	)
	(via
		(at 26.2128 -264.795)
		(size 0.508)
		(drill 0.254)
		(layers "F.Cu" "B.Cu")
		(net "GND")
	)
	(via
		(at 29.718 -420.2684)
		(size 0.508)
		(drill 0.254)
		(layers "F.Cu" "B.Cu")
		(net "GND")
	)
	(via
		(at 137.16 -492.76)
		(size 0.508)
		(drill 0.254)
		(layers "F.Cu" "B.Cu")
		(net "GND")
	)
	(via
		(at 66.04 -441.96)
		(size 0.508)
		(drill 0.254)
		(layers "F.Cu" "B.Cu")
		(net "GND")
	)
	(via
		(at 14.859 -335.407)
		(size 0.508)
		(drill 0.254)
		(layers "F.Cu" "B.Cu")
		(net "GND")
	)
	(via
		(at 137.16 -223.52)
		(size 0.508)
		(drill 0.254)
		(layers "F.Cu" "B.Cu")
		(net "GND")
	)
	(via
		(at 37.61613 -277.390098)
		(size 0.508)
		(drill 0.254)
		(layers "F.Cu" "B.Cu")
		(net "GND")
	)
	(via
		(at 187.96 -66.04)
		(size 0.508)
		(drill 0.254)
		(layers "F.Cu" "B.Cu")
		(net "GND")
	)
	(via
		(at 157.48 -264.16)
		(size 0.508)
		(drill 0.254)
		(layers "F.Cu" "B.Cu")
		(net "GND")
	)
	(via
		(at 50.8 -111.76)
		(size 0.508)
		(drill 0.254)
		(layers "F.Cu" "B.Cu")
		(net "GND")
	)
	(via
		(at 132.08 -142.24)
		(size 0.508)
		(drill 0.254)
		(layers "F.Cu" "B.Cu")
		(net "GND")
	)
	(via
		(at 121.92 -142.24)
		(size 0.508)
		(drill 0.254)
		(layers "F.Cu" "B.Cu")
		(net "GND")
	)
	(via
		(at 26.8478 -393.2428)
		(size 0.508)
		(drill 0.254)
		(layers "F.Cu" "B.Cu")
		(net "GND")
	)
	(via
		(at 262.103108 -254.918464)
		(size 0.508)
		(drill 0.254)
		(layers "F.Cu" "B.Cu")
		(net "GND")
	)
	(via
		(at 198.12 -187.96)
		(size 0.508)
		(drill 0.254)
		(layers "F.Cu" "B.Cu")
		(net "GND")
	)
	(via
		(at 92.71 -429.006)
		(size 0.508)
		(drill 0.254)
		(layers "F.Cu" "B.Cu")
		(net "GND")
	)
	(via
		(at 31.2928 -494.6015)
		(size 0.508)
		(drill 0.254)
		(layers "F.Cu" "B.Cu")
		(net "GND")
	)
	(via
		(at 198.12 -193.04)
		(size 0.508)
		(drill 0.254)
		(layers "F.Cu" "B.Cu")
		(net "GND")
	)
	(via
		(at 162.56 -294.64)
		(size 0.508)
		(drill 0.254)
		(layers "F.Cu" "B.Cu")
		(net "GND")
	)
	(via
		(at 162.56 -167.64)
		(size 0.508)
		(drill 0.254)
		(layers "F.Cu" "B.Cu")
		(net "GND")
	)
	(via
		(at 86.36 -345.44)
		(size 0.508)
		(drill 0.254)
		(layers "F.Cu" "B.Cu")
		(net "GND")
	)
	(via
		(at 157.48 -60.96)
		(size 0.508)
		(drill 0.254)
		(layers "F.Cu" "B.Cu")
		(net "GND")
	)
	(via
		(at 152.4 -142.24)
		(size 0.508)
		(drill 0.254)
		(layers "F.Cu" "B.Cu")
		(net "GND")
	)
	(via
		(at 248.92 -20.32)
		(size 0.508)
		(drill 0.254)
		(layers "F.Cu" "B.Cu")
		(net "GND")
	)
	(via
		(at 101.6 -248.92)
		(size 0.508)
		(drill 0.254)
		(layers "F.Cu" "B.Cu")
		(net "GND")
	)
	(via
		(at 254 -157.48)
		(size 0.508)
		(drill 0.254)
		(layers "F.Cu" "B.Cu")
		(net "GND")
	)
	(via
		(at 177.8 -116.84)
		(size 0.508)
		(drill 0.254)
		(layers "F.Cu" "B.Cu")
		(net "GND")
	)
	(via
		(at 213.36 -243.84)
		(size 0.508)
		(drill 0.254)
		(layers "F.Cu" "B.Cu")
		(net "GND")
	)
	(via
		(at 182.88 -462.28)
		(size 0.508)
		(drill 0.254)
		(layers "F.Cu" "B.Cu")
		(net "GND")
	)
	(via
		(at 233.68 -182.88)
		(size 0.508)
		(drill 0.254)
		(layers "F.Cu" "B.Cu")
		(net "GND")
	)
	(via
		(at 50.8 -71.12)
		(size 0.508)
		(drill 0.254)
		(layers "F.Cu" "B.Cu")
		(net "GND")
	)
	(via
		(at 27.944572 -1.397)
		(size 0.508)
		(drill 0.254)
		(layers "F.Cu" "B.Cu")
		(net "GND")
	)
	(via
		(at 101.6 -20.32)
		(size 0.508)
		(drill 0.254)
		(layers "F.Cu" "B.Cu")
		(net "GND")
	)
	(via
		(at 193.04 -213.36)
		(size 0.508)
		(drill 0.254)
		(layers "F.Cu" "B.Cu")
		(net "GND")
	)
	(via
		(at 33.3502 -84.4296)
		(size 0.508)
		(drill 0.254)
		(layers "F.Cu" "B.Cu")
		(net "GND")
	)
	(via
		(at 137.16 -147.32)
		(size 0.508)
		(drill 0.254)
		(layers "F.Cu" "B.Cu")
		(net "GND")
	)
	(via
		(at 218.44 -325.12)
		(size 0.508)
		(drill 0.254)
		(layers "F.Cu" "B.Cu")
		(net "GND")
	)
	(via
		(at 106.68 -492.76)
		(size 0.508)
		(drill 0.254)
		(layers "F.Cu" "B.Cu")
		(net "GND")
	)
	(via
		(at 228.6 -5.08)
		(size 0.508)
		(drill 0.254)
		(layers "F.Cu" "B.Cu")
		(net "GND")
	)
	(via
		(at 142.24 -335.28)
		(size 0.508)
		(drill 0.254)
		(layers "F.Cu" "B.Cu")
		(net "GND")
	)
	(via
		(at 96.52 -335.28)
		(size 0.508)
		(drill 0.254)
		(layers "F.Cu" "B.Cu")
		(net "GND")
	)
	(via
		(at 222.616014 -159.189928)
		(size 0.508)
		(drill 0.254)
		(layers "F.Cu" "B.Cu")
		(net "GND")
	)
	(via
		(at 248.92 -147.32)
		(size 0.508)
		(drill 0.254)
		(layers "F.Cu" "B.Cu")
		(net "GND")
	)
	(via
		(at 86.36 -187.96)
		(size 0.508)
		(drill 0.254)
		(layers "F.Cu" "B.Cu")
		(net "GND")
	)
	(via
		(at 137.16 -198.12)
		(size 0.508)
		(drill 0.254)
		(layers "F.Cu" "B.Cu")
		(net "GND")
	)
	(via
		(at 182.88 -71.12)
		(size 0.508)
		(drill 0.254)
		(layers "F.Cu" "B.Cu")
		(net "GND")
	)
	(via
		(at 218.4654 -84.582)
		(size 0.508)
		(drill 0.254)
		(layers "F.Cu" "B.Cu")
		(net "GND")
	)
	(via
		(at 177.8 -340.36)
		(size 0.508)
		(drill 0.254)
		(layers "F.Cu" "B.Cu")
		(net "GND")
	)
	(via
		(at 60.96 -86.36)
		(size 0.508)
		(drill 0.254)
		(layers "F.Cu" "B.Cu")
		(net "GND")
	)
	(via
		(at 92.8116 -440.5376)
		(size 0.508)
		(drill 0.254)
		(layers "F.Cu" "B.Cu")
		(net "GND")
	)
	(via
		(at 157.48 -198.12)
		(size 0.508)
		(drill 0.254)
		(layers "F.Cu" "B.Cu")
		(net "GND")
	)
	(via
		(at 248.92 -320.04)
		(size 0.508)
		(drill 0.254)
		(layers "F.Cu" "B.Cu")
		(net "GND")
	)
	(via
		(at 157.48 -15.24)
		(size 0.508)
		(drill 0.254)
		(layers "F.Cu" "B.Cu")
		(net "GND")
	)
	(via
		(at 27.721052 -128.501648)
		(size 0.508)
		(drill 0.254)
		(layers "F.Cu" "B.Cu")
		(net "GND")
	)
	(via
		(at 259.08 -152.4)
		(size 0.508)
		(drill 0.254)
		(layers "F.Cu" "B.Cu")
		(net "GND")
	)
	(via
		(at 228.6 -101.6)
		(size 0.508)
		(drill 0.254)
		(layers "F.Cu" "B.Cu")
		(net "GND")
	)
	(via
		(at 213.36 -142.24)
		(size 0.508)
		(drill 0.254)
		(layers "F.Cu" "B.Cu")
		(net "GND")
	)
	(via
		(at 26.416 -31.75)
		(size 0.508)
		(drill 0.254)
		(layers "F.Cu" "B.Cu")
		(net "GND")
	)
	(via
		(at 142.24 -167.64)
		(size 0.508)
		(drill 0.254)
		(layers "F.Cu" "B.Cu")
		(net "GND")
	)
	(via
		(at 55.88 -106.68)
		(size 0.508)
		(drill 0.254)
		(layers "F.Cu" "B.Cu")
		(net "GND")
	)
	(via
		(at 90.7415 -31.496)
		(size 0.508)
		(drill 0.254)
		(layers "F.Cu" "B.Cu")
		(net "GND")
	)
	(via
		(at 66.04 -411.48)
		(size 0.508)
		(drill 0.254)
		(layers "F.Cu" "B.Cu")
		(net "GND")
	)
	(via
		(at 157.48 -314.96)
		(size 0.508)
		(drill 0.254)
		(layers "F.Cu" "B.Cu")
		(net "GND")
	)
	(via
		(at 262.103108 -92.358464)
		(size 0.508)
		(drill 0.254)
		(layers "F.Cu" "B.Cu")
		(net "GND")
	)
	(via
		(at 142.24 -86.36)
		(size 0.508)
		(drill 0.254)
		(layers "F.Cu" "B.Cu")
		(net "GND")
	)
	(via
		(at 233.68 -177.8)
		(size 0.508)
		(drill 0.254)
		(layers "F.Cu" "B.Cu")
		(net "GND")
	)
	(via
		(at 177.8 -218.44)
		(size 0.508)
		(drill 0.254)
		(layers "F.Cu" "B.Cu")
		(net "GND")
	)
	(via
		(at 226.441 -434.848)
		(size 0.508)
		(drill 0.254)
		(layers "F.Cu" "B.Cu")
		(net "GND")
	)
	(via
		(at 66.04 -132.08)
		(size 0.508)
		(drill 0.254)
		(layers "F.Cu" "B.Cu")
		(net "GND")
	)
	(via
		(at 127 -447.04)
		(size 0.508)
		(drill 0.254)
		(layers "F.Cu" "B.Cu")
		(net "GND")
	)
	(via
		(at 262.103108 -163.478464)
		(size 0.508)
		(drill 0.254)
		(layers "F.Cu" "B.Cu")
		(net "GND")
	)
	(via
		(at 24.384 -349.210122)
		(size 0.508)
		(drill 0.254)
		(layers "F.Cu" "B.Cu")
		(net "GND")
	)
	(via
		(at 208.28 -228.6)
		(size 0.508)
		(drill 0.254)
		(layers "F.Cu" "B.Cu")
		(net "GND")
	)
	(via
		(at 5.08 -132.08)
		(size 0.508)
		(drill 0.254)
		(layers "F.Cu" "B.Cu")
		(net "GND")
	)
	(via
		(at 210.664552 -430.657)
		(size 0.508)
		(drill 0.254)
		(layers "F.Cu" "B.Cu")
		(net "GND")
	)
	(via
		(at 157.48 -127)
		(size 0.508)
		(drill 0.254)
		(layers "F.Cu" "B.Cu")
		(net "GND")
	)
	(via
		(at 134.624572 -1.397)
		(size 0.508)
		(drill 0.254)
		(layers "F.Cu" "B.Cu")
		(net "GND")
	)
	(via
		(at 203.2 -335.28)
		(size 0.508)
		(drill 0.254)
		(layers "F.Cu" "B.Cu")
		(net "GND")
	)
	(via
		(at 121.92 -233.68)
		(size 0.508)
		(drill 0.254)
		(layers "F.Cu" "B.Cu")
		(net "GND")
	)
	(via
		(at 147.32 -137.16)
		(size 0.508)
		(drill 0.254)
		(layers "F.Cu" "B.Cu")
		(net "GND")
	)
	(via
		(at 152.4 -101.6)
		(size 0.508)
		(drill 0.254)
		(layers "F.Cu" "B.Cu")
		(net "GND")
	)
	(via
		(at 243.84 -502.92)
		(size 0.508)
		(drill 0.254)
		(layers "F.Cu" "B.Cu")
		(net "GND")
	)
	(via
		(at 177.8 -111.76)
		(size 0.508)
		(drill 0.254)
		(layers "F.Cu" "B.Cu")
		(net "GND")
	)
	(via
		(at 187.96 -350.52)
		(size 0.508)
		(drill 0.254)
		(layers "F.Cu" "B.Cu")
		(net "GND")
	)
	(via
		(at 262.103108 -16.158464)
		(size 0.508)
		(drill 0.254)
		(layers "F.Cu" "B.Cu")
		(net "GND")
	)
	(via
		(at 259.08 -15.24)
		(size 0.508)
		(drill 0.254)
		(layers "F.Cu" "B.Cu")
		(net "GND")
	)
	(via
		(at 162.56 -132.08)
		(size 0.508)
		(drill 0.254)
		(layers "F.Cu" "B.Cu")
		(net "GND")
	)
	(via
		(at 4.191 -223.490282)
		(size 0.508)
		(drill 0.254)
		(layers "F.Cu" "B.Cu")
		(net "GND")
	)
	(via
		(at 226.3775 -136.525)
		(size 0.508)
		(drill 0.254)
		(layers "F.Cu" "B.Cu")
		(net "GND")
	)
	(via
		(at 137.16 -208.28)
		(size 0.508)
		(drill 0.254)
		(layers "F.Cu" "B.Cu")
		(net "GND")
	)
	(via
		(at 34.798 -423.291)
		(size 0.508)
		(drill 0.254)
		(layers "F.Cu" "B.Cu")
		(net "GND")
	)
	(via
		(at 262.103108 -290.478464)
		(size 0.508)
		(drill 0.254)
		(layers "F.Cu" "B.Cu")
		(net "GND")
	)
	(via
		(at 60.96 -55.88)
		(size 0.508)
		(drill 0.254)
		(layers "F.Cu" "B.Cu")
		(net "GND")
	)
	(via
		(at 6.223 -204.27315)
		(size 0.508)
		(drill 0.254)
		(layers "F.Cu" "B.Cu")
		(net "GND")
	)
	(via
		(at 262.103108 -193.958464)
		(size 0.508)
		(drill 0.254)
		(layers "F.Cu" "B.Cu")
		(net "GND")
	)
	(via
		(at 147.32 -127)
		(size 0.508)
		(drill 0.254)
		(layers "F.Cu" "B.Cu")
		(net "GND")
	)
	(via
		(at 24.384 -443.257686)
		(size 0.508)
		(drill 0.254)
		(layers "F.Cu" "B.Cu")
		(net "GND")
	)
	(via
		(at 10.541 -299.212)
		(size 0.508)
		(drill 0.254)
		(layers "F.Cu" "B.Cu")
		(net "GND")
	)
	(via
		(at 147.32 -35.56)
		(size 0.508)
		(drill 0.254)
		(layers "F.Cu" "B.Cu")
		(net "GND")
	)
	(via
		(at 91.186 -100.203)
		(size 0.508)
		(drill 0.254)
		(layers "F.Cu" "B.Cu")
		(net "GND")
	)
	(via
		(at 259.08 -76.2)
		(size 0.508)
		(drill 0.254)
		(layers "F.Cu" "B.Cu")
		(net "GND")
	)
	(via
		(at 96.774 -305.181)
		(size 0.508)
		(drill 0.254)
		(layers "F.Cu" "B.Cu")
		(net "GND")
	)
	(via
		(at 6.223 -447.642742)
		(size 0.508)
		(drill 0.254)
		(layers "F.Cu" "B.Cu")
		(net "GND")
	)
	(via
		(at 24.384 -132.009896)
		(size 0.508)
		(drill 0.254)
		(layers "F.Cu" "B.Cu")
		(net "GND")
	)
	(via
		(at 198.12 -502.92)
		(size 0.508)
		(drill 0.254)
		(layers "F.Cu" "B.Cu")
		(net "GND")
	)
	(via
		(at 11.4554 -470.1032)
		(size 0.508)
		(drill 0.254)
		(layers "F.Cu" "B.Cu")
		(net "GND")
	)
	(via
		(at 50.8 -492.76)
		(size 0.508)
		(drill 0.254)
		(layers "F.Cu" "B.Cu")
		(net "GND")
	)
	(via
		(at 43.58513 -482.84511)
		(size 0.508)
		(drill 0.254)
		(layers "F.Cu" "B.Cu")
		(net "GND")
	)
	(via
		(at 167.64 -187.96)
		(size 0.508)
		(drill 0.254)
		(layers "F.Cu" "B.Cu")
		(net "GND")
	)
	(via
		(at 236.982 -432.816)
		(size 0.508)
		(drill 0.254)
		(layers "F.Cu" "B.Cu")
		(net "GND")
	)
	(via
		(at 162.56 -492.76)
		(size 0.508)
		(drill 0.254)
		(layers "F.Cu" "B.Cu")
		(net "GND")
	)
	(via
		(at 223.52 -330.2)
		(size 0.508)
		(drill 0.254)
		(layers "F.Cu" "B.Cu")
		(net "GND")
	)
	(via
		(at 167.64 -86.36)
		(size 0.508)
		(drill 0.254)
		(layers "F.Cu" "B.Cu")
		(net "GND")
	)
	(via
		(at 187.96 -304.8)
		(size 0.508)
		(drill 0.254)
		(layers "F.Cu" "B.Cu")
		(net "GND")
	)
	(via
		(at 162.56 -482.6)
		(size 0.508)
		(drill 0.254)
		(layers "F.Cu" "B.Cu")
		(net "GND")
	)
	(via
		(at 237.49 -387.35)
		(size 0.7112)
		(drill 0.4064)
		(layers "F.Cu" "B.Cu")
		(net "GND")
	)
	(via
		(at 228.585014 -471.41511)
		(size 0.508)
		(drill 0.254)
		(layers "F.Cu" "B.Cu")
		(net "GND")
	)
	(via
		(at 198.12 -25.4)
		(size 0.508)
		(drill 0.254)
		(layers "F.Cu" "B.Cu")
		(net "GND")
	)
	(via
		(at 254 -15.24)
		(size 0.508)
		(drill 0.254)
		(layers "F.Cu" "B.Cu")
		(net "GND")
	)
	(via
		(at 76.2 -259.08)
		(size 0.508)
		(drill 0.254)
		(layers "F.Cu" "B.Cu")
		(net "GND")
	)
	(via
		(at 127 -314.96)
		(size 0.508)
		(drill 0.254)
		(layers "F.Cu" "B.Cu")
		(net "GND")
	)
	(via
		(at 106.68 -269.24)
		(size 0.508)
		(drill 0.254)
		(layers "F.Cu" "B.Cu")
		(net "GND")
	)
	(via
		(at 111.76 -86.36)
		(size 0.508)
		(drill 0.254)
		(layers "F.Cu" "B.Cu")
		(net "GND")
	)
	(via
		(at 172.72 -304.8)
		(size 0.508)
		(drill 0.254)
		(layers "F.Cu" "B.Cu")
		(net "GND")
	)
	(via
		(at 31.496 -31.510986)
		(size 0.508)
		(drill 0.254)
		(layers "F.Cu" "B.Cu")
		(net "GND")
	)
	(via
		(at 198.12 -335.28)
		(size 0.508)
		(drill 0.254)
		(layers "F.Cu" "B.Cu")
		(net "GND")
	)
	(via
		(at 243.84 -477.52)
		(size 0.508)
		(drill 0.254)
		(layers "F.Cu" "B.Cu")
		(net "GND")
	)
	(via
		(at 228.6 -116.84)
		(size 0.508)
		(drill 0.254)
		(layers "F.Cu" "B.Cu")
		(net "GND")
	)
	(via
		(at 66.04 -40.64)
		(size 0.508)
		(drill 0.254)
		(layers "F.Cu" "B.Cu")
		(net "GND")
	)
	(via
		(at 6.223 -297.47464)
		(size 0.508)
		(drill 0.254)
		(layers "F.Cu" "B.Cu")
		(net "GND")
	)
	(via
		(at 33.3756 -188.3918)
		(size 0.508)
		(drill 0.254)
		(layers "F.Cu" "B.Cu")
		(net "GND")
	)
	(via
		(at 137.16 -55.88)
		(size 0.508)
		(drill 0.254)
		(layers "F.Cu" "B.Cu")
		(net "GND")
	)
	(via
		(at 172.72 -182.88)
		(size 0.508)
		(drill 0.254)
		(layers "F.Cu" "B.Cu")
		(net "GND")
	)
	(via
		(at 101.6 -182.88)
		(size 0.508)
		(drill 0.254)
		(layers "F.Cu" "B.Cu")
		(net "GND")
	)
	(via
		(at 35.9918 -16.4846)
		(size 0.508)
		(drill 0.254)
		(layers "F.Cu" "B.Cu")
		(net "GND")
	)
	(via
		(at 198.12 -45.72)
		(size 0.508)
		(drill 0.254)
		(layers "F.Cu" "B.Cu")
		(net "GND")
	)
	(via
		(at 45.72 -381)
		(size 0.508)
		(drill 0.254)
		(layers "F.Cu" "B.Cu")
		(net "GND")
	)
	(via
		(at 208.28 -233.68)
		(size 0.508)
		(drill 0.254)
		(layers "F.Cu" "B.Cu")
		(net "GND")
	)
	(via
		(at 254 -20.32)
		(size 0.508)
		(drill 0.254)
		(layers "F.Cu" "B.Cu")
		(net "GND")
	)
	(via
		(at 20.32 -152.4)
		(size 0.508)
		(drill 0.254)
		(layers "F.Cu" "B.Cu")
		(net "GND")
	)
	(via
		(at 132.08 -121.92)
		(size 0.508)
		(drill 0.254)
		(layers "F.Cu" "B.Cu")
		(net "GND")
	)
	(via
		(at 18.415 -248.20499)
		(size 0.508)
		(drill 0.254)
		(layers "F.Cu" "B.Cu")
		(net "GND")
	)
	(via
		(at 121.92 -375.92)
		(size 0.508)
		(drill 0.254)
		(layers "F.Cu" "B.Cu")
		(net "GND")
	)
	(via
		(at 116.84 -365.76)
		(size 0.508)
		(drill 0.254)
		(layers "F.Cu" "B.Cu")
		(net "GND")
	)
	(via
		(at 4.191 -446.037208)
		(size 0.508)
		(drill 0.254)
		(layers "F.Cu" "B.Cu")
		(net "GND")
	)
	(via
		(at 24.384 -434.610002)
		(size 0.508)
		(drill 0.254)
		(layers "F.Cu" "B.Cu")
		(net "GND")
	)
	(via
		(at 60.96 -269.24)
		(size 0.508)
		(drill 0.254)
		(layers "F.Cu" "B.Cu")
		(net "GND")
	)
	(via
		(at 162.56 -50.8)
		(size 0.508)
		(drill 0.254)
		(layers "F.Cu" "B.Cu")
		(net "GND")
	)
	(via
		(at 208.28 -304.8)
		(size 0.508)
		(drill 0.254)
		(layers "F.Cu" "B.Cu")
		(net "GND")
	)
	(via
		(at 193.0146 -497.6368)
		(size 0.508)
		(drill 0.254)
		(layers "F.Cu" "B.Cu")
		(net "GND")
	)
	(via
		(at 216.145364 -402.97735)
		(size 0.508)
		(drill 0.254)
		(layers "F.Cu" "B.Cu")
		(net "GND")
	)
	(via
		(at 127 -101.6)
		(size 0.508)
		(drill 0.254)
		(layers "F.Cu" "B.Cu")
		(net "GND")
	)
	(via
		(at 157.48 -218.44)
		(size 0.508)
		(drill 0.254)
		(layers "F.Cu" "B.Cu")
		(net "GND")
	)
	(via
		(at 238.76 -96.52)
		(size 0.508)
		(drill 0.254)
		(layers "F.Cu" "B.Cu")
		(net "GND")
	)
	(via
		(at 219.314014 -279.398984)
		(size 0.508)
		(drill 0.254)
		(layers "F.Cu" "B.Cu")
		(net "GND")
	)
	(via
		(at 96.52 -40.64)
		(size 0.508)
		(drill 0.254)
		(layers "F.Cu" "B.Cu")
		(net "GND")
	)
	(via
		(at 101.6 -386.08)
		(size 0.508)
		(drill 0.254)
		(layers "F.Cu" "B.Cu")
		(net "GND")
	)
	(via
		(at 177.8 -452.12)
		(size 0.508)
		(drill 0.254)
		(layers "F.Cu" "B.Cu")
		(net "GND")
	)
	(via
		(at 81.28 -482.6)
		(size 0.508)
		(drill 0.254)
		(layers "F.Cu" "B.Cu")
		(net "GND")
	)
	(via
		(at 221.742 -403.606)
		(size 0.508)
		(drill 0.254)
		(layers "F.Cu" "B.Cu")
		(net "GND")
	)
	(via
		(at 91.44 -182.88)
		(size 0.508)
		(drill 0.254)
		(layers "F.Cu" "B.Cu")
		(net "GND")
	)
	(via
		(at 45.72 -152.4)
		(size 0.508)
		(drill 0.254)
		(layers "F.Cu" "B.Cu")
		(net "GND")
	)
	(via
		(at 193.04 -35.56)
		(size 0.508)
		(drill 0.254)
		(layers "F.Cu" "B.Cu")
		(net "GND")
	)
	(via
		(at 27.686 -228.219)
		(size 0.508)
		(drill 0.254)
		(layers "F.Cu" "B.Cu")
		(net "GND")
	)
	(via
		(at 71.12 -396.24)
		(size 0.508)
		(drill 0.254)
		(layers "F.Cu" "B.Cu")
		(net "GND")
	)
	(via
		(at 157.48 -137.16)
		(size 0.508)
		(drill 0.254)
		(layers "F.Cu" "B.Cu")
		(net "GND")
	)
	(via
		(at 254 -203.2)
		(size 0.508)
		(drill 0.254)
		(layers "F.Cu" "B.Cu")
		(net "GND")
	)
	(via
		(at 6.223 -427.538388)
		(size 0.508)
		(drill 0.254)
		(layers "F.Cu" "B.Cu")
		(net "GND")
	)
	(via
		(at 18.034 -14.732)
		(size 0.508)
		(drill 0.254)
		(layers "F.Cu" "B.Cu")
		(net "GND")
	)
	(via
		(at 97.4725 -292.227)
		(size 0.508)
		(drill 0.254)
		(layers "F.Cu" "B.Cu")
		(net "GND")
	)
	(via
		(at 203.2 -309.88)
		(size 0.508)
		(drill 0.254)
		(layers "F.Cu" "B.Cu")
		(net "GND")
	)
	(via
		(at 43.58513 -360.795062)
		(size 0.508)
		(drill 0.254)
		(layers "F.Cu" "B.Cu")
		(net "GND")
	)
	(via
		(at 55.88 -81.28)
		(size 0.508)
		(drill 0.254)
		(layers "F.Cu" "B.Cu")
		(net "GND")
	)
	(via
		(at 127 -66.04)
		(size 0.508)
		(drill 0.254)
		(layers "F.Cu" "B.Cu")
		(net "GND")
	)
	(via
		(at 137.16 -279.4)
		(size 0.508)
		(drill 0.254)
		(layers "F.Cu" "B.Cu")
		(net "GND")
	)
	(via
		(at 50.8 -66.04)
		(size 0.508)
		(drill 0.254)
		(layers "F.Cu" "B.Cu")
		(net "GND")
	)
	(via
		(at 172.72 -462.28)
		(size 0.508)
		(drill 0.254)
		(layers "F.Cu" "B.Cu")
		(net "GND")
	)
	(via
		(at 262.103108 -320.958464)
		(size 0.508)
		(drill 0.254)
		(layers "F.Cu" "B.Cu")
		(net "GND")
	)
	(via
		(at 193.04 -477.52)
		(size 0.508)
		(drill 0.254)
		(layers "F.Cu" "B.Cu")
		(net "GND")
	)
	(via
		(at 116.84 -86.36)
		(size 0.508)
		(drill 0.254)
		(layers "F.Cu" "B.Cu")
		(net "GND")
	)
	(via
		(at 237.49 -397.51)
		(size 0.7112)
		(drill 0.4064)
		(layers "F.Cu" "B.Cu")
		(net "GND")
	)
	(via
		(at 40.259 -144.653)
		(size 0.508)
		(drill 0.254)
		(layers "F.Cu" "B.Cu")
		(net "GND")
	)
	(via
		(at 95.377 -305.181)
		(size 0.508)
		(drill 0.254)
		(layers "F.Cu" "B.Cu")
		(net "GND")
	)
	(via
		(at 240.03 -400.05)
		(size 0.7112)
		(drill 0.4064)
		(layers "F.Cu" "B.Cu")
		(net "GND")
	)
	(via
		(at 262.103108 -443.476126)
		(size 0.508)
		(drill 0.254)
		(layers "F.Cu" "B.Cu")
		(net "GND")
	)
	(via
		(at 48.0822 -400.6088)
		(size 0.508)
		(drill 0.254)
		(layers "F.Cu" "B.Cu")
		(net "GND")
	)
	(via
		(at 142.24 -50.8)
		(size 0.508)
		(drill 0.254)
		(layers "F.Cu" "B.Cu")
		(net "GND")
	)
	(via
		(at 254 -91.44)
		(size 0.508)
		(drill 0.254)
		(layers "F.Cu" "B.Cu")
		(net "GND")
	)
	(via
		(at 262.103108 -158.398464)
		(size 0.508)
		(drill 0.254)
		(layers "F.Cu" "B.Cu")
		(net "GND")
	)
	(via
		(at 142.24 -96.52)
		(size 0.508)
		(drill 0.254)
		(layers "F.Cu" "B.Cu")
		(net "GND")
	)
	(via
		(at 33.669986 -504.603004)
		(size 0.508)
		(drill 0.254)
		(layers "F.Cu" "B.Cu")
		(net "GND")
	)
	(via
		(at 222.616014 -375.590054)
		(size 0.508)
		(drill 0.254)
		(layers "F.Cu" "B.Cu")
		(net "GND")
	)
	(via
		(at 259.08 -81.28)
		(size 0.508)
		(drill 0.254)
		(layers "F.Cu" "B.Cu")
		(net "GND")
	)
	(via
		(at 84.469986 -504.603004)
		(size 0.508)
		(drill 0.254)
		(layers "F.Cu" "B.Cu")
		(net "GND")
	)
	(via
		(at 245.11 -389.89)
		(size 0.7112)
		(drill 0.4064)
		(layers "F.Cu" "B.Cu")
		(net "GND")
	)
	(via
		(at 33.401 -291.2618)
		(size 0.508)
		(drill 0.254)
		(layers "F.Cu" "B.Cu")
		(net "GND")
	)
	(via
		(at 91.44 -40.64)
		(size 0.508)
		(drill 0.254)
		(layers "F.Cu" "B.Cu")
		(net "GND")
	)
	(via
		(at 81.28 -274.32)
		(size 0.508)
		(drill 0.254)
		(layers "F.Cu" "B.Cu")
		(net "GND")
	)
	(via
		(at 254 -142.24)
		(size 0.508)
		(drill 0.254)
		(layers "F.Cu" "B.Cu")
		(net "GND")
	)
	(via
		(at 106.68 -431.8)
		(size 0.508)
		(drill 0.254)
		(layers "F.Cu" "B.Cu")
		(net "GND")
	)
	(via
		(at 6.223 -179.662328)
		(size 0.508)
		(drill 0.254)
		(layers "F.Cu" "B.Cu")
		(net "GND")
	)
	(via
		(at 31.369 -382.3208)
		(size 0.508)
		(drill 0.254)
		(layers "F.Cu" "B.Cu")
		(net "GND")
	)
	(via
		(at 182.88 -330.2)
		(size 0.508)
		(drill 0.254)
		(layers "F.Cu" "B.Cu")
		(net "GND")
	)
	(via
		(at 167.64 -375.92)
		(size 0.508)
		(drill 0.254)
		(layers "F.Cu" "B.Cu")
		(net "GND")
	)
	(via
		(at 10.7442 -469.0745)
		(size 0.508)
		(drill 0.254)
		(layers "F.Cu" "B.Cu")
		(net "GND")
	)
	(via
		(at 172.72 -274.32)
		(size 0.508)
		(drill 0.254)
		(layers "F.Cu" "B.Cu")
		(net "GND")
	)
	(via
		(at 51.689 -411.099)
		(size 0.508)
		(drill 0.254)
		(layers "F.Cu" "B.Cu")
		(net "GND")
	)
	(via
		(at 4.169918 -333.142082)
		(size 0.508)
		(drill 0.254)
		(layers "F.Cu" "B.Cu")
		(net "GND")
	)
	(via
		(at 31.741364 -196.98335)
		(size 0.508)
		(drill 0.254)
		(layers "F.Cu" "B.Cu")
		(net "GND")
	)
	(via
		(at 22.371304 -400.284696)
		(size 0.508)
		(drill 0.254)
		(layers "F.Cu" "B.Cu")
		(net "GND")
	)
	(via
		(at 106.68 -345.44)
		(size 0.508)
		(drill 0.254)
		(layers "F.Cu" "B.Cu")
		(net "GND")
	)
	(via
		(at 18.415 -126.154942)
		(size 0.508)
		(drill 0.254)
		(layers "F.Cu" "B.Cu")
		(net "GND")
	)
	(via
		(at 86.36 -370.84)
		(size 0.508)
		(drill 0.254)
		(layers "F.Cu" "B.Cu")
		(net "GND")
	)
	(via
		(at 228.981 -79.375)
		(size 0.508)
		(drill 0.254)
		(layers "F.Cu" "B.Cu")
		(net "GND")
	)
	(via
		(at 167.64 -152.4)
		(size 0.508)
		(drill 0.254)
		(layers "F.Cu" "B.Cu")
		(net "GND")
	)
	(via
		(at 208.28 -55.88)
		(size 0.508)
		(drill 0.254)
		(layers "F.Cu" "B.Cu")
		(net "GND")
	)
	(via
		(at 1.397 -137.409428)
		(size 0.508)
		(drill 0.254)
		(layers "F.Cu" "B.Cu")
		(net "GND")
	)
	(via
		(at 111.76 -96.52)
		(size 0.508)
		(drill 0.254)
		(layers "F.Cu" "B.Cu")
		(net "GND")
	)
	(via
		(at 243.84 -30.48)
		(size 0.508)
		(drill 0.254)
		(layers "F.Cu" "B.Cu")
		(net "GND")
	)
	(via
		(at 127 -243.84)
		(size 0.508)
		(drill 0.254)
		(layers "F.Cu" "B.Cu")
		(net "GND")
	)
	(via
		(at 233.68 -15.24)
		(size 0.508)
		(drill 0.254)
		(layers "F.Cu" "B.Cu")
		(net "GND")
	)
	(via
		(at 132.08 -269.24)
		(size 0.508)
		(drill 0.254)
		(layers "F.Cu" "B.Cu")
		(net "GND")
	)
	(via
		(at 92.329 -295.91)
		(size 0.508)
		(drill 0.254)
		(layers "F.Cu" "B.Cu")
		(net "GND")
	)
	(via
		(at 4.191 -213.890098)
		(size 0.508)
		(drill 0.254)
		(layers "F.Cu" "B.Cu")
		(net "GND")
	)
	(via
		(at 219.274644 -377.479052)
		(size 0.508)
		(drill 0.254)
		(layers "F.Cu" "B.Cu")
		(net "GND")
	)
	(via
		(at 89.549986 -504.603004)
		(size 0.508)
		(drill 0.254)
		(layers "F.Cu" "B.Cu")
		(net "GND")
	)
	(via
		(at 37.61613 -179.189888)
		(size 0.508)
		(drill 0.254)
		(layers "F.Cu" "B.Cu")
		(net "GND")
	)
	(via
		(at 177.8 -365.76)
		(size 0.508)
		(drill 0.254)
		(layers "F.Cu" "B.Cu")
		(net "GND")
	)
	(via
		(at 77.3176 -105.7148)
		(size 0.508)
		(drill 0.254)
		(layers "F.Cu" "B.Cu")
		(net "GND")
	)
	(via
		(at 78.486 -296.291)
		(size 0.508)
		(drill 0.254)
		(layers "F.Cu" "B.Cu")
		(net "GND")
	)
	(via
		(at 243.84 -187.96)
		(size 0.508)
		(drill 0.254)
		(layers "F.Cu" "B.Cu")
		(net "GND")
	)
	(via
		(at 92.71 -98.806)
		(size 0.508)
		(drill 0.254)
		(layers "F.Cu" "B.Cu")
		(net "GND")
	)
	(via
		(at 37.61613 -377.9901)
		(size 0.508)
		(drill 0.254)
		(layers "F.Cu" "B.Cu")
		(net "GND")
	)
	(via
		(at 106.68 -177.8)
		(size 0.508)
		(drill 0.254)
		(layers "F.Cu" "B.Cu")
		(net "GND")
	)
	(via
		(at 248.92 -492.76)
		(size 0.508)
		(drill 0.254)
		(layers "F.Cu" "B.Cu")
		(net "GND")
	)
	(via
		(at 106.68 -5.08)
		(size 0.508)
		(drill 0.254)
		(layers "F.Cu" "B.Cu")
		(net "GND")
	)
	(via
		(at 19.635724 -65.882774)
		(size 0.508)
		(drill 0.254)
		(layers "F.Cu" "B.Cu")
		(net "GND")
	)
	(via
		(at 35.433 -93.98)
		(size 0.508)
		(drill 0.254)
		(layers "F.Cu" "B.Cu")
		(net "GND")
	)
	(via
		(at 121.92 -172.72)
		(size 0.508)
		(drill 0.254)
		(layers "F.Cu" "B.Cu")
		(net "GND")
	)
	(via
		(at 262.103108 -275.238464)
		(size 0.508)
		(drill 0.254)
		(layers "F.Cu" "B.Cu")
		(net "GND")
	)
	(via
		(at 198.12 -127)
		(size 0.508)
		(drill 0.254)
		(layers "F.Cu" "B.Cu")
		(net "GND")
	)
	(via
		(at 187.96 -76.2)
		(size 0.508)
		(drill 0.254)
		(layers "F.Cu" "B.Cu")
		(net "GND")
	)
	(via
		(at 142.24 -71.12)
		(size 0.508)
		(drill 0.254)
		(layers "F.Cu" "B.Cu")
		(net "GND")
	)
	(via
		(at 142.24 -248.92)
		(size 0.508)
		(drill 0.254)
		(layers "F.Cu" "B.Cu")
		(net "GND")
	)
	(via
		(at 237.49 -392.43)
		(size 0.7112)
		(drill 0.4064)
		(layers "F.Cu" "B.Cu")
		(net "GND")
	)
	(via
		(at 147.32 -198.12)
		(size 0.508)
		(drill 0.254)
		(layers "F.Cu" "B.Cu")
		(net "GND")
	)
	(via
		(at 223.52 -45.72)
		(size 0.508)
		(drill 0.254)
		(layers "F.Cu" "B.Cu")
		(net "GND")
	)
	(via
		(at 121.92 -198.12)
		(size 0.508)
		(drill 0.254)
		(layers "F.Cu" "B.Cu")
		(net "GND")
	)
	(via
		(at 259.08 -182.88)
		(size 0.508)
		(drill 0.254)
		(layers "F.Cu" "B.Cu")
		(net "GND")
	)
	(via
		(at 37.61613 -80.989932)
		(size 0.508)
		(drill 0.254)
		(layers "F.Cu" "B.Cu")
		(net "GND")
	)
	(via
		(at 182.88 -264.16)
		(size 0.508)
		(drill 0.254)
		(layers "F.Cu" "B.Cu")
		(net "GND")
	)
	(via
		(at 87.3125 -114.554)
		(size 0.508)
		(drill 0.254)
		(layers "F.Cu" "B.Cu")
		(net "GND")
	)
	(via
		(at 4.191 -186.055)
		(size 0.508)
		(drill 0.254)
		(layers "F.Cu" "B.Cu")
		(net "GND")
	)
	(via
		(at 4.191 -283.166312)
		(size 0.508)
		(drill 0.254)
		(layers "F.Cu" "B.Cu")
		(net "GND")
	)
	(via
		(at 6.223 -391.59434)
		(size 0.508)
		(drill 0.254)
		(layers "F.Cu" "B.Cu")
		(net "GND")
	)
	(via
		(at 262.103108 -489.196126)
		(size 0.508)
		(drill 0.254)
		(layers "F.Cu" "B.Cu")
		(net "GND")
	)
	(via
		(at 259.08 -55.88)
		(size 0.508)
		(drill 0.254)
		(layers "F.Cu" "B.Cu")
		(net "GND")
	)
	(via
		(at 111.76 -350.52)
		(size 0.508)
		(drill 0.254)
		(layers "F.Cu" "B.Cu")
		(net "GND")
	)
	(via
		(at 157.48 -40.64)
		(size 0.508)
		(drill 0.254)
		(layers "F.Cu" "B.Cu")
		(net "GND")
	)
	(via
		(at 243.84 -304.8)
		(size 0.508)
		(drill 0.254)
		(layers "F.Cu" "B.Cu")
		(net "GND")
	)
	(via
		(at 6.223 -181.073044)
		(size 0.508)
		(drill 0.254)
		(layers "F.Cu" "B.Cu")
		(net "GND")
	)
	(via
		(at 147.32 -50.8)
		(size 0.508)
		(drill 0.254)
		(layers "F.Cu" "B.Cu")
		(net "GND")
	)
	(via
		(at 127 -60.96)
		(size 0.508)
		(drill 0.254)
		(layers "F.Cu" "B.Cu")
		(net "GND")
	)
	(via
		(at 6.223 -213.82228)
		(size 0.508)
		(drill 0.254)
		(layers "F.Cu" "B.Cu")
		(net "GND")
	)
	(via
		(at 19.304 -179.451)
		(size 0.508)
		(drill 0.254)
		(layers "F.Cu" "B.Cu")
		(net "GND")
	)
	(via
		(at 243.84 -162.56)
		(size 0.508)
		(drill 0.254)
		(layers "F.Cu" "B.Cu")
		(net "GND")
	)
	(via
		(at 106.68 -325.12)
		(size 0.508)
		(drill 0.254)
		(layers "F.Cu" "B.Cu")
		(net "GND")
	)
	(via
		(at 27.686 -244.147848)
		(size 0.508)
		(drill 0.254)
		(layers "F.Cu" "B.Cu")
		(net "GND")
	)
	(via
		(at 167.64 -121.92)
		(size 0.508)
		(drill 0.254)
		(layers "F.Cu" "B.Cu")
		(net "GND")
	)
	(via
		(at 147.32 -502.92)
		(size 0.508)
		(drill 0.254)
		(layers "F.Cu" "B.Cu")
		(net "GND")
	)
	(via
		(at 137.16 -167.64)
		(size 0.508)
		(drill 0.254)
		(layers "F.Cu" "B.Cu")
		(net "GND")
	)
	(via
		(at 177.8 -284.48)
		(size 0.508)
		(drill 0.254)
		(layers "F.Cu" "B.Cu")
		(net "GND")
	)
	(via
		(at 27.721052 -129.917952)
		(size 0.508)
		(drill 0.254)
		(layers "F.Cu" "B.Cu")
		(net "GND")
	)
	(via
		(at 157.48 -35.56)
		(size 0.508)
		(drill 0.254)
		(layers "F.Cu" "B.Cu")
		(net "GND")
	)
	(via
		(at 152.4 -370.84)
		(size 0.508)
		(drill 0.254)
		(layers "F.Cu" "B.Cu")
		(net "GND")
	)
	(via
		(at 127 -355.6)
		(size 0.508)
		(drill 0.254)
		(layers "F.Cu" "B.Cu")
		(net "GND")
	)
	(via
		(at 152.4 -264.16)
		(size 0.508)
		(drill 0.254)
		(layers "F.Cu" "B.Cu")
		(net "GND")
	)
	(via
		(at 37.338 -299.8216)
		(size 0.508)
		(drill 0.254)
		(layers "F.Cu" "B.Cu")
		(net "GND")
	)
	(via
		(at 152.4 -269.24)
		(size 0.508)
		(drill 0.254)
		(layers "F.Cu" "B.Cu")
		(net "GND")
	)
	(via
		(at 137.16 -345.44)
		(size 0.508)
		(drill 0.254)
		(layers "F.Cu" "B.Cu")
		(net "GND")
	)
	(via
		(at 162.56 -55.88)
		(size 0.508)
		(drill 0.254)
		(layers "F.Cu" "B.Cu")
		(net "GND")
	)
	(via
		(at 157.48 -502.92)
		(size 0.508)
		(drill 0.254)
		(layers "F.Cu" "B.Cu")
		(net "GND")
	)
	(via
		(at 142.24 -355.6)
		(size 0.508)
		(drill 0.254)
		(layers "F.Cu" "B.Cu")
		(net "GND")
	)
	(via
		(at 4.191 -343.090246)
		(size 0.508)
		(drill 0.254)
		(layers "F.Cu" "B.Cu")
		(net "GND")
	)
	(via
		(at 172.72 -203.2)
		(size 0.508)
		(drill 0.254)
		(layers "F.Cu" "B.Cu")
		(net "GND")
	)
	(via
		(at 17.145 -34.50082)
		(size 0.508)
		(drill 0.254)
		(layers "F.Cu" "B.Cu")
		(net "GND")
	)
	(via
		(at 221.986348 -427.101)
		(size 0.508)
		(drill 0.254)
		(layers "F.Cu" "B.Cu")
		(net "GND")
	)
	(via
		(at 254 -116.84)
		(size 0.508)
		(drill 0.254)
		(layers "F.Cu" "B.Cu")
		(net "GND")
	)
	(via
		(at 21.017992 -372.25224)
		(size 0.508)
		(drill 0.254)
		(layers "F.Cu" "B.Cu")
		(net "GND")
	)
	(via
		(at 157.48 -243.84)
		(size 0.508)
		(drill 0.254)
		(layers "F.Cu" "B.Cu")
		(net "GND")
	)
	(via
		(at 137.16 -218.44)
		(size 0.508)
		(drill 0.254)
		(layers "F.Cu" "B.Cu")
		(net "GND")
	)
	(via
		(at 56.0832 -447.9925)
		(size 0.508)
		(drill 0.254)
		(layers "F.Cu" "B.Cu")
		(net "GND")
	)
	(via
		(at 66.04 -223.52)
		(size 0.508)
		(drill 0.254)
		(layers "F.Cu" "B.Cu")
		(net "GND")
	)
	(via
		(at 37.7698 -105.0036)
		(size 0.508)
		(drill 0.254)
		(layers "F.Cu" "B.Cu")
		(net "GND")
	)
	(via
		(at 101.6 -111.76)
		(size 0.508)
		(drill 0.254)
		(layers "F.Cu" "B.Cu")
		(net "GND")
	)
	(via
		(at 116.84 -304.8)
		(size 0.508)
		(drill 0.254)
		(layers "F.Cu" "B.Cu")
		(net "GND")
	)
	(via
		(at 40.64 -345.44)
		(size 0.508)
		(drill 0.254)
		(layers "F.Cu" "B.Cu")
		(net "GND")
	)
	(via
		(at 96.52 -457.2)
		(size 0.508)
		(drill 0.254)
		(layers "F.Cu" "B.Cu")
		(net "GND")
	)
	(via
		(at 236.224572 -1.397)
		(size 0.508)
		(drill 0.254)
		(layers "F.Cu" "B.Cu")
		(net "GND")
	)
	(via
		(at 100.33 -204.851)
		(size 0.508)
		(drill 0.254)
		(layers "F.Cu" "B.Cu")
		(net "GND")
	)
	(via
		(at 142.24 -477.52)
		(size 0.508)
		(drill 0.254)
		(layers "F.Cu" "B.Cu")
		(net "GND")
	)
	(via
		(at 76.2 -274.32)
		(size 0.508)
		(drill 0.254)
		(layers "F.Cu" "B.Cu")
		(net "GND")
	)
	(via
		(at 93.98 -101.6)
		(size 0.508)
		(drill 0.254)
		(layers "F.Cu" "B.Cu")
		(net "GND")
	)
	(via
		(at 147.32 -10.16)
		(size 0.508)
		(drill 0.254)
		(layers "F.Cu" "B.Cu")
		(net "GND")
	)
	(via
		(at 66.04 -340.36)
		(size 0.508)
		(drill 0.254)
		(layers "F.Cu" "B.Cu")
		(net "GND")
	)
	(via
		(at 66.04 -320.04)
		(size 0.508)
		(drill 0.254)
		(layers "F.Cu" "B.Cu")
		(net "GND")
	)
	(via
		(at 203.2 -10.16)
		(size 0.508)
		(drill 0.254)
		(layers "F.Cu" "B.Cu")
		(net "GND")
	)
	(via
		(at 4.191 -393.192)
		(size 0.508)
		(drill 0.254)
		(layers "F.Cu" "B.Cu")
		(net "GND")
	)
	(via
		(at 177.8 -203.2)
		(size 0.508)
		(drill 0.254)
		(layers "F.Cu" "B.Cu")
		(net "GND")
	)
	(via
		(at 162.56 -472.44)
		(size 0.508)
		(drill 0.254)
		(layers "F.Cu" "B.Cu")
		(net "GND")
	)
	(via
		(at 96.774 -302.387)
		(size 0.508)
		(drill 0.254)
		(layers "F.Cu" "B.Cu")
		(net "GND")
	)
	(via
		(at 4.191 -233.090212)
		(size 0.508)
		(drill 0.254)
		(layers "F.Cu" "B.Cu")
		(net "GND")
	)
	(via
		(at 33.655 -59.944)
		(size 0.508)
		(drill 0.254)
		(layers "F.Cu" "B.Cu")
		(net "GND")
	)
	(via
		(at 95.0722 -20.6756)
		(size 0.508)
		(drill 0.254)
		(layers "F.Cu" "B.Cu")
		(net "GND")
	)
	(via
		(at 127 -467.36)
		(size 0.508)
		(drill 0.254)
		(layers "F.Cu" "B.Cu")
		(net "GND")
	)
	(via
		(at 182.88 -350.52)
		(size 0.508)
		(drill 0.254)
		(layers "F.Cu" "B.Cu")
		(net "GND")
	)
	(via
		(at 50.8 -147.32)
		(size 0.508)
		(drill 0.254)
		(layers "F.Cu" "B.Cu")
		(net "GND")
	)
	(via
		(at 84.201 -430.53)
		(size 0.508)
		(drill 0.254)
		(layers "F.Cu" "B.Cu")
		(net "GND")
	)
	(via
		(at 137.16 -40.64)
		(size 0.508)
		(drill 0.254)
		(layers "F.Cu" "B.Cu")
		(net "GND")
	)
	(via
		(at 226.314 -436.88)
		(size 0.508)
		(drill 0.254)
		(layers "F.Cu" "B.Cu")
		(net "GND")
	)
	(via
		(at 49.43348 -473.71)
		(size 0.508)
		(drill 0.254)
		(layers "F.Cu" "B.Cu")
		(net "GND")
	)
	(via
		(at 6.985 -137.16)
		(size 0.508)
		(drill 0.254)
		(layers "F.Cu" "B.Cu")
		(net "GND")
	)
	(via
		(at 66.04 -284.48)
		(size 0.508)
		(drill 0.254)
		(layers "F.Cu" "B.Cu")
		(net "GND")
	)
	(via
		(at 34.275014 -67.101212)
		(size 0.508)
		(drill 0.254)
		(layers "F.Cu" "B.Cu")
		(net "GND")
	)
	(via
		(at 259.08 -492.76)
		(size 0.508)
		(drill 0.254)
		(layers "F.Cu" "B.Cu")
		(net "GND")
	)
	(via
		(at 106.68 -20.32)
		(size 0.508)
		(drill 0.254)
		(layers "F.Cu" "B.Cu")
		(net "GND")
	)
	(via
		(at 167.64 -462.28)
		(size 0.508)
		(drill 0.254)
		(layers "F.Cu" "B.Cu")
		(net "GND")
	)
	(via
		(at 48.264572 -1.397)
		(size 0.508)
		(drill 0.254)
		(layers "F.Cu" "B.Cu")
		(net "GND")
	)
	(via
		(at 86.36 -66.04)
		(size 0.508)
		(drill 0.254)
		(layers "F.Cu" "B.Cu")
		(net "GND")
	)
	(via
		(at 222.616014 -362.789978)
		(size 0.508)
		(drill 0.254)
		(layers "F.Cu" "B.Cu")
		(net "GND")
	)
	(via
		(at 213.36 -147.32)
		(size 0.508)
		(drill 0.254)
		(layers "F.Cu" "B.Cu")
		(net "GND")
	)
	(via
		(at 213.36 -416.56)
		(size 0.508)
		(drill 0.254)
		(layers "F.Cu" "B.Cu")
		(net "GND")
	)
	(via
		(at 45.72 -457.2)
		(size 0.508)
		(drill 0.254)
		(layers "F.Cu" "B.Cu")
		(net "GND")
	)
	(via
		(at 4.191 -336.690208)
		(size 0.508)
		(drill 0.254)
		(layers "F.Cu" "B.Cu")
		(net "GND")
	)
	(via
		(at 219.279978 -67.081908)
		(size 0.508)
		(drill 0.254)
		(layers "F.Cu" "B.Cu")
		(net "GND")
	)
	(via
		(at 55.88 -396.24)
		(size 0.508)
		(drill 0.254)
		(layers "F.Cu" "B.Cu")
		(net "GND")
	)
	(via
		(at 262.103108 -112.678464)
		(size 0.508)
		(drill 0.254)
		(layers "F.Cu" "B.Cu")
		(net "GND")
	)
	(via
		(at 83.185 -203.962)
		(size 0.508)
		(drill 0.254)
		(layers "F.Cu" "B.Cu")
		(net "GND")
	)
	(via
		(at 259.08 -233.68)
		(size 0.508)
		(drill 0.254)
		(layers "F.Cu" "B.Cu")
		(net "GND")
	)
	(via
		(at 55.88 -269.24)
		(size 0.508)
		(drill 0.254)
		(layers "F.Cu" "B.Cu")
		(net "GND")
	)
	(via
		(at 162.56 -243.84)
		(size 0.508)
		(drill 0.254)
		(layers "F.Cu" "B.Cu")
		(net "GND")
	)
	(via
		(at 254 -55.88)
		(size 0.508)
		(drill 0.254)
		(layers "F.Cu" "B.Cu")
		(net "GND")
	)
	(via
		(at 142.24 -426.72)
		(size 0.508)
		(drill 0.254)
		(layers "F.Cu" "B.Cu")
		(net "GND")
	)
	(via
		(at 24.384 -324.41007)
		(size 0.508)
		(drill 0.254)
		(layers "F.Cu" "B.Cu")
		(net "GND")
	)
	(via
		(at 50.8 -289.56)
		(size 0.508)
		(drill 0.254)
		(layers "F.Cu" "B.Cu")
		(net "GND")
	)
	(via
		(at 10.16 -40.64)
		(size 0.508)
		(drill 0.254)
		(layers "F.Cu" "B.Cu")
		(net "GND")
	)
	(via
		(at 66.04 -426.72)
		(size 0.508)
		(drill 0.254)
		(layers "F.Cu" "B.Cu")
		(net "GND")
	)
	(via
		(at 248.92 -233.68)
		(size 0.508)
		(drill 0.254)
		(layers "F.Cu" "B.Cu")
		(net "GND")
	)
	(via
		(at 6.223 -354.41001)
		(size 0.508)
		(drill 0.254)
		(layers "F.Cu" "B.Cu")
		(net "GND")
	)
	(via
		(at 193.04 -492.76)
		(size 0.508)
		(drill 0.254)
		(layers "F.Cu" "B.Cu")
		(net "GND")
	)
	(via
		(at 37.61613 -468.190072)
		(size 0.508)
		(drill 0.254)
		(layers "F.Cu" "B.Cu")
		(net "GND")
	)
	(via
		(at 172.72 -162.56)
		(size 0.508)
		(drill 0.254)
		(layers "F.Cu" "B.Cu")
		(net "GND")
	)
	(via
		(at 21.463 -80.01)
		(size 0.508)
		(drill 0.254)
		(layers "F.Cu" "B.Cu")
		(net "GND")
	)
	(via
		(at 106.68 -238.76)
		(size 0.508)
		(drill 0.254)
		(layers "F.Cu" "B.Cu")
		(net "GND")
	)
	(via
		(at 147.32 -314.96)
		(size 0.508)
		(drill 0.254)
		(layers "F.Cu" "B.Cu")
		(net "GND")
	)
	(via
		(at 132.08 -106.68)
		(size 0.508)
		(drill 0.254)
		(layers "F.Cu" "B.Cu")
		(net "GND")
	)
	(via
		(at 60.96 -45.72)
		(size 0.508)
		(drill 0.254)
		(layers "F.Cu" "B.Cu")
		(net "GND")
	)
	(via
		(at 157.48 -325.12)
		(size 0.508)
		(drill 0.254)
		(layers "F.Cu" "B.Cu")
		(net "GND")
	)
	(via
		(at 254 -233.68)
		(size 0.508)
		(drill 0.254)
		(layers "F.Cu" "B.Cu")
		(net "GND")
	)
	(via
		(at 4.191 -417.76269)
		(size 0.508)
		(drill 0.254)
		(layers "F.Cu" "B.Cu")
		(net "GND")
	)
	(via
		(at 157.48 -208.28)
		(size 0.508)
		(drill 0.254)
		(layers "F.Cu" "B.Cu")
		(net "GND")
	)
	(via
		(at 24.345646 -91.837256)
		(size 0.508)
		(drill 0.254)
		(layers "F.Cu" "B.Cu")
		(net "GND")
	)
	(via
		(at 177.8 -502.92)
		(size 0.508)
		(drill 0.254)
		(layers "F.Cu" "B.Cu")
		(net "GND")
	)
	(via
		(at 106.68 -50.8)
		(size 0.508)
		(drill 0.254)
		(layers "F.Cu" "B.Cu")
		(net "GND")
	)
	(via
		(at 91.186 -208.026)
		(size 0.508)
		(drill 0.254)
		(layers "F.Cu" "B.Cu")
		(net "GND")
	)
	(via
		(at 24.384 -233.409998)
		(size 0.508)
		(drill 0.254)
		(layers "F.Cu" "B.Cu")
		(net "GND")
	)
	(via
		(at 121.92 -15.24)
		(size 0.508)
		(drill 0.254)
		(layers "F.Cu" "B.Cu")
		(net "GND")
	)
	(via
		(at 9.271 -253.873)
		(size 0.508)
		(drill 0.254)
		(layers "F.Cu" "B.Cu")
		(net "GND")
	)
	(via
		(at 106.68 -15.24)
		(size 0.508)
		(drill 0.254)
		(layers "F.Cu" "B.Cu")
		(net "GND")
	)
	(via
		(at 95.885 -24.892)
		(size 0.508)
		(drill 0.254)
		(layers "F.Cu" "B.Cu")
		(net "GND")
	)
	(via
		(at 209.38109 -92.94241)
		(size 0.508)
		(drill 0.254)
		(layers "F.Cu" "B.Cu")
		(net "GND")
	)
	(via
		(at 132.08 -30.48)
		(size 0.508)
		(drill 0.254)
		(layers "F.Cu" "B.Cu")
		(net "GND")
	)
	(via
		(at 167.64 -467.36)
		(size 0.508)
		(drill 0.254)
		(layers "F.Cu" "B.Cu")
		(net "GND")
	)
	(via
		(at 228.585014 -158.604966)
		(size 0.508)
		(drill 0.254)
		(layers "F.Cu" "B.Cu")
		(net "GND")
	)
	(via
		(at 78.744572 -1.397)
		(size 0.508)
		(drill 0.254)
		(layers "F.Cu" "B.Cu")
		(net "GND")
	)
	(via
		(at 233.68 -106.68)
		(size 0.508)
		(drill 0.254)
		(layers "F.Cu" "B.Cu")
		(net "GND")
	)
	(via
		(at 172.72 -345.44)
		(size 0.508)
		(drill 0.254)
		(layers "F.Cu" "B.Cu")
		(net "GND")
	)
	(via
		(at 95.377 -210.82)
		(size 0.508)
		(drill 0.254)
		(layers "F.Cu" "B.Cu")
		(net "GND")
	)
	(via
		(at 203.2 -55.88)
		(size 0.508)
		(drill 0.254)
		(layers "F.Cu" "B.Cu")
		(net "GND")
	)
	(via
		(at 5.08 -121.92)
		(size 0.508)
		(drill 0.254)
		(layers "F.Cu" "B.Cu")
		(net "GND")
	)
	(via
		(at 21.6535 -165.7985)
		(size 0.508)
		(drill 0.254)
		(layers "F.Cu" "B.Cu")
		(net "GND")
	)
	(via
		(at 147.32 -386.08)
		(size 0.508)
		(drill 0.254)
		(layers "F.Cu" "B.Cu")
		(net "GND")
	)
	(via
		(at 86.36 -467.36)
		(size 0.508)
		(drill 0.254)
		(layers "F.Cu" "B.Cu")
		(net "GND")
	)
	(via
		(at 187.96 -264.16)
		(size 0.508)
		(drill 0.254)
		(layers "F.Cu" "B.Cu")
		(net "GND")
	)
	(via
		(at 35.56 -325.12)
		(size 0.508)
		(drill 0.254)
		(layers "F.Cu" "B.Cu")
		(net "GND")
	)
	(via
		(at 147.32 -91.44)
		(size 0.508)
		(drill 0.254)
		(layers "F.Cu" "B.Cu")
		(net "GND")
	)
	(via
		(at 28.6004 -318.5922)
		(size 0.508)
		(drill 0.254)
		(layers "F.Cu" "B.Cu")
		(net "GND")
	)
	(via
		(at 43.66133 -162.414966)
		(size 0.508)
		(drill 0.254)
		(layers "F.Cu" "B.Cu")
		(net "GND")
	)
	(via
		(at 259.08 -447.04)
		(size 0.508)
		(drill 0.254)
		(layers "F.Cu" "B.Cu")
		(net "GND")
	)
	(via
		(at 193.04 -157.48)
		(size 0.508)
		(drill 0.254)
		(layers "F.Cu" "B.Cu")
		(net "GND")
	)
	(via
		(at 91.44 -487.68)
		(size 0.508)
		(drill 0.254)
		(layers "F.Cu" "B.Cu")
		(net "GND")
	)
	(via
		(at 157.48 -172.72)
		(size 0.508)
		(drill 0.254)
		(layers "F.Cu" "B.Cu")
		(net "GND")
	)
	(via
		(at 76.2 -248.92)
		(size 0.508)
		(drill 0.254)
		(layers "F.Cu" "B.Cu")
		(net "GND")
	)
	(via
		(at 86.233 -105.8545)
		(size 0.508)
		(drill 0.254)
		(layers "F.Cu" "B.Cu")
		(net "GND")
	)
	(via
		(at 91.44 -248.92)
		(size 0.508)
		(drill 0.254)
		(layers "F.Cu" "B.Cu")
		(net "GND")
	)
	(via
		(at 50.8 -116.84)
		(size 0.508)
		(drill 0.254)
		(layers "F.Cu" "B.Cu")
		(net "GND")
	)
	(via
		(at 259.08 -243.84)
		(size 0.508)
		(drill 0.254)
		(layers "F.Cu" "B.Cu")
		(net "GND")
	)
	(via
		(at 40.64 -431.8)
		(size 0.508)
		(drill 0.254)
		(layers "F.Cu" "B.Cu")
		(net "GND")
	)
	(via
		(at 77.7748 -434.2384)
		(size 0.508)
		(drill 0.254)
		(layers "F.Cu" "B.Cu")
		(net "GND")
	)
	(via
		(at 213.36 -60.96)
		(size 0.508)
		(drill 0.254)
		(layers "F.Cu" "B.Cu")
		(net "GND")
	)
	(via
		(at 243.84 -121.92)
		(size 0.508)
		(drill 0.254)
		(layers "F.Cu" "B.Cu")
		(net "GND")
	)
	(via
		(at 127 -482.6)
		(size 0.508)
		(drill 0.254)
		(layers "F.Cu" "B.Cu")
		(net "GND")
	)
	(via
		(at 5.08 -20.32)
		(size 0.508)
		(drill 0.254)
		(layers "F.Cu" "B.Cu")
		(net "GND")
	)
	(via
		(at 222.616014 -369.190016)
		(size 0.508)
		(drill 0.254)
		(layers "F.Cu" "B.Cu")
		(net "GND")
	)
	(via
		(at 6.223 -212.411564)
		(size 0.508)
		(drill 0.254)
		(layers "F.Cu" "B.Cu")
		(net "GND")
	)
	(via
		(at 245.11 -392.43)
		(size 0.7112)
		(drill 0.4064)
		(layers "F.Cu" "B.Cu")
		(net "GND")
	)
	(via
		(at 101.6 -502.92)
		(size 0.508)
		(drill 0.254)
		(layers "F.Cu" "B.Cu")
		(net "GND")
	)
	(via
		(at 162.56 -355.6)
		(size 0.508)
		(drill 0.254)
		(layers "F.Cu" "B.Cu")
		(net "GND")
	)
	(via
		(at 34.290254 -282.649168)
		(size 0.508)
		(drill 0.254)
		(layers "F.Cu" "B.Cu")
		(net "GND")
	)
	(via
		(at 238.76 -355.6)
		(size 0.508)
		(drill 0.254)
		(layers "F.Cu" "B.Cu")
		(net "GND")
	)
	(via
		(at 4.191 -437.896)
		(size 0.508)
		(drill 0.254)
		(layers "F.Cu" "B.Cu")
		(net "GND")
	)
	(via
		(at 24.384 -34.036)
		(size 0.508)
		(drill 0.254)
		(layers "F.Cu" "B.Cu")
		(net "GND")
	)
	(via
		(at 203.2 -304.8)
		(size 0.508)
		(drill 0.254)
		(layers "F.Cu" "B.Cu")
		(net "GND")
	)
	(via
		(at 6.731 -458.5208)
		(size 0.7112)
		(drill 0.4064)
		(layers "F.Cu" "B.Cu")
		(net "GND")
	)
	(via
		(at 4.191 -401.955)
		(size 0.508)
		(drill 0.254)
		(layers "F.Cu" "B.Cu")
		(net "GND")
	)
	(via
		(at 254 -254)
		(size 0.508)
		(drill 0.254)
		(layers "F.Cu" "B.Cu")
		(net "GND")
	)
	(via
		(at 254 -50.8)
		(size 0.508)
		(drill 0.254)
		(layers "F.Cu" "B.Cu")
		(net "GND")
	)
	(via
		(at 132.08 -375.92)
		(size 0.508)
		(drill 0.254)
		(layers "F.Cu" "B.Cu")
		(net "GND")
	)
	(via
		(at 4.191 -166.878)
		(size 0.508)
		(drill 0.254)
		(layers "F.Cu" "B.Cu")
		(net "GND")
	)
	(via
		(at 95.377 -100.203)
		(size 0.508)
		(drill 0.254)
		(layers "F.Cu" "B.Cu")
		(net "GND")
	)
	(via
		(at 193.04 -452.12)
		(size 0.508)
		(drill 0.254)
		(layers "F.Cu" "B.Cu")
		(net "GND")
	)
	(via
		(at 198.12 -345.44)
		(size 0.508)
		(drill 0.254)
		(layers "F.Cu" "B.Cu")
		(net "GND")
	)
	(via
		(at 248.92 -60.96)
		(size 0.508)
		(drill 0.254)
		(layers "F.Cu" "B.Cu")
		(net "GND")
	)
	(via
		(at 222.616014 -284.589982)
		(size 0.508)
		(drill 0.254)
		(layers "F.Cu" "B.Cu")
		(net "GND")
	)
	(via
		(at 228.585014 -360.795062)
		(size 0.508)
		(drill 0.254)
		(layers "F.Cu" "B.Cu")
		(net "GND")
	)
	(via
		(at 228.585014 -276.845014)
		(size 0.508)
		(drill 0.254)
		(layers "F.Cu" "B.Cu")
		(net "GND")
	)
	(via
		(at 243.84 -193.04)
		(size 0.508)
		(drill 0.254)
		(layers "F.Cu" "B.Cu")
		(net "GND")
	)
	(via
		(at 127 -162.56)
		(size 0.508)
		(drill 0.254)
		(layers "F.Cu" "B.Cu")
		(net "GND")
	)
	(via
		(at 262.103108 -285.398464)
		(size 0.508)
		(drill 0.254)
		(layers "F.Cu" "B.Cu")
		(net "GND")
	)
	(via
		(at 14.986 -167.513)
		(size 0.508)
		(drill 0.254)
		(layers "F.Cu" "B.Cu")
		(net "GND")
	)
	(via
		(at 261.624572 -1.397)
		(size 0.508)
		(drill 0.254)
		(layers "F.Cu" "B.Cu")
		(net "GND")
	)
	(via
		(at 142.24 -350.52)
		(size 0.508)
		(drill 0.254)
		(layers "F.Cu" "B.Cu")
		(net "GND")
	)
	(via
		(at 193.04 -436.88)
		(size 0.508)
		(drill 0.254)
		(layers "F.Cu" "B.Cu")
		(net "GND")
	)
	(via
		(at 28.6004 -112.395)
		(size 0.508)
		(drill 0.254)
		(layers "F.Cu" "B.Cu")
		(net "GND")
	)
	(via
		(at 21.6535 -62.798452)
		(size 0.508)
		(drill 0.254)
		(layers "F.Cu" "B.Cu")
		(net "GND")
	)
	(via
		(at 213.36 -152.4)
		(size 0.508)
		(drill 0.254)
		(layers "F.Cu" "B.Cu")
		(net "GND")
	)
	(via
		(at 116.84 -426.72)
		(size 0.508)
		(drill 0.254)
		(layers "F.Cu" "B.Cu")
		(net "GND")
	)
	(via
		(at 259.08 -203.2)
		(size 0.508)
		(drill 0.254)
		(layers "F.Cu" "B.Cu")
		(net "GND")
	)
	(via
		(at 116.84 -482.6)
		(size 0.508)
		(drill 0.254)
		(layers "F.Cu" "B.Cu")
		(net "GND")
	)
	(via
		(at 75.565 -148.082)
		(size 0.508)
		(drill 0.254)
		(layers "F.Cu" "B.Cu")
		(net "GND")
	)
	(via
		(at 243.84 -467.36)
		(size 0.508)
		(drill 0.254)
		(layers "F.Cu" "B.Cu")
		(net "GND")
	)
	(via
		(at 4.191 -209.166206)
		(size 0.508)
		(drill 0.254)
		(layers "F.Cu" "B.Cu")
		(net "GND")
	)
	(via
		(at 91.44 -71.12)
		(size 0.508)
		(drill 0.254)
		(layers "F.Cu" "B.Cu")
		(net "GND")
	)
	(via
		(at 79.629 -98.044)
		(size 0.508)
		(drill 0.254)
		(layers "F.Cu" "B.Cu")
		(net "GND")
	)
	(via
		(at 127 -462.28)
		(size 0.508)
		(drill 0.254)
		(layers "F.Cu" "B.Cu")
		(net "GND")
	)
	(via
		(at 96.52 -127)
		(size 0.508)
		(drill 0.254)
		(layers "F.Cu" "B.Cu")
		(net "GND")
	)
	(via
		(at 116.84 -345.44)
		(size 0.508)
		(drill 0.254)
		(layers "F.Cu" "B.Cu")
		(net "GND")
	)
	(via
		(at 157.48 -228.6)
		(size 0.508)
		(drill 0.254)
		(layers "F.Cu" "B.Cu")
		(net "GND")
	)
	(via
		(at 43.942 -491.363)
		(size 0.508)
		(drill 0.254)
		(layers "F.Cu" "B.Cu")
		(net "GND")
	)
	(via
		(at 50.8 -81.28)
		(size 0.508)
		(drill 0.254)
		(layers "F.Cu" "B.Cu")
		(net "GND")
	)
	(via
		(at 233.68 -477.52)
		(size 0.508)
		(drill 0.254)
		(layers "F.Cu" "B.Cu")
		(net "GND")
	)
	(via
		(at 167.64 -10.16)
		(size 0.508)
		(drill 0.254)
		(layers "F.Cu" "B.Cu")
		(net "GND")
	)
	(via
		(at 83.185 -298.323)
		(size 0.508)
		(drill 0.254)
		(layers "F.Cu" "B.Cu")
		(net "GND")
	)
	(via
		(at 92.3925 -18.6182)
		(size 0.508)
		(drill 0.254)
		(layers "F.Cu" "B.Cu")
		(net "GND")
	)
	(via
		(at 187.96 -127)
		(size 0.508)
		(drill 0.254)
		(layers "F.Cu" "B.Cu")
		(net "GND")
	)
	(via
		(at 86.36 -60.96)
		(size 0.508)
		(drill 0.254)
		(layers "F.Cu" "B.Cu")
		(net "GND")
	)
	(via
		(at 259.08 -66.04)
		(size 0.508)
		(drill 0.254)
		(layers "F.Cu" "B.Cu")
		(net "GND")
	)
	(via
		(at 5.08 -101.6)
		(size 0.508)
		(drill 0.254)
		(layers "F.Cu" "B.Cu")
		(net "GND")
	)
	(via
		(at 147.32 -15.24)
		(size 0.508)
		(drill 0.254)
		(layers "F.Cu" "B.Cu")
		(net "GND")
	)
	(via
		(at 193.04 -193.04)
		(size 0.508)
		(drill 0.254)
		(layers "F.Cu" "B.Cu")
		(net "GND")
	)
	(via
		(at 86.36 -502.92)
		(size 0.508)
		(drill 0.254)
		(layers "F.Cu" "B.Cu")
		(net "GND")
	)
	(via
		(at 198.12 -60.96)
		(size 0.508)
		(drill 0.254)
		(layers "F.Cu" "B.Cu")
		(net "GND")
	)
	(via
		(at 233.68 -208.28)
		(size 0.508)
		(drill 0.254)
		(layers "F.Cu" "B.Cu")
		(net "GND")
	)
	(via
		(at 66.04 -492.76)
		(size 0.508)
		(drill 0.254)
		(layers "F.Cu" "B.Cu")
		(net "GND")
	)
	(via
		(at 218.44 -152.4)
		(size 0.508)
		(drill 0.254)
		(layers "F.Cu" "B.Cu")
		(net "GND")
	)
	(via
		(at 252.73 -420.649908)
		(size 0.508)
		(drill 0.254)
		(layers "F.Cu" "B.Cu")
		(net "GND")
	)
	(via
		(at 167.64 -223.52)
		(size 0.508)
		(drill 0.254)
		(layers "F.Cu" "B.Cu")
		(net "GND")
	)
	(via
		(at 37.61613 -266.189968)
		(size 0.508)
		(drill 0.254)
		(layers "F.Cu" "B.Cu")
		(net "GND")
	)
	(via
		(at 10.16 -30.48)
		(size 0.508)
		(drill 0.254)
		(layers "F.Cu" "B.Cu")
		(net "GND")
	)
	(via
		(at 86.36 -259.08)
		(size 0.508)
		(drill 0.254)
		(layers "F.Cu" "B.Cu")
		(net "GND")
	)
	(via
		(at 116.84 -492.76)
		(size 0.508)
		(drill 0.254)
		(layers "F.Cu" "B.Cu")
		(net "GND")
	)
	(via
		(at 6.985 -140.589)
		(size 0.508)
		(drill 0.254)
		(layers "F.Cu" "B.Cu")
		(net "GND")
	)
	(via
		(at 157.48 -223.52)
		(size 0.508)
		(drill 0.254)
		(layers "F.Cu" "B.Cu")
		(net "GND")
	)
	(via
		(at 222.616014 -264.590022)
		(size 0.508)
		(drill 0.254)
		(layers "F.Cu" "B.Cu")
		(net "GND")
	)
	(via
		(at 142.24 -91.44)
		(size 0.508)
		(drill 0.254)
		(layers "F.Cu" "B.Cu")
		(net "GND")
	)
	(via
		(at 5.08 -238.76)
		(size 0.508)
		(drill 0.254)
		(layers "F.Cu" "B.Cu")
		(net "GND")
	)
	(via
		(at 142.24 -492.76)
		(size 0.508)
		(drill 0.254)
		(layers "F.Cu" "B.Cu")
		(net "GND")
	)
	(via
		(at 259.08 -289.56)
		(size 0.508)
		(drill 0.254)
		(layers "F.Cu" "B.Cu")
		(net "GND")
	)
	(via
		(at 243.84 -81.28)
		(size 0.508)
		(drill 0.254)
		(layers "F.Cu" "B.Cu")
		(net "GND")
	)
	(via
		(at 17.018 -242.189)
		(size 0.508)
		(drill 0.254)
		(layers "F.Cu" "B.Cu")
		(net "GND")
	)
	(via
		(at 55.9308 -442.1886)
		(size 0.508)
		(drill 0.254)
		(layers "F.Cu" "B.Cu")
		(net "GND")
	)
	(via
		(at 98.017584 -112.84331)
		(size 0.508)
		(drill 0.254)
		(layers "F.Cu" "B.Cu")
		(net "GND")
	)
	(via
		(at 137.16 -360.68)
		(size 0.508)
		(drill 0.254)
		(layers "F.Cu" "B.Cu")
		(net "GND")
	)
	(via
		(at 132.08 -482.6)
		(size 0.508)
		(drill 0.254)
		(layers "F.Cu" "B.Cu")
		(net "GND")
	)
	(via
		(at 223.52 -121.92)
		(size 0.508)
		(drill 0.254)
		(layers "F.Cu" "B.Cu")
		(net "GND")
	)
	(via
		(at 109.869986 -504.603004)
		(size 0.508)
		(drill 0.254)
		(layers "F.Cu" "B.Cu")
		(net "GND")
	)
	(via
		(at 101.6 -30.48)
		(size 0.508)
		(drill 0.254)
		(layers "F.Cu" "B.Cu")
		(net "GND")
	)
	(via
		(at 147.32 -86.36)
		(size 0.508)
		(drill 0.254)
		(layers "F.Cu" "B.Cu")
		(net "GND")
	)
	(via
		(at 223.52 -106.68)
		(size 0.508)
		(drill 0.254)
		(layers "F.Cu" "B.Cu")
		(net "GND")
	)
	(via
		(at 262.103108 -473.956126)
		(size 0.508)
		(drill 0.254)
		(layers "F.Cu" "B.Cu")
		(net "GND")
	)
	(via
		(at 94.488 -92.583)
		(size 0.508)
		(drill 0.254)
		(layers "F.Cu" "B.Cu")
		(net "GND")
	)
	(via
		(at 198.12 -375.92)
		(size 0.508)
		(drill 0.254)
		(layers "F.Cu" "B.Cu")
		(net "GND")
	)
	(via
		(at 228.6 -304.8)
		(size 0.508)
		(drill 0.254)
		(layers "F.Cu" "B.Cu")
		(net "GND")
	)
	(via
		(at 142.24 -162.56)
		(size 0.508)
		(drill 0.254)
		(layers "F.Cu" "B.Cu")
		(net "GND")
	)
	(via
		(at 167.64 -76.2)
		(size 0.508)
		(drill 0.254)
		(layers "F.Cu" "B.Cu")
		(net "GND")
	)
	(via
		(at 167.64 -233.68)
		(size 0.508)
		(drill 0.254)
		(layers "F.Cu" "B.Cu")
		(net "GND")
	)
	(via
		(at 58.293 -410.083)
		(size 0.508)
		(drill 0.254)
		(layers "F.Cu" "B.Cu")
		(net "GND")
	)
	(via
		(at 147.32 -55.88)
		(size 0.508)
		(drill 0.254)
		(layers "F.Cu" "B.Cu")
		(net "GND")
	)
	(via
		(at 4.191 -434.848)
		(size 0.508)
		(drill 0.254)
		(layers "F.Cu" "B.Cu")
		(net "GND")
	)
	(via
		(at 69.469 -357.505)
		(size 0.508)
		(drill 0.254)
		(layers "F.Cu" "B.Cu")
		(net "GND")
	)
	(via
		(at 43.58513 -379.845062)
		(size 0.508)
		(drill 0.254)
		(layers "F.Cu" "B.Cu")
		(net "GND")
	)
	(via
		(at 4.191 -176.36617)
		(size 0.508)
		(drill 0.254)
		(layers "F.Cu" "B.Cu")
		(net "GND")
	)
	(via
		(at 27.69616 -427.826932)
		(size 0.508)
		(drill 0.254)
		(layers "F.Cu" "B.Cu")
		(net "GND")
	)
	(via
		(at 121.92 -162.56)
		(size 0.508)
		(drill 0.254)
		(layers "F.Cu" "B.Cu")
		(net "GND")
	)
	(via
		(at 37.61613 -169.589958)
		(size 0.508)
		(drill 0.254)
		(layers "F.Cu" "B.Cu")
		(net "GND")
	)
	(via
		(at 172.72 -86.36)
		(size 0.508)
		(drill 0.254)
		(layers "F.Cu" "B.Cu")
		(net "GND")
	)
	(via
		(at 157.48 -162.56)
		(size 0.508)
		(drill 0.254)
		(layers "F.Cu" "B.Cu")
		(net "GND")
	)
	(via
		(at 182.88 -106.68)
		(size 0.508)
		(drill 0.254)
		(layers "F.Cu" "B.Cu")
		(net "GND")
	)
	(via
		(at 16.637 -220.345)
		(size 0.508)
		(drill 0.254)
		(layers "F.Cu" "B.Cu")
		(net "GND")
	)
	(via
		(at 66.04 -294.64)
		(size 0.508)
		(drill 0.254)
		(layers "F.Cu" "B.Cu")
		(net "GND")
	)
	(via
		(at 25.4 -45.72)
		(size 0.508)
		(drill 0.254)
		(layers "F.Cu" "B.Cu")
		(net "GND")
	)
	(via
		(at 233.426 -368.486436)
		(size 0.508)
		(drill 0.254)
		(layers "F.Cu" "B.Cu")
		(net "GND")
	)
	(via
		(at 262.103108 -504.436126)
		(size 0.508)
		(drill 0.254)
		(layers "F.Cu" "B.Cu")
		(net "GND")
	)
	(via
		(at 96.774 -98.806)
		(size 0.508)
		(drill 0.254)
		(layers "F.Cu" "B.Cu")
		(net "GND")
	)
	(via
		(at 6.223 -163.66236)
		(size 0.508)
		(drill 0.254)
		(layers "F.Cu" "B.Cu")
		(net "GND")
	)
	(via
		(at 18.034 -426.72)
		(size 0.508)
		(drill 0.254)
		(layers "F.Cu" "B.Cu")
		(net "GND")
	)
	(via
		(at 111.76 -492.76)
		(size 0.508)
		(drill 0.254)
		(layers "F.Cu" "B.Cu")
		(net "GND")
	)
	(via
		(at 44.196 -140.589)
		(size 0.508)
		(drill 0.254)
		(layers "F.Cu" "B.Cu")
		(net "GND")
	)
	(via
		(at 89.3445 -444.754)
		(size 0.508)
		(drill 0.254)
		(layers "F.Cu" "B.Cu")
		(net "GND")
	)
	(via
		(at 4.191 -409.956)
		(size 0.508)
		(drill 0.254)
		(layers "F.Cu" "B.Cu")
		(net "GND")
	)
	(via
		(at 111.76 -228.6)
		(size 0.508)
		(drill 0.254)
		(layers "F.Cu" "B.Cu")
		(net "GND")
	)
	(via
		(at 6.223 -299.209968)
		(size 0.508)
		(drill 0.254)
		(layers "F.Cu" "B.Cu")
		(net "GND")
	)
	(via
		(at 222.616014 -259.78993)
		(size 0.508)
		(drill 0.254)
		(layers "F.Cu" "B.Cu")
		(net "GND")
	)
	(via
		(at 193.04 -91.44)
		(size 0.508)
		(drill 0.254)
		(layers "F.Cu" "B.Cu")
		(net "GND")
	)
	(via
		(at 213.36 -5.08)
		(size 0.508)
		(drill 0.254)
		(layers "F.Cu" "B.Cu")
		(net "GND")
	)
	(via
		(at 121.92 -101.6)
		(size 0.508)
		(drill 0.254)
		(layers "F.Cu" "B.Cu")
		(net "GND")
	)
	(via
		(at 111.76 -121.92)
		(size 0.508)
		(drill 0.254)
		(layers "F.Cu" "B.Cu")
		(net "GND")
	)
	(via
		(at 248.92 -86.36)
		(size 0.508)
		(drill 0.254)
		(layers "F.Cu" "B.Cu")
		(net "GND")
	)
	(via
		(at 137.16 -330.2)
		(size 0.508)
		(drill 0.254)
		(layers "F.Cu" "B.Cu")
		(net "GND")
	)
	(via
		(at 193.04 -203.2)
		(size 0.508)
		(drill 0.254)
		(layers "F.Cu" "B.Cu")
		(net "GND")
	)
	(via
		(at 127 -223.52)
		(size 0.508)
		(drill 0.254)
		(layers "F.Cu" "B.Cu")
		(net "GND")
	)
	(via
		(at 203.2 -452.12)
		(size 0.508)
		(drill 0.254)
		(layers "F.Cu" "B.Cu")
		(net "GND")
	)
	(via
		(at 34.27349 -376.101356)
		(size 0.508)
		(drill 0.254)
		(layers "F.Cu" "B.Cu")
		(net "GND")
	)
	(via
		(at 152.4 -10.16)
		(size 0.508)
		(drill 0.254)
		(layers "F.Cu" "B.Cu")
		(net "GND")
	)
	(via
		(at 182.88 -96.52)
		(size 0.508)
		(drill 0.254)
		(layers "F.Cu" "B.Cu")
		(net "GND")
	)
	(via
		(at 106.68 -340.36)
		(size 0.508)
		(drill 0.254)
		(layers "F.Cu" "B.Cu")
		(net "GND")
	)
	(via
		(at 167.64 -360.68)
		(size 0.508)
		(drill 0.254)
		(layers "F.Cu" "B.Cu")
		(net "GND")
	)
	(via
		(at 34.275014 -171.478956)
		(size 0.508)
		(drill 0.254)
		(layers "F.Cu" "B.Cu")
		(net "GND")
	)
	(via
		(at 228.6 -406.4)
		(size 0.508)
		(drill 0.254)
		(layers "F.Cu" "B.Cu")
		(net "GND")
	)
	(via
		(at 213.36 -335.28)
		(size 0.508)
		(drill 0.254)
		(layers "F.Cu" "B.Cu")
		(net "GND")
	)
	(via
		(at 187.96 -360.68)
		(size 0.508)
		(drill 0.254)
		(layers "F.Cu" "B.Cu")
		(net "GND")
	)
	(via
		(at 248.92 -157.48)
		(size 0.508)
		(drill 0.254)
		(layers "F.Cu" "B.Cu")
		(net "GND")
	)
	(via
		(at 182.88 -116.84)
		(size 0.508)
		(drill 0.254)
		(layers "F.Cu" "B.Cu")
		(net "GND")
	)
	(via
		(at 6.223 -438.042812)
		(size 0.508)
		(drill 0.254)
		(layers "F.Cu" "B.Cu")
		(net "GND")
	)
	(via
		(at 4.191 -453.136)
		(size 0.508)
		(drill 0.254)
		(layers "F.Cu" "B.Cu")
		(net "GND")
	)
	(via
		(at 218.44 -213.36)
		(size 0.508)
		(drill 0.254)
		(layers "F.Cu" "B.Cu")
		(net "GND")
	)
	(via
		(at 24.4094 -298.8818)
		(size 0.508)
		(drill 0.254)
		(layers "F.Cu" "B.Cu")
		(net "GND")
	)
	(via
		(at 91.44 -269.24)
		(size 0.508)
		(drill 0.254)
		(layers "F.Cu" "B.Cu")
		(net "GND")
	)
	(via
		(at 92.3925 -16.5735)
		(size 0.508)
		(drill 0.254)
		(layers "F.Cu" "B.Cu")
		(net "GND")
	)
	(via
		(at 157.48 -167.64)
		(size 0.508)
		(drill 0.254)
		(layers "F.Cu" "B.Cu")
		(net "GND")
	)
	(via
		(at 147.32 -203.2)
		(size 0.508)
		(drill 0.254)
		(layers "F.Cu" "B.Cu")
		(net "GND")
	)
	(via
		(at 238.76 -55.88)
		(size 0.508)
		(drill 0.254)
		(layers "F.Cu" "B.Cu")
		(net "GND")
	)
	(via
		(at 167.64 -167.64)
		(size 0.508)
		(drill 0.254)
		(layers "F.Cu" "B.Cu")
		(net "GND")
	)
	(via
		(at 234.569 -401.2692)
		(size 0.508)
		(drill 0.254)
		(layers "F.Cu" "B.Cu")
		(net "GND")
	)
	(via
		(at 208.28 -137.16)
		(size 0.508)
		(drill 0.254)
		(layers "F.Cu" "B.Cu")
		(net "GND")
	)
	(via
		(at 238.76 -182.88)
		(size 0.508)
		(drill 0.254)
		(layers "F.Cu" "B.Cu")
		(net "GND")
	)
	(via
		(at 187.96 -320.04)
		(size 0.508)
		(drill 0.254)
		(layers "F.Cu" "B.Cu")
		(net "GND")
	)
	(via
		(at 152.4 -447.04)
		(size 0.508)
		(drill 0.254)
		(layers "F.Cu" "B.Cu")
		(net "GND")
	)
	(via
		(at 248.285 -357.886)
		(size 0.508)
		(drill 0.254)
		(layers "F.Cu" "B.Cu")
		(net "GND")
	)
	(via
		(at 86.36 -5.08)
		(size 0.508)
		(drill 0.254)
		(layers "F.Cu" "B.Cu")
		(net "GND")
	)
	(via
		(at 127 -177.8)
		(size 0.508)
		(drill 0.254)
		(layers "F.Cu" "B.Cu")
		(net "GND")
	)
	(via
		(at 60.96 -299.72)
		(size 0.508)
		(drill 0.254)
		(layers "F.Cu" "B.Cu")
		(net "GND")
	)
	(via
		(at 116.84 -10.16)
		(size 0.508)
		(drill 0.254)
		(layers "F.Cu" "B.Cu")
		(net "GND")
	)
	(via
		(at 228.585014 -173.844966)
		(size 0.508)
		(drill 0.254)
		(layers "F.Cu" "B.Cu")
		(net "GND")
	)
	(via
		(at 43.58513 -471.41511)
		(size 0.508)
		(drill 0.254)
		(layers "F.Cu" "B.Cu")
		(net "GND")
	)
	(via
		(at 142.24 -5.08)
		(size 0.508)
		(drill 0.254)
		(layers "F.Cu" "B.Cu")
		(net "GND")
	)
	(via
		(at 142.24 -436.88)
		(size 0.508)
		(drill 0.254)
		(layers "F.Cu" "B.Cu")
		(net "GND")
	)
	(via
		(at 24.384 -130.40995)
		(size 0.508)
		(drill 0.254)
		(layers "F.Cu" "B.Cu")
		(net "GND")
	)
	(via
		(at 121.92 -294.64)
		(size 0.508)
		(drill 0.254)
		(layers "F.Cu" "B.Cu")
		(net "GND")
	)
	(via
		(at 45.72 -386.08)
		(size 0.508)
		(drill 0.254)
		(layers "F.Cu" "B.Cu")
		(net "GND")
	)
	(via
		(at 16.894048 -73.126346)
		(size 0.508)
		(drill 0.254)
		(layers "F.Cu" "B.Cu")
		(net "GND")
	)
	(via
		(at 233.68 -167.64)
		(size 0.508)
		(drill 0.254)
		(layers "F.Cu" "B.Cu")
		(net "GND")
	)
	(via
		(at 187.96 -208.28)
		(size 0.508)
		(drill 0.254)
		(layers "F.Cu" "B.Cu")
		(net "GND")
	)
	(via
		(at 233.68 -467.36)
		(size 0.508)
		(drill 0.254)
		(layers "F.Cu" "B.Cu")
		(net "GND")
	)
	(via
		(at 223.52 -228.6)
		(size 0.508)
		(drill 0.254)
		(layers "F.Cu" "B.Cu")
		(net "GND")
	)
	(via
		(at 233.68 -355.6)
		(size 0.508)
		(drill 0.254)
		(layers "F.Cu" "B.Cu")
		(net "GND")
	)
	(via
		(at 93.599 -219.71)
		(size 0.508)
		(drill 0.254)
		(layers "F.Cu" "B.Cu")
		(net "GND")
	)
	(via
		(at 79.629 -301.625)
		(size 0.508)
		(drill 0.254)
		(layers "F.Cu" "B.Cu")
		(net "GND")
	)
	(via
		(at 182.88 -487.68)
		(size 0.508)
		(drill 0.254)
		(layers "F.Cu" "B.Cu")
		(net "GND")
	)
	(via
		(at 8.269986 -504.603004)
		(size 0.508)
		(drill 0.254)
		(layers "F.Cu" "B.Cu")
		(net "GND")
	)
	(via
		(at 238.76 -213.36)
		(size 0.508)
		(drill 0.254)
		(layers "F.Cu" "B.Cu")
		(net "GND")
	)
	(via
		(at 6.223 -173.26229)
		(size 0.508)
		(drill 0.254)
		(layers "F.Cu" "B.Cu")
		(net "GND")
	)
	(via
		(at 137.16 -355.6)
		(size 0.508)
		(drill 0.254)
		(layers "F.Cu" "B.Cu")
		(net "GND")
	)
	(via
		(at 10.301224 -486.936288)
		(size 0.508)
		(drill 0.254)
		(layers "F.Cu" "B.Cu")
		(net "GND")
	)
	(via
		(at 249.3518 -357.886)
		(size 0.508)
		(drill 0.254)
		(layers "F.Cu" "B.Cu")
		(net "GND")
	)
	(via
		(at 12.954 -232.029)
		(size 0.508)
		(drill 0.254)
		(layers "F.Cu" "B.Cu")
		(net "GND")
	)
	(via
		(at 219.289884 -490.1311)
		(size 0.508)
		(drill 0.254)
		(layers "F.Cu" "B.Cu")
		(net "GND")
	)
	(via
		(at 111.76 -132.08)
		(size 0.508)
		(drill 0.254)
		(layers "F.Cu" "B.Cu")
		(net "GND")
	)
	(via
		(at 37.61613 -371.590062)
		(size 0.508)
		(drill 0.254)
		(layers "F.Cu" "B.Cu")
		(net "GND")
	)
	(via
		(at 254 -198.12)
		(size 0.508)
		(drill 0.254)
		(layers "F.Cu" "B.Cu")
		(net "GND")
	)
	(via
		(at 222.616014 -472.190064)
		(size 0.508)
		(drill 0.254)
		(layers "F.Cu" "B.Cu")
		(net "GND")
	)
	(via
		(at 6.223 -401.889976)
		(size 0.508)
		(drill 0.254)
		(layers "F.Cu" "B.Cu")
		(net "GND")
	)
	(via
		(at 96.52 -472.44)
		(size 0.508)
		(drill 0.254)
		(layers "F.Cu" "B.Cu")
		(net "GND")
	)
	(via
		(at 79.389986 -504.603004)
		(size 0.508)
		(drill 0.254)
		(layers "F.Cu" "B.Cu")
		(net "GND")
	)
	(via
		(at 177.8 -375.92)
		(size 0.508)
		(drill 0.254)
		(layers "F.Cu" "B.Cu")
		(net "GND")
	)
	(via
		(at 40.2082 -34.3408)
		(size 0.508)
		(drill 0.254)
		(layers "F.Cu" "B.Cu")
		(net "GND")
	)
	(via
		(at 7.624572 -1.397)
		(size 0.508)
		(drill 0.254)
		(layers "F.Cu" "B.Cu")
		(net "GND")
	)
	(via
		(at 127 -238.76)
		(size 0.508)
		(drill 0.254)
		(layers "F.Cu" "B.Cu")
		(net "GND")
	)
	(via
		(at 105.227374 -208.470754)
		(size 0.508)
		(drill 0.254)
		(layers "F.Cu" "B.Cu")
		(net "GND")
	)
	(via
		(at 262.103108 -331.118464)
		(size 0.508)
		(drill 0.254)
		(layers "F.Cu" "B.Cu")
		(net "GND")
	)
	(via
		(at 86.36 -264.16)
		(size 0.508)
		(drill 0.254)
		(layers "F.Cu" "B.Cu")
		(net "GND")
	)
	(via
		(at 172.72 -477.52)
		(size 0.508)
		(drill 0.254)
		(layers "F.Cu" "B.Cu")
		(net "GND")
	)
	(via
		(at 182.88 -55.88)
		(size 0.508)
		(drill 0.254)
		(layers "F.Cu" "B.Cu")
		(net "GND")
	)
	(via
		(at 167.64 -193.04)
		(size 0.508)
		(drill 0.254)
		(layers "F.Cu" "B.Cu")
		(net "GND")
	)
	(via
		(at 222.616014 -268.590014)
		(size 0.508)
		(drill 0.254)
		(layers "F.Cu" "B.Cu")
		(net "GND")
	)
	(via
		(at 157.48 -248.92)
		(size 0.508)
		(drill 0.254)
		(layers "F.Cu" "B.Cu")
		(net "GND")
	)
	(via
		(at 4.191 -195.490084)
		(size 0.508)
		(drill 0.254)
		(layers "F.Cu" "B.Cu")
		(net "GND")
	)
	(via
		(at 96.774 -100.203)
		(size 0.508)
		(drill 0.254)
		(layers "F.Cu" "B.Cu")
		(net "GND")
	)
	(via
		(at 182.88 -208.28)
		(size 0.508)
		(drill 0.254)
		(layers "F.Cu" "B.Cu")
		(net "GND")
	)
	(via
		(at 238.76 -101.6)
		(size 0.508)
		(drill 0.254)
		(layers "F.Cu" "B.Cu")
		(net "GND")
	)
	(via
		(at 121.92 -421.64)
		(size 0.508)
		(drill 0.254)
		(layers "F.Cu" "B.Cu")
		(net "GND")
	)
	(via
		(at 24.384 -228.609906)
		(size 0.508)
		(drill 0.254)
		(layers "F.Cu" "B.Cu")
		(net "GND")
	)
	(via
		(at 132.08 -198.12)
		(size 0.508)
		(drill 0.254)
		(layers "F.Cu" "B.Cu")
		(net "GND")
	)
	(via
		(at 182.88 -436.88)
		(size 0.508)
		(drill 0.254)
		(layers "F.Cu" "B.Cu")
		(net "GND")
	)
	(via
		(at 111.76 -45.72)
		(size 0.508)
		(drill 0.254)
		(layers "F.Cu" "B.Cu")
		(net "GND")
	)
	(via
		(at 254 -228.6)
		(size 0.508)
		(drill 0.254)
		(layers "F.Cu" "B.Cu")
		(net "GND")
	)
	(via
		(at 247.65 -394.97)
		(size 0.7112)
		(drill 0.4064)
		(layers "F.Cu" "B.Cu")
		(net "GND")
	)
	(via
		(at 172.72 -264.16)
		(size 0.508)
		(drill 0.254)
		(layers "F.Cu" "B.Cu")
		(net "GND")
	)
	(via
		(at 140.349986 -504.603004)
		(size 0.508)
		(drill 0.254)
		(layers "F.Cu" "B.Cu")
		(net "GND")
	)
	(via
		(at 243.84 -238.76)
		(size 0.508)
		(drill 0.254)
		(layers "F.Cu" "B.Cu")
		(net "GND")
	)
	(via
		(at 259.08 -101.6)
		(size 0.508)
		(drill 0.254)
		(layers "F.Cu" "B.Cu")
		(net "GND")
	)
	(via
		(at 30.361636 -308.98465)
		(size 0.508)
		(drill 0.254)
		(layers "F.Cu" "B.Cu")
		(net "GND")
	)
	(via
		(at 157.48 -320.04)
		(size 0.508)
		(drill 0.254)
		(layers "F.Cu" "B.Cu")
		(net "GND")
	)
	(via
		(at 127 -20.32)
		(size 0.508)
		(drill 0.254)
		(layers "F.Cu" "B.Cu")
		(net "GND")
	)
	(via
		(at 193.04 -304.8)
		(size 0.508)
		(drill 0.254)
		(layers "F.Cu" "B.Cu")
		(net "GND")
	)
	(via
		(at 172.72 -50.8)
		(size 0.508)
		(drill 0.254)
		(layers "F.Cu" "B.Cu")
		(net "GND")
	)
	(via
		(at 91.44 -462.28)
		(size 0.508)
		(drill 0.254)
		(layers "F.Cu" "B.Cu")
		(net "GND")
	)
	(via
		(at 106.68 -426.72)
		(size 0.508)
		(drill 0.254)
		(layers "F.Cu" "B.Cu")
		(net "GND")
	)
	(via
		(at 238.76 -447.04)
		(size 0.508)
		(drill 0.254)
		(layers "F.Cu" "B.Cu")
		(net "GND")
	)
	(via
		(at 243.84 -20.32)
		(size 0.508)
		(drill 0.254)
		(layers "F.Cu" "B.Cu")
		(net "GND")
	)
	(via
		(at 121.92 -299.72)
		(size 0.508)
		(drill 0.254)
		(layers "F.Cu" "B.Cu")
		(net "GND")
	)
	(via
		(at 222.616014 -62.589918)
		(size 0.508)
		(drill 0.254)
		(layers "F.Cu" "B.Cu")
		(net "GND")
	)
	(via
		(at 91.44 -472.44)
		(size 0.508)
		(drill 0.254)
		(layers "F.Cu" "B.Cu")
		(net "GND")
	)
	(via
		(at 81.28 -472.44)
		(size 0.508)
		(drill 0.254)
		(layers "F.Cu" "B.Cu")
		(net "GND")
	)
	(via
		(at 127 -492.76)
		(size 0.508)
		(drill 0.254)
		(layers "F.Cu" "B.Cu")
		(net "GND")
	)
	(via
		(at 81.28 -269.24)
		(size 0.508)
		(drill 0.254)
		(layers "F.Cu" "B.Cu")
		(net "GND")
	)
	(via
		(at 95.377 -430.403)
		(size 0.508)
		(drill 0.254)
		(layers "F.Cu" "B.Cu")
		(net "GND")
	)
	(via
		(at 43.58513 -154.794966)
		(size 0.508)
		(drill 0.254)
		(layers "F.Cu" "B.Cu")
		(net "GND")
	)
	(via
		(at 6.223 -351.209864)
		(size 0.508)
		(drill 0.254)
		(layers "F.Cu" "B.Cu")
		(net "GND")
	)
	(via
		(at 230.798116 -470.700862)
		(size 0.508)
		(drill 0.254)
		(layers "F.Cu" "B.Cu")
		(net "GND")
	)
	(via
		(at 248.92 -106.68)
		(size 0.508)
		(drill 0.254)
		(layers "F.Cu" "B.Cu")
		(net "GND")
	)
	(via
		(at 6.985 -96.52)
		(size 0.508)
		(drill 0.254)
		(layers "F.Cu" "B.Cu")
		(net "GND")
	)
	(via
		(at 76.2 -55.88)
		(size 0.508)
		(drill 0.254)
		(layers "F.Cu" "B.Cu")
		(net "GND")
	)
	(via
		(at 226.441 -433.832)
		(size 0.508)
		(drill 0.254)
		(layers "F.Cu" "B.Cu")
		(net "GND")
	)
	(via
		(at 242.57 -387.35)
		(size 0.7112)
		(drill 0.4064)
		(layers "F.Cu" "B.Cu")
		(net "GND")
	)
	(via
		(at 81.661 -214.122)
		(size 0.508)
		(drill 0.254)
		(layers "F.Cu" "B.Cu")
		(net "GND")
	)
	(via
		(at 137.16 -101.6)
		(size 0.508)
		(drill 0.254)
		(layers "F.Cu" "B.Cu")
		(net "GND")
	)
	(via
		(at 152.4 -487.68)
		(size 0.508)
		(drill 0.254)
		(layers "F.Cu" "B.Cu")
		(net "GND")
	)
	(via
		(at 4.191 -422.921176)
		(size 0.508)
		(drill 0.254)
		(layers "F.Cu" "B.Cu")
		(net "GND")
	)
	(via
		(at 167.64 -248.92)
		(size 0.508)
		(drill 0.254)
		(layers "F.Cu" "B.Cu")
		(net "GND")
	)
	(via
		(at 142.24 -172.72)
		(size 0.508)
		(drill 0.254)
		(layers "F.Cu" "B.Cu")
		(net "GND")
	)
	(via
		(at 50.8 -177.8)
		(size 0.508)
		(drill 0.254)
		(layers "F.Cu" "B.Cu")
		(net "GND")
	)
	(via
		(at 101.6 -142.24)
		(size 0.508)
		(drill 0.254)
		(layers "F.Cu" "B.Cu")
		(net "GND")
	)
	(via
		(at 259.08 -309.88)
		(size 0.508)
		(drill 0.254)
		(layers "F.Cu" "B.Cu")
		(net "GND")
	)
	(via
		(at 34.31413 -158.852108)
		(size 0.508)
		(drill 0.254)
		(layers "F.Cu" "B.Cu")
		(net "GND")
	)
	(via
		(at 192.9638 -466.725)
		(size 0.508)
		(drill 0.254)
		(layers "F.Cu" "B.Cu")
		(net "GND")
	)
	(via
		(at 76.2 -314.96)
		(size 0.508)
		(drill 0.254)
		(layers "F.Cu" "B.Cu")
		(net "GND")
	)
	(via
		(at 71.12 -284.48)
		(size 0.508)
		(drill 0.254)
		(layers "F.Cu" "B.Cu")
		(net "GND")
	)
	(via
		(at 262.103108 -315.878464)
		(size 0.508)
		(drill 0.254)
		(layers "F.Cu" "B.Cu")
		(net "GND")
	)
	(via
		(at 213.36 -162.56)
		(size 0.508)
		(drill 0.254)
		(layers "F.Cu" "B.Cu")
		(net "GND")
	)
	(via
		(at 60.96 -284.48)
		(size 0.508)
		(drill 0.254)
		(layers "F.Cu" "B.Cu")
		(net "GND")
	)
	(via
		(at 24.384 -35.409886)
		(size 0.508)
		(drill 0.254)
		(layers "F.Cu" "B.Cu")
		(net "GND")
	)
	(via
		(at 5.6134 -457.9112)
		(size 0.7112)
		(drill 0.4064)
		(layers "F.Cu" "B.Cu")
		(net "GND")
	)
	(via
		(at 93.98 -98.806)
		(size 0.508)
		(drill 0.254)
		(layers "F.Cu" "B.Cu")
		(net "GND")
	)
	(via
		(at 106.68 -330.2)
		(size 0.508)
		(drill 0.254)
		(layers "F.Cu" "B.Cu")
		(net "GND")
	)
	(via
		(at 116.84 -127)
		(size 0.508)
		(drill 0.254)
		(layers "F.Cu" "B.Cu")
		(net "GND")
	)
	(via
		(at 6.223 -182.81142)
		(size 0.508)
		(drill 0.254)
		(layers "F.Cu" "B.Cu")
		(net "GND")
	)
	(via
		(at 24.384 -37.809932)
		(size 0.508)
		(drill 0.254)
		(layers "F.Cu" "B.Cu")
		(net "GND")
	)
	(via
		(at 233.68 -147.32)
		(size 0.508)
		(drill 0.254)
		(layers "F.Cu" "B.Cu")
		(net "GND")
	)
	(via
		(at 243.84 -25.4)
		(size 0.508)
		(drill 0.254)
		(layers "F.Cu" "B.Cu")
		(net "GND")
	)
	(via
		(at 111.76 -355.6)
		(size 0.508)
		(drill 0.254)
		(layers "F.Cu" "B.Cu")
		(net "GND")
	)
	(via
		(at 210.312 -472.948)
		(size 0.508)
		(drill 0.254)
		(layers "F.Cu" "B.Cu")
		(net "GND")
	)
	(via
		(at 66.04 -406.4)
		(size 0.508)
		(drill 0.254)
		(layers "F.Cu" "B.Cu")
		(net "GND")
	)
	(via
		(at 4.191 -218.766136)
		(size 0.508)
		(drill 0.254)
		(layers "F.Cu" "B.Cu")
		(net "GND")
	)
	(via
		(at 91.44 -350.52)
		(size 0.508)
		(drill 0.254)
		(layers "F.Cu" "B.Cu")
		(net "GND")
	)
	(via
		(at 43.58513 -467.60511)
		(size 0.508)
		(drill 0.254)
		(layers "F.Cu" "B.Cu")
		(net "GND")
	)
	(via
		(at 6.223 -158.723838)
		(size 0.508)
		(drill 0.254)
		(layers "F.Cu" "B.Cu")
		(net "GND")
	)
	(via
		(at 233.68 -320.04)
		(size 0.508)
		(drill 0.254)
		(layers "F.Cu" "B.Cu")
		(net "GND")
	)
	(via
		(at 262.103108 -183.798464)
		(size 0.508)
		(drill 0.254)
		(layers "F.Cu" "B.Cu")
		(net "GND")
	)
	(via
		(at 18.669 -197.993)
		(size 0.508)
		(drill 0.254)
		(layers "F.Cu" "B.Cu")
		(net "GND")
	)
	(via
		(at 254 -96.52)
		(size 0.508)
		(drill 0.254)
		(layers "F.Cu" "B.Cu")
		(net "GND")
	)
	(via
		(at 172.72 -147.32)
		(size 0.508)
		(drill 0.254)
		(layers "F.Cu" "B.Cu")
		(net "GND")
	)
	(via
		(at 228.6 -25.4)
		(size 0.508)
		(drill 0.254)
		(layers "F.Cu" "B.Cu")
		(net "GND")
	)
	(via
		(at 172.72 -76.2)
		(size 0.508)
		(drill 0.254)
		(layers "F.Cu" "B.Cu")
		(net "GND")
	)
	(via
		(at 76.449936 -364.109)
		(size 0.508)
		(drill 0.254)
		(layers "F.Cu" "B.Cu")
		(net "GND")
	)
	(via
		(at 6.223 -441.242704)
		(size 0.508)
		(drill 0.254)
		(layers "F.Cu" "B.Cu")
		(net "GND")
	)
	(via
		(at 213.36 -314.96)
		(size 0.508)
		(drill 0.254)
		(layers "F.Cu" "B.Cu")
		(net "GND")
	)
	(via
		(at 198.12 -162.56)
		(size 0.508)
		(drill 0.254)
		(layers "F.Cu" "B.Cu")
		(net "GND")
	)
	(via
		(at 208.28 -360.68)
		(size 0.508)
		(drill 0.254)
		(layers "F.Cu" "B.Cu")
		(net "GND")
	)
	(via
		(at 127 -325.12)
		(size 0.508)
		(drill 0.254)
		(layers "F.Cu" "B.Cu")
		(net "GND")
	)
	(via
		(at 12.446 -162.052)
		(size 0.508)
		(drill 0.254)
		(layers "F.Cu" "B.Cu")
		(net "GND")
	)
	(via
		(at 223.52 -15.24)
		(size 0.508)
		(drill 0.254)
		(layers "F.Cu" "B.Cu")
		(net "GND")
	)
	(via
		(at 34.31413 -174.780956)
		(size 0.508)
		(drill 0.254)
		(layers "F.Cu" "B.Cu")
		(net "GND")
	)
	(via
		(at 96.774 -306.578)
		(size 0.508)
		(drill 0.254)
		(layers "F.Cu" "B.Cu")
		(net "GND")
	)
	(via
		(at 6.223 -408.290014)
		(size 0.508)
		(drill 0.254)
		(layers "F.Cu" "B.Cu")
		(net "GND")
	)
	(via
		(at 40.64 -340.36)
		(size 0.508)
		(drill 0.254)
		(layers "F.Cu" "B.Cu")
		(net "GND")
	)
	(via
		(at 91.186 -431.8)
		(size 0.508)
		(drill 0.254)
		(layers "F.Cu" "B.Cu")
		(net "GND")
	)
	(via
		(at 116.84 -375.92)
		(size 0.508)
		(drill 0.254)
		(layers "F.Cu" "B.Cu")
		(net "GND")
	)
	(via
		(at 203.2 -71.12)
		(size 0.508)
		(drill 0.254)
		(layers "F.Cu" "B.Cu")
		(net "GND")
	)
	(via
		(at 121.92 -71.12)
		(size 0.508)
		(drill 0.254)
		(layers "F.Cu" "B.Cu")
		(net "GND")
	)
	(via
		(at 262.103108 -188.878464)
		(size 0.508)
		(drill 0.254)
		(layers "F.Cu" "B.Cu")
		(net "GND")
	)
	(via
		(at 187.96 -60.96)
		(size 0.508)
		(drill 0.254)
		(layers "F.Cu" "B.Cu")
		(net "GND")
	)
	(via
		(at 55.88 -91.44)
		(size 0.508)
		(drill 0.254)
		(layers "F.Cu" "B.Cu")
		(net "GND")
	)
	(via
		(at 50.8 -20.32)
		(size 0.508)
		(drill 0.254)
		(layers "F.Cu" "B.Cu")
		(net "GND")
	)
	(via
		(at 137.16 -381)
		(size 0.508)
		(drill 0.254)
		(layers "F.Cu" "B.Cu")
		(net "GND")
	)
	(via
		(at 27.695652 -17.392904)
		(size 0.508)
		(drill 0.254)
		(layers "F.Cu" "B.Cu")
		(net "GND")
	)
	(via
		(at 243.84 -71.12)
		(size 0.508)
		(drill 0.254)
		(layers "F.Cu" "B.Cu")
		(net "GND")
	)
	(via
		(at 157.48 -269.24)
		(size 0.508)
		(drill 0.254)
		(layers "F.Cu" "B.Cu")
		(net "GND")
	)
	(via
		(at 106.68 -375.92)
		(size 0.508)
		(drill 0.254)
		(layers "F.Cu" "B.Cu")
		(net "GND")
	)
	(via
		(at 116.84 -223.52)
		(size 0.508)
		(drill 0.254)
		(layers "F.Cu" "B.Cu")
		(net "GND")
	)
	(via
		(at 162.56 -223.52)
		(size 0.508)
		(drill 0.254)
		(layers "F.Cu" "B.Cu")
		(net "GND")
	)
	(via
		(at 32.5628 -15.5702)
		(size 0.508)
		(drill 0.254)
		(layers "F.Cu" "B.Cu")
		(net "GND")
	)
	(via
		(at 193.04 -55.88)
		(size 0.508)
		(drill 0.254)
		(layers "F.Cu" "B.Cu")
		(net "GND")
	)
	(via
		(at 94.629986 -504.603004)
		(size 0.508)
		(drill 0.254)
		(layers "F.Cu" "B.Cu")
		(net "GND")
	)
	(via
		(at 81.28 -86.36)
		(size 0.508)
		(drill 0.254)
		(layers "F.Cu" "B.Cu")
		(net "GND")
	)
	(via
		(at 248.92 -355.6)
		(size 0.508)
		(drill 0.254)
		(layers "F.Cu" "B.Cu")
		(net "GND")
	)
	(via
		(at 71.12 -20.32)
		(size 0.508)
		(drill 0.254)
		(layers "F.Cu" "B.Cu")
		(net "GND")
	)
	(via
		(at 152.4 -177.8)
		(size 0.508)
		(drill 0.254)
		(layers "F.Cu" "B.Cu")
		(net "GND")
	)
	(via
		(at 238.76 -111.76)
		(size 0.508)
		(drill 0.254)
		(layers "F.Cu" "B.Cu")
		(net "GND")
	)
	(via
		(at 219.274898 -479.101404)
		(size 0.508)
		(drill 0.254)
		(layers "F.Cu" "B.Cu")
		(net "GND")
	)
	(via
		(at 177.8 -127)
		(size 0.508)
		(drill 0.254)
		(layers "F.Cu" "B.Cu")
		(net "GND")
	)
	(via
		(at 96.52 -142.24)
		(size 0.508)
		(drill 0.254)
		(layers "F.Cu" "B.Cu")
		(net "GND")
	)
	(via
		(at 152.4 -81.28)
		(size 0.508)
		(drill 0.254)
		(layers "F.Cu" "B.Cu")
		(net "GND")
	)
	(via
		(at 220.726 -403.606)
		(size 0.508)
		(drill 0.254)
		(layers "F.Cu" "B.Cu")
		(net "GND")
	)
	(via
		(at 243.84 -177.8)
		(size 0.508)
		(drill 0.254)
		(layers "F.Cu" "B.Cu")
		(net "GND")
	)
	(via
		(at 9.732518 -458.340714)
		(size 0.7112)
		(drill 0.4064)
		(layers "F.Cu" "B.Cu")
		(net "GND")
	)
	(via
		(at 162.56 -502.92)
		(size 0.508)
		(drill 0.254)
		(layers "F.Cu" "B.Cu")
		(net "GND")
	)
	(via
		(at 40.64 -20.32)
		(size 0.508)
		(drill 0.254)
		(layers "F.Cu" "B.Cu")
		(net "GND")
	)
	(via
		(at 254 -472.44)
		(size 0.508)
		(drill 0.254)
		(layers "F.Cu" "B.Cu")
		(net "GND")
	)
	(via
		(at 193.04 -218.44)
		(size 0.508)
		(drill 0.254)
		(layers "F.Cu" "B.Cu")
		(net "GND")
	)
	(via
		(at 6.223 -355.874574)
		(size 0.508)
		(drill 0.254)
		(layers "F.Cu" "B.Cu")
		(net "GND")
	)
	(via
		(at 71.12 -106.68)
		(size 0.508)
		(drill 0.254)
		(layers "F.Cu" "B.Cu")
		(net "GND")
	)
	(via
		(at 27.686 -434.219096)
		(size 0.508)
		(drill 0.254)
		(layers "F.Cu" "B.Cu")
		(net "GND")
	)
	(via
		(at 6.223 -168.324022)
		(size 0.508)
		(drill 0.254)
		(layers "F.Cu" "B.Cu")
		(net "GND")
	)
	(via
		(at 34.31413 -176.398936)
		(size 0.508)
		(drill 0.254)
		(layers "F.Cu" "B.Cu")
		(net "GND")
	)
	(via
		(at 198.12 -441.96)
		(size 0.508)
		(drill 0.254)
		(layers "F.Cu" "B.Cu")
		(net "GND")
	)
	(via
		(at 221.71025 -444.9064)
		(size 0.508)
		(drill 0.254)
		(layers "F.Cu" "B.Cu")
		(net "GND")
	)
	(via
		(at 6.223 -231.611424)
		(size 0.508)
		(drill 0.254)
		(layers "F.Cu" "B.Cu")
		(net "GND")
	)
	(via
		(at 203.2 -86.36)
		(size 0.508)
		(drill 0.254)
		(layers "F.Cu" "B.Cu")
		(net "GND")
	)
	(via
		(at 121.92 -386.08)
		(size 0.508)
		(drill 0.254)
		(layers "F.Cu" "B.Cu")
		(net "GND")
	)
	(via
		(at 238.76 -269.24)
		(size 0.508)
		(drill 0.254)
		(layers "F.Cu" "B.Cu")
		(net "GND")
	)
	(via
		(at 243.84 -436.88)
		(size 0.508)
		(drill 0.254)
		(layers "F.Cu" "B.Cu")
		(net "GND")
	)
	(via
		(at 66.04 -259.08)
		(size 0.508)
		(drill 0.254)
		(layers "F.Cu" "B.Cu")
		(net "GND")
	)
	(via
		(at 127 -86.36)
		(size 0.508)
		(drill 0.254)
		(layers "F.Cu" "B.Cu")
		(net "GND")
	)
	(via
		(at 35.56 -269.113)
		(size 0.508)
		(drill 0.254)
		(layers "F.Cu" "B.Cu")
		(net "GND")
	)
	(via
		(at 147.32 -243.84)
		(size 0.508)
		(drill 0.254)
		(layers "F.Cu" "B.Cu")
		(net "GND")
	)
	(via
		(at 60.96 -347.345)
		(size 0.508)
		(drill 0.254)
		(layers "F.Cu" "B.Cu")
		(net "GND")
	)
	(via
		(at 86.36 -289.56)
		(size 0.508)
		(drill 0.254)
		(layers "F.Cu" "B.Cu")
		(net "GND")
	)
	(via
		(at 182.88 -157.48)
		(size 0.508)
		(drill 0.254)
		(layers "F.Cu" "B.Cu")
		(net "GND")
	)
	(via
		(at 4.191 -335.166208)
		(size 0.508)
		(drill 0.254)
		(layers "F.Cu" "B.Cu")
		(net "GND")
	)
	(via
		(at 127 -50.8)
		(size 0.508)
		(drill 0.254)
		(layers "F.Cu" "B.Cu")
		(net "GND")
	)
	(via
		(at 197.7136 -167.5892)
		(size 0.508)
		(drill 0.254)
		(layers "F.Cu" "B.Cu")
		(net "GND")
	)
	(via
		(at 172.72 -81.28)
		(size 0.508)
		(drill 0.254)
		(layers "F.Cu" "B.Cu")
		(net "GND")
	)
	(via
		(at 228.6 -309.88)
		(size 0.508)
		(drill 0.254)
		(layers "F.Cu" "B.Cu")
		(net "GND")
	)
	(via
		(at 105.225596 -310.704484)
		(size 0.508)
		(drill 0.254)
		(layers "F.Cu" "B.Cu")
		(net "GND")
	)
	(via
		(at 116.84 -25.4)
		(size 0.508)
		(drill 0.254)
		(layers "F.Cu" "B.Cu")
		(net "GND")
	)
	(via
		(at 92.837 -202.438)
		(size 0.508)
		(drill 0.254)
		(layers "F.Cu" "B.Cu")
		(net "GND")
	)
	(via
		(at 127 -127)
		(size 0.508)
		(drill 0.254)
		(layers "F.Cu" "B.Cu")
		(net "GND")
	)
	(via
		(at 238.76 -223.52)
		(size 0.508)
		(drill 0.254)
		(layers "F.Cu" "B.Cu")
		(net "GND")
	)
	(via
		(at 4.191 -331.09027)
		(size 0.508)
		(drill 0.254)
		(layers "F.Cu" "B.Cu")
		(net "GND")
	)
	(via
		(at 157.48 -299.72)
		(size 0.508)
		(drill 0.254)
		(layers "F.Cu" "B.Cu")
		(net "GND")
	)
	(via
		(at 94.488 -314.071)
		(size 0.508)
		(drill 0.254)
		(layers "F.Cu" "B.Cu")
		(net "GND")
	)
	(via
		(at 228.585014 -484.11511)
		(size 0.508)
		(drill 0.254)
		(layers "F.Cu" "B.Cu")
		(net "GND")
	)
	(via
		(at 99.50831 -294.094408)
		(size 0.508)
		(drill 0.254)
		(layers "F.Cu" "B.Cu")
		(net "GND")
	)
	(via
		(at 66.04 -50.8)
		(size 0.508)
		(drill 0.254)
		(layers "F.Cu" "B.Cu")
		(net "GND")
	)
	(via
		(at 6.223 -429.242728)
		(size 0.508)
		(drill 0.254)
		(layers "F.Cu" "B.Cu")
		(net "GND")
	)
	(via
		(at 259.08 -137.16)
		(size 0.508)
		(drill 0.254)
		(layers "F.Cu" "B.Cu")
		(net "GND")
	)
	(via
		(at 142.24 -15.24)
		(size 0.508)
		(drill 0.254)
		(layers "F.Cu" "B.Cu")
		(net "GND")
	)
	(via
		(at 147.32 -101.6)
		(size 0.508)
		(drill 0.254)
		(layers "F.Cu" "B.Cu")
		(net "GND")
	)
	(via
		(at 50.8 -477.52)
		(size 0.508)
		(drill 0.254)
		(layers "F.Cu" "B.Cu")
		(net "GND")
	)
	(via
		(at 137.16 -203.2)
		(size 0.508)
		(drill 0.254)
		(layers "F.Cu" "B.Cu")
		(net "GND")
	)
	(via
		(at 49.657 -241.2365)
		(size 0.508)
		(drill 0.254)
		(layers "F.Cu" "B.Cu")
		(net "GND")
	)
	(via
		(at 28.7528 -421.5892)
		(size 0.508)
		(drill 0.254)
		(layers "F.Cu" "B.Cu")
		(net "GND")
	)
	(via
		(at 248.92 -279.4)
		(size 0.508)
		(drill 0.254)
		(layers "F.Cu" "B.Cu")
		(net "GND")
	)
	(via
		(at 262.103108 -448.556126)
		(size 0.508)
		(drill 0.254)
		(layers "F.Cu" "B.Cu")
		(net "GND")
	)
	(via
		(at 4.191 -321.490086)
		(size 0.508)
		(drill 0.254)
		(layers "F.Cu" "B.Cu")
		(net "GND")
	)
	(via
		(at 250.4948 -357.886)
		(size 0.508)
		(drill 0.254)
		(layers "F.Cu" "B.Cu")
		(net "GND")
	)
	(via
		(at 35.56 -462.28)
		(size 0.508)
		(drill 0.254)
		(layers "F.Cu" "B.Cu")
		(net "GND")
	)
	(via
		(at 259.08 -60.96)
		(size 0.508)
		(drill 0.254)
		(layers "F.Cu" "B.Cu")
		(net "GND")
	)
	(via
		(at 228.6 -203.2)
		(size 0.508)
		(drill 0.254)
		(layers "F.Cu" "B.Cu")
		(net "GND")
	)
	(via
		(at 6.223 -389.89)
		(size 0.508)
		(drill 0.254)
		(layers "F.Cu" "B.Cu")
		(net "GND")
	)
	(via
		(at 228.585014 -463.79511)
		(size 0.508)
		(drill 0.254)
		(layers "F.Cu" "B.Cu")
		(net "GND")
	)
	(via
		(at 248.92 -218.44)
		(size 0.508)
		(drill 0.254)
		(layers "F.Cu" "B.Cu")
		(net "GND")
	)
	(via
		(at 142.24 -441.96)
		(size 0.508)
		(drill 0.254)
		(layers "F.Cu" "B.Cu")
		(net "GND")
	)
	(via
		(at 4.191 -291.090096)
		(size 0.508)
		(drill 0.254)
		(layers "F.Cu" "B.Cu")
		(net "GND")
	)
	(via
		(at 60.96 -218.44)
		(size 0.508)
		(drill 0.254)
		(layers "F.Cu" "B.Cu")
		(net "GND")
	)
	(via
		(at 121.92 -182.88)
		(size 0.508)
		(drill 0.254)
		(layers "F.Cu" "B.Cu")
		(net "GND")
	)
	(via
		(at 262.103108 -259.998464)
		(size 0.508)
		(drill 0.254)
		(layers "F.Cu" "B.Cu")
		(net "GND")
	)
	(via
		(at 6.223 -336.725514)
		(size 0.508)
		(drill 0.254)
		(layers "F.Cu" "B.Cu")
		(net "GND")
	)
	(via
		(at 127 -299.72)
		(size 0.508)
		(drill 0.254)
		(layers "F.Cu" "B.Cu")
		(net "GND")
	)
	(via
		(at 193.04 -137.16)
		(size 0.508)
		(drill 0.254)
		(layers "F.Cu" "B.Cu")
		(net "GND")
	)
	(via
		(at 71.12 -55.88)
		(size 0.508)
		(drill 0.254)
		(layers "F.Cu" "B.Cu")
		(net "GND")
	)
	(via
		(at 6.223 -397.994378)
		(size 0.508)
		(drill 0.254)
		(layers "F.Cu" "B.Cu")
		(net "GND")
	)
	(via
		(at 236.869986 -504.603004)
		(size 0.508)
		(drill 0.254)
		(layers "F.Cu" "B.Cu")
		(net "GND")
	)
	(via
		(at 116.84 -477.52)
		(size 0.508)
		(drill 0.254)
		(layers "F.Cu" "B.Cu")
		(net "GND")
	)
	(via
		(at 228.6 -330.2)
		(size 0.508)
		(drill 0.254)
		(layers "F.Cu" "B.Cu")
		(net "GND")
	)
	(via
		(at 254 -497.84)
		(size 0.508)
		(drill 0.254)
		(layers "F.Cu" "B.Cu")
		(net "GND")
	)
	(via
		(at 262.103108 -499.356126)
		(size 0.508)
		(drill 0.254)
		(layers "F.Cu" "B.Cu")
		(net "GND")
	)
	(via
		(at 50.8 -187.96)
		(size 0.508)
		(drill 0.254)
		(layers "F.Cu" "B.Cu")
		(net "GND")
	)
	(via
		(at 137.16 -187.96)
		(size 0.508)
		(drill 0.254)
		(layers "F.Cu" "B.Cu")
		(net "GND")
	)
	(via
		(at 4.191 -228.366066)
		(size 0.508)
		(drill 0.254)
		(layers "F.Cu" "B.Cu")
		(net "GND")
	)
	(via
		(at 152.4 -502.92)
		(size 0.508)
		(drill 0.254)
		(layers "F.Cu" "B.Cu")
		(net "GND")
	)
	(via
		(at 81.28 -259.08)
		(size 0.508)
		(drill 0.254)
		(layers "F.Cu" "B.Cu")
		(net "GND")
	)
	(via
		(at 106.68 -365.76)
		(size 0.508)
		(drill 0.254)
		(layers "F.Cu" "B.Cu")
		(net "GND")
	)
	(via
		(at 219.314014 -73.398888)
		(size 0.508)
		(drill 0.254)
		(layers "F.Cu" "B.Cu")
		(net "GND")
	)
	(via
		(at 172.72 -213.36)
		(size 0.508)
		(drill 0.254)
		(layers "F.Cu" "B.Cu")
		(net "GND")
	)
	(via
		(at 254 -436.88)
		(size 0.508)
		(drill 0.254)
		(layers "F.Cu" "B.Cu")
		(net "GND")
	)
	(via
		(at 111.76 -254)
		(size 0.508)
		(drill 0.254)
		(layers "F.Cu" "B.Cu")
		(net "GND")
	)
	(via
		(at 77.343 -212.5218)
		(size 0.508)
		(drill 0.254)
		(layers "F.Cu" "B.Cu")
		(net "GND")
	)
	(via
		(at 27.69616 -326.393048)
		(size 0.508)
		(drill 0.254)
		(layers "F.Cu" "B.Cu")
		(net "GND")
	)
	(via
		(at 17.784572 -1.397)
		(size 0.508)
		(drill 0.254)
		(layers "F.Cu" "B.Cu")
		(net "GND")
	)
	(via
		(at 86.36 -30.48)
		(size 0.508)
		(drill 0.254)
		(layers "F.Cu" "B.Cu")
		(net "GND")
	)
	(via
		(at 172.72 -487.68)
		(size 0.508)
		(drill 0.254)
		(layers "F.Cu" "B.Cu")
		(net "GND")
	)
	(via
		(at 238.76 -284.48)
		(size 0.508)
		(drill 0.254)
		(layers "F.Cu" "B.Cu")
		(net "GND")
	)
	(via
		(at 35.56 -62.865)
		(size 0.508)
		(drill 0.254)
		(layers "F.Cu" "B.Cu")
		(net "GND")
	)
	(via
		(at 170.829986 -504.603004)
		(size 0.508)
		(drill 0.254)
		(layers "F.Cu" "B.Cu")
		(net "GND")
	)
	(via
		(at 41.529 -107.442)
		(size 0.508)
		(drill 0.254)
		(layers "F.Cu" "B.Cu")
		(net "GND")
	)
	(via
		(at 203.2 -457.2)
		(size 0.508)
		(drill 0.254)
		(layers "F.Cu" "B.Cu")
		(net "GND")
	)
	(via
		(at 4.191 -179.566062)
		(size 0.508)
		(drill 0.254)
		(layers "F.Cu" "B.Cu")
		(net "GND")
	)
	(via
		(at 37.61613 -259.78993)
		(size 0.508)
		(drill 0.254)
		(layers "F.Cu" "B.Cu")
		(net "GND")
	)
	(via
		(at 127 -121.92)
		(size 0.508)
		(drill 0.254)
		(layers "F.Cu" "B.Cu")
		(net "GND")
	)
	(via
		(at 4.191 -430.784)
		(size 0.508)
		(drill 0.254)
		(layers "F.Cu" "B.Cu")
		(net "GND")
	)
	(via
		(at 167.64 -40.64)
		(size 0.508)
		(drill 0.254)
		(layers "F.Cu" "B.Cu")
		(net "GND")
	)
	(via
		(at 229.828852 -470.700862)
		(size 0.508)
		(drill 0.254)
		(layers "F.Cu" "B.Cu")
		(net "GND")
	)
	(via
		(at 111.76 -152.4)
		(size 0.508)
		(drill 0.254)
		(layers "F.Cu" "B.Cu")
		(net "GND")
	)
	(via
		(at 24.384 -235.009944)
		(size 0.508)
		(drill 0.254)
		(layers "F.Cu" "B.Cu")
		(net "GND")
	)
	(via
		(at 60.96 -40.64)
		(size 0.508)
		(drill 0.254)
		(layers "F.Cu" "B.Cu")
		(net "GND")
	)
	(via
		(at 87.312246 -222.071692)
		(size 0.508)
		(drill 0.254)
		(layers "F.Cu" "B.Cu")
		(net "GND")
	)
	(via
		(at 24.384 -27.409902)
		(size 0.508)
		(drill 0.254)
		(layers "F.Cu" "B.Cu")
		(net "GND")
	)
	(via
		(at 172.72 -218.44)
		(size 0.508)
		(drill 0.254)
		(layers "F.Cu" "B.Cu")
		(net "GND")
	)
	(via
		(at 4.191 -357.566214)
		(size 0.508)
		(drill 0.254)
		(layers "F.Cu" "B.Cu")
		(net "GND")
	)
	(via
		(at 203.2 -294.64)
		(size 0.508)
		(drill 0.254)
		(layers "F.Cu" "B.Cu")
		(net "GND")
	)
	(via
		(at 95.377 -434.594)
		(size 0.508)
		(drill 0.254)
		(layers "F.Cu" "B.Cu")
		(net "GND")
	)
	(via
		(at 71.12 -50.8)
		(size 0.508)
		(drill 0.254)
		(layers "F.Cu" "B.Cu")
		(net "GND")
	)
	(via
		(at 6.223 -333.525368)
		(size 0.508)
		(drill 0.254)
		(layers "F.Cu" "B.Cu")
		(net "GND")
	)
	(via
		(at 212.3186 -501.269)
		(size 0.508)
		(drill 0.254)
		(layers "F.Cu" "B.Cu")
		(net "GND")
	)
	(via
		(at 91.44 -45.72)
		(size 0.508)
		(drill 0.254)
		(layers "F.Cu" "B.Cu")
		(net "GND")
	)
	(via
		(at 187.96 -10.16)
		(size 0.508)
		(drill 0.254)
		(layers "F.Cu" "B.Cu")
		(net "GND")
	)
	(via
		(at 137.16 -375.92)
		(size 0.508)
		(drill 0.254)
		(layers "F.Cu" "B.Cu")
		(net "GND")
	)
	(via
		(at 248.910348 -273.103594)
		(size 0.508)
		(drill 0.254)
		(layers "F.Cu" "B.Cu")
		(net "GND")
	)
	(via
		(at 177.8 -304.8)
		(size 0.508)
		(drill 0.254)
		(layers "F.Cu" "B.Cu")
		(net "GND")
	)
	(via
		(at 233.68 -269.24)
		(size 0.508)
		(drill 0.254)
		(layers "F.Cu" "B.Cu")
		(net "GND")
	)
	(via
		(at 206.389986 -504.603004)
		(size 0.508)
		(drill 0.254)
		(layers "F.Cu" "B.Cu")
		(net "GND")
	)
	(via
		(at 28.915614 -401.5486)
		(size 0.508)
		(drill 0.254)
		(layers "F.Cu" "B.Cu")
		(net "GND")
	)
	(via
		(at 177.8 -50.8)
		(size 0.508)
		(drill 0.254)
		(layers "F.Cu" "B.Cu")
		(net "GND")
	)
	(via
		(at 142.24 -10.16)
		(size 0.508)
		(drill 0.254)
		(layers "F.Cu" "B.Cu")
		(net "GND")
	)
	(via
		(at 37.61613 -492.990124)
		(size 0.508)
		(drill 0.254)
		(layers "F.Cu" "B.Cu")
		(net "GND")
	)
	(via
		(at 198.12 -55.88)
		(size 0.508)
		(drill 0.254)
		(layers "F.Cu" "B.Cu")
		(net "GND")
	)
	(via
		(at 223.4184 -97.8408)
		(size 0.508)
		(drill 0.254)
		(layers "F.Cu" "B.Cu")
		(net "GND")
	)
	(via
		(at 29.267912 -477.46158)
		(size 0.508)
		(drill 0.254)
		(layers "F.Cu" "B.Cu")
		(net "GND")
	)
	(via
		(at 243.84 -350.52)
		(size 0.508)
		(drill 0.254)
		(layers "F.Cu" "B.Cu")
		(net "GND")
	)
	(via
		(at 4.191 -212.366098)
		(size 0.508)
		(drill 0.254)
		(layers "F.Cu" "B.Cu")
		(net "GND")
	)
	(via
		(at 121.92 -35.56)
		(size 0.508)
		(drill 0.254)
		(layers "F.Cu" "B.Cu")
		(net "GND")
	)
	(via
		(at 182.88 -45.72)
		(size 0.508)
		(drill 0.254)
		(layers "F.Cu" "B.Cu")
		(net "GND")
	)
	(via
		(at 243.84 -289.56)
		(size 0.508)
		(drill 0.254)
		(layers "F.Cu" "B.Cu")
		(net "GND")
	)
	(via
		(at 157.48 -279.4)
		(size 0.508)
		(drill 0.254)
		(layers "F.Cu" "B.Cu")
		(net "GND")
	)
	(via
		(at 66.04 -457.2)
		(size 0.508)
		(drill 0.254)
		(layers "F.Cu" "B.Cu")
		(net "GND")
	)
	(via
		(at 228.585014 -51.794918)
		(size 0.508)
		(drill 0.254)
		(layers "F.Cu" "B.Cu")
		(net "GND")
	)
	(via
		(at 15.5194 -152.4254)
		(size 0.508)
		(drill 0.254)
		(layers "F.Cu" "B.Cu")
		(net "GND")
	)
	(via
		(at 259.08 -142.24)
		(size 0.508)
		(drill 0.254)
		(layers "F.Cu" "B.Cu")
		(net "GND")
	)
	(via
		(at 106.68 -401.32)
		(size 0.508)
		(drill 0.254)
		(layers "F.Cu" "B.Cu")
		(net "GND")
	)
	(via
		(at 96.774 -433.197)
		(size 0.508)
		(drill 0.254)
		(layers "F.Cu" "B.Cu")
		(net "GND")
	)
	(via
		(at 90.484452 -420.553388)
		(size 0.508)
		(drill 0.254)
		(layers "F.Cu" "B.Cu")
		(net "GND")
	)
	(via
		(at 240.03 -394.97)
		(size 0.7112)
		(drill 0.4064)
		(layers "F.Cu" "B.Cu")
		(net "GND")
	)
	(via
		(at 213.36 -30.48)
		(size 0.508)
		(drill 0.254)
		(layers "F.Cu" "B.Cu")
		(net "GND")
	)
	(via
		(at 50.8 -86.36)
		(size 0.508)
		(drill 0.254)
		(layers "F.Cu" "B.Cu")
		(net "GND")
	)
	(via
		(at 142.24 -20.32)
		(size 0.508)
		(drill 0.254)
		(layers "F.Cu" "B.Cu")
		(net "GND")
	)
	(via
		(at 162.56 -187.96)
		(size 0.508)
		(drill 0.254)
		(layers "F.Cu" "B.Cu")
		(net "GND")
	)
	(via
		(at 91.44 -238.76)
		(size 0.508)
		(drill 0.254)
		(layers "F.Cu" "B.Cu")
		(net "GND")
	)
	(via
		(at 30.48 -426.212)
		(size 0.508)
		(drill 0.254)
		(layers "F.Cu" "B.Cu")
		(net "GND")
	)
	(via
		(at 187.96 -116.84)
		(size 0.508)
		(drill 0.254)
		(layers "F.Cu" "B.Cu")
		(net "GND")
	)
	(via
		(at 248.92 -294.64)
		(size 0.508)
		(drill 0.254)
		(layers "F.Cu" "B.Cu")
		(net "GND")
	)
	(via
		(at 172.72 -30.48)
		(size 0.508)
		(drill 0.254)
		(layers "F.Cu" "B.Cu")
		(net "GND")
	)
	(via
		(at 238.76 -30.48)
		(size 0.508)
		(drill 0.254)
		(layers "F.Cu" "B.Cu")
		(net "GND")
	)
	(via
		(at 154.944572 -1.397)
		(size 0.508)
		(drill 0.254)
		(layers "F.Cu" "B.Cu")
		(net "GND")
	)
	(via
		(at 182.88 -472.44)
		(size 0.508)
		(drill 0.254)
		(layers "F.Cu" "B.Cu")
		(net "GND")
	)
	(via
		(at 91.44 -167.64)
		(size 0.508)
		(drill 0.254)
		(layers "F.Cu" "B.Cu")
		(net "GND")
	)
	(via
		(at 182.88 -152.4)
		(size 0.508)
		(drill 0.254)
		(layers "F.Cu" "B.Cu")
		(net "GND")
	)
	(via
		(at 182.88 -309.88)
		(size 0.508)
		(drill 0.254)
		(layers "F.Cu" "B.Cu")
		(net "GND")
	)
	(via
		(at 152.4 -314.96)
		(size 0.508)
		(drill 0.254)
		(layers "F.Cu" "B.Cu")
		(net "GND")
	)
	(via
		(at 50.8 -182.88)
		(size 0.508)
		(drill 0.254)
		(layers "F.Cu" "B.Cu")
		(net "GND")
	)
	(via
		(at 219.314014 -485.39908)
		(size 0.508)
		(drill 0.254)
		(layers "F.Cu" "B.Cu")
		(net "GND")
	)
	(via
		(at 132.08 -294.64)
		(size 0.508)
		(drill 0.254)
		(layers "F.Cu" "B.Cu")
		(net "GND")
	)
	(via
		(at 152.4 -147.32)
		(size 0.508)
		(drill 0.254)
		(layers "F.Cu" "B.Cu")
		(net "GND")
	)
	(via
		(at 111.76 -66.04)
		(size 0.508)
		(drill 0.254)
		(layers "F.Cu" "B.Cu")
		(net "GND")
	)
	(via
		(at 127 -375.92)
		(size 0.508)
		(drill 0.254)
		(layers "F.Cu" "B.Cu")
		(net "GND")
	)
	(via
		(at 254 -218.44)
		(size 0.508)
		(drill 0.254)
		(layers "F.Cu" "B.Cu")
		(net "GND")
	)
	(via
		(at 213.36 -421.64)
		(size 0.508)
		(drill 0.254)
		(layers "F.Cu" "B.Cu")
		(net "GND")
	)
	(via
		(at 248.92 -284.48)
		(size 0.508)
		(drill 0.254)
		(layers "F.Cu" "B.Cu")
		(net "GND")
	)
	(via
		(at 6.223 -294.274748)
		(size 0.508)
		(drill 0.254)
		(layers "F.Cu" "B.Cu")
		(net "GND")
	)
	(via
		(at 152.4 -213.36)
		(size 0.508)
		(drill 0.254)
		(layers "F.Cu" "B.Cu")
		(net "GND")
	)
	(via
		(at 262.103108 -11.078464)
		(size 0.508)
		(drill 0.254)
		(layers "F.Cu" "B.Cu")
		(net "GND")
	)
	(via
		(at 222.616014 -169.589958)
		(size 0.508)
		(drill 0.254)
		(layers "F.Cu" "B.Cu")
		(net "GND")
	)
	(via
		(at 86.36 -375.92)
		(size 0.508)
		(drill 0.254)
		(layers "F.Cu" "B.Cu")
		(net "GND")
	)
	(via
		(at 157.48 -421.64)
		(size 0.508)
		(drill 0.254)
		(layers "F.Cu" "B.Cu")
		(net "GND")
	)
	(via
		(at 60.96 -50.8)
		(size 0.508)
		(drill 0.254)
		(layers "F.Cu" "B.Cu")
		(net "GND")
	)
	(via
		(at 94.0308 -314.8838)
		(size 0.508)
		(drill 0.254)
		(layers "F.Cu" "B.Cu")
		(net "GND")
	)
	(via
		(at 132.08 -152.4)
		(size 0.508)
		(drill 0.254)
		(layers "F.Cu" "B.Cu")
		(net "GND")
	)
	(via
		(at 177.8 -20.32)
		(size 0.508)
		(drill 0.254)
		(layers "F.Cu" "B.Cu")
		(net "GND")
	)
	(via
		(at 31.369 -285.369)
		(size 0.508)
		(drill 0.254)
		(layers "F.Cu" "B.Cu")
		(net "GND")
	)
	(via
		(at 91.186 -307.975)
		(size 0.508)
		(drill 0.254)
		(layers "F.Cu" "B.Cu")
		(net "GND")
	)
	(via
		(at 37.61613 -490.590078)
		(size 0.508)
		(drill 0.254)
		(layers "F.Cu" "B.Cu")
		(net "GND")
	)
	(via
		(at 30.48 -116.84)
		(size 0.508)
		(drill 0.254)
		(layers "F.Cu" "B.Cu")
		(net "GND")
	)
	(via
		(at 193.04 -101.6)
		(size 0.508)
		(drill 0.254)
		(layers "F.Cu" "B.Cu")
		(net "GND")
	)
	(via
		(at 152.4 -299.72)
		(size 0.508)
		(drill 0.254)
		(layers "F.Cu" "B.Cu")
		(net "GND")
	)
	(via
		(at 96.52 -162.56)
		(size 0.508)
		(drill 0.254)
		(layers "F.Cu" "B.Cu")
		(net "GND")
	)
	(via
		(at 132.08 -386.08)
		(size 0.508)
		(drill 0.254)
		(layers "F.Cu" "B.Cu")
		(net "GND")
	)
	(via
		(at 198.12 -340.36)
		(size 0.508)
		(drill 0.254)
		(layers "F.Cu" "B.Cu")
		(net "GND")
	)
	(via
		(at 55.88 -289.56)
		(size 0.508)
		(drill 0.254)
		(layers "F.Cu" "B.Cu")
		(net "GND")
	)
	(via
		(at 152.4 -477.52)
		(size 0.508)
		(drill 0.254)
		(layers "F.Cu" "B.Cu")
		(net "GND")
	)
	(via
		(at 5.08 -15.24)
		(size 0.508)
		(drill 0.254)
		(layers "F.Cu" "B.Cu")
		(net "GND")
	)
	(via
		(at 248.92 -238.76)
		(size 0.508)
		(drill 0.254)
		(layers "F.Cu" "B.Cu")
		(net "GND")
	)
	(via
		(at 207.264 -47.498)
		(size 0.508)
		(drill 0.254)
		(layers "F.Cu" "B.Cu")
		(net "GND")
	)
	(via
		(at 6.223 -184.27319)
		(size 0.508)
		(drill 0.254)
		(layers "F.Cu" "B.Cu")
		(net "GND")
	)
	(via
		(at 147.32 -482.6)
		(size 0.508)
		(drill 0.254)
		(layers "F.Cu" "B.Cu")
		(net "GND")
	)
	(via
		(at 71.12 -259.08)
		(size 0.508)
		(drill 0.254)
		(layers "F.Cu" "B.Cu")
		(net "GND")
	)
	(via
		(at 106.68 -55.88)
		(size 0.508)
		(drill 0.254)
		(layers "F.Cu" "B.Cu")
		(net "GND")
	)
	(via
		(at 71.12 -497.84)
		(size 0.508)
		(drill 0.254)
		(layers "F.Cu" "B.Cu")
		(net "GND")
	)
	(via
		(at 208.28 -182.88)
		(size 0.508)
		(drill 0.254)
		(layers "F.Cu" "B.Cu")
		(net "GND")
	)
	(via
		(at 193.04 -127)
		(size 0.508)
		(drill 0.254)
		(layers "F.Cu" "B.Cu")
		(net "GND")
	)
	(via
		(at 90.932 -201.676)
		(size 0.508)
		(drill 0.254)
		(layers "F.Cu" "B.Cu")
		(net "GND")
	)
	(via
		(at 247.65 -400.05)
		(size 0.7112)
		(drill 0.4064)
		(layers "F.Cu" "B.Cu")
		(net "GND")
	)
	(via
		(at 228.6 -127)
		(size 0.508)
		(drill 0.254)
		(layers "F.Cu" "B.Cu")
		(net "GND")
	)
	(via
		(at 75.819 -172.7708)
		(size 0.508)
		(drill 0.254)
		(layers "F.Cu" "B.Cu")
		(net "GND")
	)
	(via
		(at 162.56 -198.12)
		(size 0.508)
		(drill 0.254)
		(layers "F.Cu" "B.Cu")
		(net "GND")
	)
	(via
		(at 81.28 -325.12)
		(size 0.508)
		(drill 0.254)
		(layers "F.Cu" "B.Cu")
		(net "GND")
	)
	(via
		(at 96.323912 -222.066358)
		(size 0.508)
		(drill 0.254)
		(layers "F.Cu" "B.Cu")
		(net "GND")
	)
	(via
		(at 217.043 -291.7698)
		(size 0.508)
		(drill 0.254)
		(layers "F.Cu" "B.Cu")
		(net "GND")
	)
	(via
		(at 71.12 -121.92)
		(size 0.508)
		(drill 0.254)
		(layers "F.Cu" "B.Cu")
		(net "GND")
	)
	(via
		(at 137.16 -294.64)
		(size 0.508)
		(drill 0.254)
		(layers "F.Cu" "B.Cu")
		(net "GND")
	)
	(via
		(at 198.12 -50.8)
		(size 0.508)
		(drill 0.254)
		(layers "F.Cu" "B.Cu")
		(net "GND")
	)
	(via
		(at 114.3 -458.089)
		(size 0.508)
		(drill 0.254)
		(layers "F.Cu" "B.Cu")
		(net "GND")
	)
	(via
		(at 121.92 -243.84)
		(size 0.508)
		(drill 0.254)
		(layers "F.Cu" "B.Cu")
		(net "GND")
	)
	(via
		(at 162.56 -101.6)
		(size 0.508)
		(drill 0.254)
		(layers "F.Cu" "B.Cu")
		(net "GND")
	)
	(via
		(at 222.616014 -483.390194)
		(size 0.508)
		(drill 0.254)
		(layers "F.Cu" "B.Cu")
		(net "GND")
	)
	(via
		(at 245.11 -387.35)
		(size 0.7112)
		(drill 0.4064)
		(layers "F.Cu" "B.Cu")
		(net "GND")
	)
	(via
		(at 219.274898 -480.4791)
		(size 0.508)
		(drill 0.254)
		(layers "F.Cu" "B.Cu")
		(net "GND")
	)
	(via
		(at 152.4 -30.48)
		(size 0.508)
		(drill 0.254)
		(layers "F.Cu" "B.Cu")
		(net "GND")
	)
	(via
		(at 76.2 -467.36)
		(size 0.508)
		(drill 0.254)
		(layers "F.Cu" "B.Cu")
		(net "GND")
	)
	(via
		(at 35.56 -116.84)
		(size 0.508)
		(drill 0.254)
		(layers "F.Cu" "B.Cu")
		(net "GND")
	)
	(via
		(at 208.28 -5.08)
		(size 0.508)
		(drill 0.254)
		(layers "F.Cu" "B.Cu")
		(net "GND")
	)
	(via
		(at 243.84 -335.28)
		(size 0.508)
		(drill 0.254)
		(layers "F.Cu" "B.Cu")
		(net "GND")
	)
	(via
		(at 203.2 -162.56)
		(size 0.508)
		(drill 0.254)
		(layers "F.Cu" "B.Cu")
		(net "GND")
	)
	(via
		(at 243.84 -248.92)
		(size 0.508)
		(drill 0.254)
		(layers "F.Cu" "B.Cu")
		(net "GND")
	)
	(via
		(at 192.9638 -461.645)
		(size 0.508)
		(drill 0.254)
		(layers "F.Cu" "B.Cu")
		(net "GND")
	)
	(via
		(at 172.72 -294.64)
		(size 0.508)
		(drill 0.254)
		(layers "F.Cu" "B.Cu")
		(net "GND")
	)
	(via
		(at 238.76 -457.2)
		(size 0.508)
		(drill 0.254)
		(layers "F.Cu" "B.Cu")
		(net "GND")
	)
	(via
		(at 182.88 -457.2)
		(size 0.508)
		(drill 0.254)
		(layers "F.Cu" "B.Cu")
		(net "GND")
	)
	(via
		(at 66.04 -360.68)
		(size 0.508)
		(drill 0.254)
		(layers "F.Cu" "B.Cu")
		(net "GND")
	)
	(via
		(at 91.44 -279.4)
		(size 0.508)
		(drill 0.254)
		(layers "F.Cu" "B.Cu")
		(net "GND")
	)
	(via
		(at 228.585014 -467.60511)
		(size 0.508)
		(drill 0.254)
		(layers "F.Cu" "B.Cu")
		(net "GND")
	)
	(via
		(at 4.191 -450.723)
		(size 0.508)
		(drill 0.254)
		(layers "F.Cu" "B.Cu")
		(net "GND")
	)
	(via
		(at 198.12 -198.12)
		(size 0.508)
		(drill 0.254)
		(layers "F.Cu" "B.Cu")
		(net "GND")
	)
	(via
		(at 55.88 -421.64)
		(size 0.508)
		(drill 0.254)
		(layers "F.Cu" "B.Cu")
		(net "GND")
	)
	(via
		(at 92.583 -431.8)
		(size 0.508)
		(drill 0.254)
		(layers "F.Cu" "B.Cu")
		(net "GND")
	)
	(via
		(at 106.68 -157.48)
		(size 0.508)
		(drill 0.254)
		(layers "F.Cu" "B.Cu")
		(net "GND")
	)
	(via
		(at 85.725 -103.1875)
		(size 0.508)
		(drill 0.254)
		(layers "F.Cu" "B.Cu")
		(net "GND")
	)
	(via
		(at 193.04 -147.32)
		(size 0.508)
		(drill 0.254)
		(layers "F.Cu" "B.Cu")
		(net "GND")
	)
	(via
		(at 167.64 -457.2)
		(size 0.508)
		(drill 0.254)
		(layers "F.Cu" "B.Cu")
		(net "GND")
	)
	(via
		(at 177.8 -381)
		(size 0.508)
		(drill 0.254)
		(layers "F.Cu" "B.Cu")
		(net "GND")
	)
	(via
		(at 193.04 -132.08)
		(size 0.508)
		(drill 0.254)
		(layers "F.Cu" "B.Cu")
		(net "GND")
	)
	(via
		(at 17.992852 -351.57791)
		(size 0.508)
		(drill 0.254)
		(layers "F.Cu" "B.Cu")
		(net "GND")
	)
	(via
		(at 66.04 -10.16)
		(size 0.508)
		(drill 0.254)
		(layers "F.Cu" "B.Cu")
		(net "GND")
	)
	(via
		(at 137.16 -467.36)
		(size 0.508)
		(drill 0.254)
		(layers "F.Cu" "B.Cu")
		(net "GND")
	)
	(via
		(at 222.616014 -488.190032)
		(size 0.508)
		(drill 0.254)
		(layers "F.Cu" "B.Cu")
		(net "GND")
	)
	(via
		(at 238.76 -299.72)
		(size 0.508)
		(drill 0.254)
		(layers "F.Cu" "B.Cu")
		(net "GND")
	)
	(via
		(at 24.384 -140.809726)
		(size 0.508)
		(drill 0.254)
		(layers "F.Cu" "B.Cu")
		(net "GND")
	)
	(via
		(at 177.8 -350.52)
		(size 0.508)
		(drill 0.254)
		(layers "F.Cu" "B.Cu")
		(net "GND")
	)
	(via
		(at 137.16 -5.08)
		(size 0.508)
		(drill 0.254)
		(layers "F.Cu" "B.Cu")
		(net "GND")
	)
	(via
		(at 6.223 -321.474592)
		(size 0.508)
		(drill 0.254)
		(layers "F.Cu" "B.Cu")
		(net "GND")
	)
	(via
		(at 142.24 -137.16)
		(size 0.508)
		(drill 0.254)
		(layers "F.Cu" "B.Cu")
		(net "GND")
	)
	(via
		(at 237.49 -400.05)
		(size 0.7112)
		(drill 0.4064)
		(layers "F.Cu" "B.Cu")
		(net "GND")
	)
	(via
		(at 92.583 -104.394)
		(size 0.508)
		(drill 0.254)
		(layers "F.Cu" "B.Cu")
		(net "GND")
	)
	(via
		(at 243.84 -274.32)
		(size 0.508)
		(drill 0.254)
		(layers "F.Cu" "B.Cu")
		(net "GND")
	)
	(via
		(at 187.96 -203.2)
		(size 0.508)
		(drill 0.254)
		(layers "F.Cu" "B.Cu")
		(net "GND")
	)
	(via
		(at 182.88 -15.24)
		(size 0.508)
		(drill 0.254)
		(layers "F.Cu" "B.Cu")
		(net "GND")
	)
	(via
		(at 254 -127)
		(size 0.508)
		(drill 0.254)
		(layers "F.Cu" "B.Cu")
		(net "GND")
	)
	(via
		(at 147.32 -162.56)
		(size 0.508)
		(drill 0.254)
		(layers "F.Cu" "B.Cu")
		(net "GND")
	)
	(via
		(at 218.44 -421.64)
		(size 0.508)
		(drill 0.254)
		(layers "F.Cu" "B.Cu")
		(net "GND")
	)
	(via
		(at 248.92 -25.4)
		(size 0.508)
		(drill 0.254)
		(layers "F.Cu" "B.Cu")
		(net "GND")
	)
	(via
		(at 1.397 -51.049428)
		(size 0.508)
		(drill 0.254)
		(layers "F.Cu" "B.Cu")
		(net "GND")
	)
	(via
		(at 177.8 -35.56)
		(size 0.508)
		(drill 0.254)
		(layers "F.Cu" "B.Cu")
		(net "GND")
	)
	(via
		(at 218.44 -66.04)
		(size 0.508)
		(drill 0.254)
		(layers "F.Cu" "B.Cu")
		(net "GND")
	)
	(via
		(at 243.84 -40.64)
		(size 0.508)
		(drill 0.254)
		(layers "F.Cu" "B.Cu")
		(net "GND")
	)
	(via
		(at 147.32 -284.48)
		(size 0.508)
		(drill 0.254)
		(layers "F.Cu" "B.Cu")
		(net "GND")
	)
	(via
		(at 259.08 -264.16)
		(size 0.508)
		(drill 0.254)
		(layers "F.Cu" "B.Cu")
		(net "GND")
	)
	(via
		(at 243.84 -264.16)
		(size 0.508)
		(drill 0.254)
		(layers "F.Cu" "B.Cu")
		(net "GND")
	)
	(via
		(at 93.98 -100.203)
		(size 0.508)
		(drill 0.254)
		(layers "F.Cu" "B.Cu")
		(net "GND")
	)
	(via
		(at 86.36 -457.2)
		(size 0.508)
		(drill 0.254)
		(layers "F.Cu" "B.Cu")
		(net "GND")
	)
	(via
		(at 48.603662 -450.32676)
		(size 0.508)
		(drill 0.254)
		(layers "F.Cu" "B.Cu")
		(net "GND")
	)
	(via
		(at 224.9805 -432.181)
		(size 0.508)
		(drill 0.254)
		(layers "F.Cu" "B.Cu")
		(net "GND")
	)
	(via
		(at 247.65 -397.51)
		(size 0.7112)
		(drill 0.4064)
		(layers "F.Cu" "B.Cu")
		(net "GND")
	)
	(via
		(at 187.96 -472.44)
		(size 0.508)
		(drill 0.254)
		(layers "F.Cu" "B.Cu")
		(net "GND")
	)
	(via
		(at 86.36 -274.32)
		(size 0.508)
		(drill 0.254)
		(layers "F.Cu" "B.Cu")
		(net "GND")
	)
	(via
		(at 254 -431.8)
		(size 0.508)
		(drill 0.254)
		(layers "F.Cu" "B.Cu")
		(net "GND")
	)
	(via
		(at 86.36 -462.28)
		(size 0.508)
		(drill 0.254)
		(layers "F.Cu" "B.Cu")
		(net "GND")
	)
	(via
		(at 198.12 -467.36)
		(size 0.508)
		(drill 0.254)
		(layers "F.Cu" "B.Cu")
		(net "GND")
	)
	(via
		(at 254 -10.16)
		(size 0.508)
		(drill 0.254)
		(layers "F.Cu" "B.Cu")
		(net "GND")
	)
	(via
		(at 248.924572 -482.055424)
		(size 0.508)
		(drill 0.254)
		(layers "F.Cu" "B.Cu")
		(net "GND")
	)
	(via
		(at 111.76 -477.52)
		(size 0.508)
		(drill 0.254)
		(layers "F.Cu" "B.Cu")
		(net "GND")
	)
	(via
		(at 233.68 -81.28)
		(size 0.508)
		(drill 0.254)
		(layers "F.Cu" "B.Cu")
		(net "GND")
	)
	(via
		(at 137.16 -335.28)
		(size 0.508)
		(drill 0.254)
		(layers "F.Cu" "B.Cu")
		(net "GND")
	)
	(via
		(at 162.56 -238.76)
		(size 0.508)
		(drill 0.254)
		(layers "F.Cu" "B.Cu")
		(net "GND")
	)
	(via
		(at 76.2 -35.56)
		(size 0.508)
		(drill 0.254)
		(layers "F.Cu" "B.Cu")
		(net "GND")
	)
	(via
		(at 147.32 -497.84)
		(size 0.508)
		(drill 0.254)
		(layers "F.Cu" "B.Cu")
		(net "GND")
	)
	(via
		(at 203.2 -248.92)
		(size 0.508)
		(drill 0.254)
		(layers "F.Cu" "B.Cu")
		(net "GND")
	)
	(via
		(at 37.61613 -367.59007)
		(size 0.508)
		(drill 0.254)
		(layers "F.Cu" "B.Cu")
		(net "GND")
	)
	(via
		(at 142.24 -421.64)
		(size 0.508)
		(drill 0.254)
		(layers "F.Cu" "B.Cu")
		(net "GND")
	)
	(via
		(at 238.76 -467.36)
		(size 0.508)
		(drill 0.254)
		(layers "F.Cu" "B.Cu")
		(net "GND")
	)
	(via
		(at 81.28 -294.894)
		(size 0.508)
		(drill 0.254)
		(layers "F.Cu" "B.Cu")
		(net "GND")
	)
	(via
		(at 8.5598 -497.9162)
		(size 0.508)
		(drill 0.254)
		(layers "F.Cu" "B.Cu")
		(net "GND")
	)
	(via
		(at 147.32 -447.04)
		(size 0.508)
		(drill 0.254)
		(layers "F.Cu" "B.Cu")
		(net "GND")
	)
	(via
		(at 50.8 -497.84)
		(size 0.508)
		(drill 0.254)
		(layers "F.Cu" "B.Cu")
		(net "GND")
	)
	(via
		(at 66.04 -142.24)
		(size 0.508)
		(drill 0.254)
		(layers "F.Cu" "B.Cu")
		(net "GND")
	)
	(via
		(at 233.68 -121.92)
		(size 0.508)
		(drill 0.254)
		(layers "F.Cu" "B.Cu")
		(net "GND")
	)
	(via
		(at 96.774 -104.394)
		(size 0.508)
		(drill 0.254)
		(layers "F.Cu" "B.Cu")
		(net "GND")
	)
	(via
		(at 37.61613 -373.990108)
		(size 0.508)
		(drill 0.254)
		(layers "F.Cu" "B.Cu")
		(net "GND")
	)
	(via
		(at 177.8 -71.12)
		(size 0.508)
		(drill 0.254)
		(layers "F.Cu" "B.Cu")
		(net "GND")
	)
	(via
		(at 240.03 -389.89)
		(size 0.7112)
		(drill 0.4064)
		(layers "F.Cu" "B.Cu")
		(net "GND")
	)
	(via
		(at 162.56 -111.76)
		(size 0.508)
		(drill 0.254)
		(layers "F.Cu" "B.Cu")
		(net "GND")
	)
	(via
		(at 25.3746 -147.9296)
		(size 0.508)
		(drill 0.254)
		(layers "F.Cu" "B.Cu")
		(net "GND")
	)
	(via
		(at 223.52 -213.36)
		(size 0.508)
		(drill 0.254)
		(layers "F.Cu" "B.Cu")
		(net "GND")
	)
	(via
		(at 162.56 -477.52)
		(size 0.508)
		(drill 0.254)
		(layers "F.Cu" "B.Cu")
		(net "GND")
	)
	(via
		(at 177.8 -477.52)
		(size 0.508)
		(drill 0.254)
		(layers "F.Cu" "B.Cu")
		(net "GND")
	)
	(via
		(at 121.92 -487.68)
		(size 0.508)
		(drill 0.254)
		(layers "F.Cu" "B.Cu")
		(net "GND")
	)
	(via
		(at 18.415 -433.885086)
		(size 0.508)
		(drill 0.254)
		(layers "F.Cu" "B.Cu")
		(net "GND")
	)
	(via
		(at 167.64 -142.24)
		(size 0.508)
		(drill 0.254)
		(layers "F.Cu" "B.Cu")
		(net "GND")
	)
	(via
		(at 193.04 -294.64)
		(size 0.508)
		(drill 0.254)
		(layers "F.Cu" "B.Cu")
		(net "GND")
	)
	(via
		(at 182.88 -40.64)
		(size 0.508)
		(drill 0.254)
		(layers "F.Cu" "B.Cu")
		(net "GND")
	)
	(via
		(at 31.75 -446.489836)
		(size 0.508)
		(drill 0.254)
		(layers "F.Cu" "B.Cu")
		(net "GND")
	)
	(via
		(at 116.84 -330.2)
		(size 0.508)
		(drill 0.254)
		(layers "F.Cu" "B.Cu")
		(net "GND")
	)
	(via
		(at 45.72 -121.92)
		(size 0.508)
		(drill 0.254)
		(layers "F.Cu" "B.Cu")
		(net "GND")
	)
	(via
		(at 152.4 -294.64)
		(size 0.508)
		(drill 0.254)
		(layers "F.Cu" "B.Cu")
		(net "GND")
	)
	(via
		(at 238.76 -335.28)
		(size 0.508)
		(drill 0.254)
		(layers "F.Cu" "B.Cu")
		(net "GND")
	)
	(via
		(at 262.103108 -438.396126)
		(size 0.508)
		(drill 0.254)
		(layers "F.Cu" "B.Cu")
		(net "GND")
	)
	(via
		(at 142.24 -238.76)
		(size 0.508)
		(drill 0.254)
		(layers "F.Cu" "B.Cu")
		(net "GND")
	)
	(via
		(at 4.191 -281.490166)
		(size 0.508)
		(drill 0.254)
		(layers "F.Cu" "B.Cu")
		(net "GND")
	)
	(via
		(at 193.04 -228.6)
		(size 0.508)
		(drill 0.254)
		(layers "F.Cu" "B.Cu")
		(net "GND")
	)
	(via
		(at 24.384 -432.21021)
		(size 0.508)
		(drill 0.254)
		(layers "F.Cu" "B.Cu")
		(net "GND")
	)
	(via
		(at 152.4 -198.12)
		(size 0.508)
		(drill 0.254)
		(layers "F.Cu" "B.Cu")
		(net "GND")
	)
	(via
		(at 116.84 -320.04)
		(size 0.508)
		(drill 0.254)
		(layers "F.Cu" "B.Cu")
		(net "GND")
	)
	(via
		(at 221.71025 -238.99495)
		(size 0.508)
		(drill 0.254)
		(layers "F.Cu" "B.Cu")
		(net "GND")
	)
	(via
		(at 66.04 -91.44)
		(size 0.508)
		(drill 0.254)
		(layers "F.Cu" "B.Cu")
		(net "GND")
	)
	(via
		(at 160.024572 -1.397)
		(size 0.508)
		(drill 0.254)
		(layers "F.Cu" "B.Cu")
		(net "GND")
	)
	(via
		(at 96.52 -467.36)
		(size 0.508)
		(drill 0.254)
		(layers "F.Cu" "B.Cu")
		(net "GND")
	)
	(via
		(at 262.103108 -61.878464)
		(size 0.508)
		(drill 0.254)
		(layers "F.Cu" "B.Cu")
		(net "GND")
	)
	(via
		(at 218.313 -290.6014)
		(size 0.508)
		(drill 0.254)
		(layers "F.Cu" "B.Cu")
		(net "GND")
	)
	(via
		(at 84.455 -149.606)
		(size 0.508)
		(drill 0.254)
		(layers "F.Cu" "B.Cu")
		(net "GND")
	)
	(via
		(at 65.163446 -482.184964)
		(size 0.508)
		(drill 0.254)
		(layers "F.Cu" "B.Cu")
		(net "GND")
	)
	(via
		(at 74.309986 -504.603004)
		(size 0.508)
		(drill 0.254)
		(layers "F.Cu" "B.Cu")
		(net "GND")
	)
	(via
		(at 203.2 -213.36)
		(size 0.508)
		(drill 0.254)
		(layers "F.Cu" "B.Cu")
		(net "GND")
	)
	(via
		(at 26.543 -412.115)
		(size 0.508)
		(drill 0.254)
		(layers "F.Cu" "B.Cu")
		(net "GND")
	)
	(via
		(at 6.223 -160.462214)
		(size 0.508)
		(drill 0.254)
		(layers "F.Cu" "B.Cu")
		(net "GND")
	)
	(via
		(at 248.92 -335.28)
		(size 0.508)
		(drill 0.254)
		(layers "F.Cu" "B.Cu")
		(net "GND")
	)
	(via
		(at 208.28 -142.24)
		(size 0.508)
		(drill 0.254)
		(layers "F.Cu" "B.Cu")
		(net "GND")
	)
	(via
		(at 247.65 -405.13)
		(size 0.7112)
		(drill 0.4064)
		(layers "F.Cu" "B.Cu")
		(net "GND")
	)
	(via
		(at 101.6 -25.4)
		(size 0.508)
		(drill 0.254)
		(layers "F.Cu" "B.Cu")
		(net "GND")
	)
	(via
		(at 216.0524 -299.98035)
		(size 0.508)
		(drill 0.254)
		(layers "F.Cu" "B.Cu")
		(net "GND")
	)
	(via
		(at 60.96 -381)
		(size 0.508)
		(drill 0.254)
		(layers "F.Cu" "B.Cu")
		(net "GND")
	)
	(via
		(at 262.103108 -5.998464)
		(size 0.508)
		(drill 0.254)
		(layers "F.Cu" "B.Cu")
		(net "GND")
	)
	(via
		(at 254 -132.08)
		(size 0.508)
		(drill 0.254)
		(layers "F.Cu" "B.Cu")
		(net "GND")
	)
	(via
		(at 127 -137.16)
		(size 0.508)
		(drill 0.254)
		(layers "F.Cu" "B.Cu")
		(net "GND")
	)
	(via
		(at 147.32 -487.68)
		(size 0.508)
		(drill 0.254)
		(layers "F.Cu" "B.Cu")
		(net "GND")
	)
	(via
		(at 4.191 -202.766168)
		(size 0.508)
		(drill 0.254)
		(layers "F.Cu" "B.Cu")
		(net "GND")
	)
	(via
		(at 252.095 -415.544)
		(size 0.508)
		(drill 0.254)
		(layers "F.Cu" "B.Cu")
		(net "GND")
	)
	(via
		(at 111.76 -35.56)
		(size 0.508)
		(drill 0.254)
		(layers "F.Cu" "B.Cu")
		(net "GND")
	)
	(via
		(at 259.08 -259.08)
		(size 0.508)
		(drill 0.254)
		(layers "F.Cu" "B.Cu")
		(net "GND")
	)
	(via
		(at 208.28 -10.16)
		(size 0.508)
		(drill 0.254)
		(layers "F.Cu" "B.Cu")
		(net "GND")
	)
	(via
		(at 116.84 -467.36)
		(size 0.508)
		(drill 0.254)
		(layers "F.Cu" "B.Cu")
		(net "GND")
	)
	(via
		(at 221.8436 -187.5536)
		(size 0.508)
		(drill 0.254)
		(layers "F.Cu" "B.Cu")
		(net "GND")
	)
	(via
		(at 101.6 -15.24)
		(size 0.508)
		(drill 0.254)
		(layers "F.Cu" "B.Cu")
		(net "GND")
	)
	(via
		(at 116.84 -15.24)
		(size 0.508)
		(drill 0.254)
		(layers "F.Cu" "B.Cu")
		(net "GND")
	)
	(via
		(at 43.58513 -381.115062)
		(size 0.508)
		(drill 0.254)
		(layers "F.Cu" "B.Cu")
		(net "GND")
	)
	(via
		(at 37.61613 -167.990012)
		(size 0.508)
		(drill 0.254)
		(layers "F.Cu" "B.Cu")
		(net "GND")
	)
	(via
		(at 132.08 -436.88)
		(size 0.508)
		(drill 0.254)
		(layers "F.Cu" "B.Cu")
		(net "GND")
	)
	(via
		(at 6.223 -409.994354)
		(size 0.508)
		(drill 0.254)
		(layers "F.Cu" "B.Cu")
		(net "GND")
	)
	(via
		(at 1.397 -40.889428)
		(size 0.508)
		(drill 0.254)
		(layers "F.Cu" "B.Cu")
		(net "GND")
	)
	(via
		(at 167.64 -116.84)
		(size 0.508)
		(drill 0.254)
		(layers "F.Cu" "B.Cu")
		(net "GND")
	)
	(via
		(at 34.306256 -54.20106)
		(size 0.508)
		(drill 0.254)
		(layers "F.Cu" "B.Cu")
		(net "GND")
	)
	(via
		(at 121.92 -106.68)
		(size 0.508)
		(drill 0.254)
		(layers "F.Cu" "B.Cu")
		(net "GND")
	)
	(via
		(at 94.615 -440.563)
		(size 0.508)
		(drill 0.254)
		(layers "F.Cu" "B.Cu")
		(net "GND")
	)
	(via
		(at 254 -452.12)
		(size 0.508)
		(drill 0.254)
		(layers "F.Cu" "B.Cu")
		(net "GND")
	)
	(via
		(at 142.24 -198.12)
		(size 0.508)
		(drill 0.254)
		(layers "F.Cu" "B.Cu")
		(net "GND")
	)
	(via
		(at 167.64 -431.8)
		(size 0.508)
		(drill 0.254)
		(layers "F.Cu" "B.Cu")
		(net "GND")
	)
	(via
		(at 162.56 -497.84)
		(size 0.508)
		(drill 0.254)
		(layers "F.Cu" "B.Cu")
		(net "GND")
	)
	(via
		(at 259.08 -320.04)
		(size 0.508)
		(drill 0.254)
		(layers "F.Cu" "B.Cu")
		(net "GND")
	)
	(via
		(at 24.384 -427.409864)
		(size 0.508)
		(drill 0.254)
		(layers "F.Cu" "B.Cu")
		(net "GND")
	)
	(via
		(at 238.76 -71.12)
		(size 0.508)
		(drill 0.254)
		(layers "F.Cu" "B.Cu")
		(net "GND")
	)
	(via
		(at 177.8 -294.64)
		(size 0.508)
		(drill 0.254)
		(layers "F.Cu" "B.Cu")
		(net "GND")
	)
	(via
		(at 203.2 -137.16)
		(size 0.508)
		(drill 0.254)
		(layers "F.Cu" "B.Cu")
		(net "GND")
	)
	(via
		(at 45.72 -254)
		(size 0.508)
		(drill 0.254)
		(layers "F.Cu" "B.Cu")
		(net "GND")
	)
	(via
		(at 233.68 -487.68)
		(size 0.508)
		(drill 0.254)
		(layers "F.Cu" "B.Cu")
		(net "GND")
	)
	(via
		(at 106.68 -497.84)
		(size 0.508)
		(drill 0.254)
		(layers "F.Cu" "B.Cu")
		(net "GND")
	)
	(via
		(at 60.96 -238.76)
		(size 0.508)
		(drill 0.254)
		(layers "F.Cu" "B.Cu")
		(net "GND")
	)
	(via
		(at 1.397 -122.169428)
		(size 0.508)
		(drill 0.254)
		(layers "F.Cu" "B.Cu")
		(net "GND")
	)
	(via
		(at 167.64 -355.6)
		(size 0.508)
		(drill 0.254)
		(layers "F.Cu" "B.Cu")
		(net "GND")
	)
	(via
		(at 111.76 -71.12)
		(size 0.508)
		(drill 0.254)
		(layers "F.Cu" "B.Cu")
		(net "GND")
	)
	(via
		(at 238.76 -407.67)
		(size 0.7112)
		(drill 0.3556)
		(layers "F.Cu" "B.Cu")
		(net "GND")
	)
	(via
		(at 81.28 -447.04)
		(size 0.508)
		(drill 0.254)
		(layers "F.Cu" "B.Cu")
		(net "GND")
	)
	(via
		(at 91.186 -209.423)
		(size 0.508)
		(drill 0.254)
		(layers "F.Cu" "B.Cu")
		(net "GND")
	)
	(via
		(at 18.415 -446.585086)
		(size 0.508)
		(drill 0.254)
		(layers "F.Cu" "B.Cu")
		(net "GND")
	)
	(via
		(at 177.8 -66.04)
		(size 0.508)
		(drill 0.254)
		(layers "F.Cu" "B.Cu")
		(net "GND")
	)
	(via
		(at 233.426 -165.483794)
		(size 0.508)
		(drill 0.254)
		(layers "F.Cu" "B.Cu")
		(net "GND")
	)
	(via
		(at 71.12 -330.2)
		(size 0.508)
		(drill 0.254)
		(layers "F.Cu" "B.Cu")
		(net "GND")
	)
	(via
		(at 91.44 -177.8)
		(size 0.508)
		(drill 0.254)
		(layers "F.Cu" "B.Cu")
		(net "GND")
	)
	(via
		(at 208.28 -330.2)
		(size 0.508)
		(drill 0.254)
		(layers "F.Cu" "B.Cu")
		(net "GND")
	)
	(via
		(at 216.145364 -93.98635)
		(size 0.508)
		(drill 0.254)
		(layers "F.Cu" "B.Cu")
		(net "GND")
	)
	(via
		(at 10.7188 -472.1987)
		(size 0.508)
		(drill 0.254)
		(layers "F.Cu" "B.Cu")
		(net "GND")
	)
	(via
		(at 101.6 -137.16)
		(size 0.508)
		(drill 0.254)
		(layers "F.Cu" "B.Cu")
		(net "GND")
	)
	(via
		(at 71.12 -91.44)
		(size 0.508)
		(drill 0.254)
		(layers "F.Cu" "B.Cu")
		(net "GND")
	)
	(via
		(at 187.96 -172.72)
		(size 0.508)
		(drill 0.254)
		(layers "F.Cu" "B.Cu")
		(net "GND")
	)
	(via
		(at 101.6 -5.08)
		(size 0.508)
		(drill 0.254)
		(layers "F.Cu" "B.Cu")
		(net "GND")
	)
	(via
		(at 142.24 -218.44)
		(size 0.508)
		(drill 0.254)
		(layers "F.Cu" "B.Cu")
		(net "GND")
	)
	(via
		(at 101.6 -320.04)
		(size 0.508)
		(drill 0.254)
		(layers "F.Cu" "B.Cu")
		(net "GND")
	)
	(via
		(at 101.6 -35.56)
		(size 0.508)
		(drill 0.254)
		(layers "F.Cu" "B.Cu")
		(net "GND")
	)
	(via
		(at 24.384 -29.009848)
		(size 0.508)
		(drill 0.254)
		(layers "F.Cu" "B.Cu")
		(net "GND")
	)
	(via
		(at 259.08 -436.88)
		(size 0.508)
		(drill 0.254)
		(layers "F.Cu" "B.Cu")
		(net "GND")
	)
	(via
		(at 8.636 -335.534)
		(size 0.508)
		(drill 0.254)
		(layers "F.Cu" "B.Cu")
		(net "GND")
	)
	(via
		(at 127 -45.72)
		(size 0.508)
		(drill 0.254)
		(layers "F.Cu" "B.Cu")
		(net "GND")
	)
	(via
		(at 248.92 -116.84)
		(size 0.508)
		(drill 0.254)
		(layers "F.Cu" "B.Cu")
		(net "GND")
	)
	(via
		(at 177.8 -147.32)
		(size 0.508)
		(drill 0.254)
		(layers "F.Cu" "B.Cu")
		(net "GND")
	)
	(via
		(at 147.32 -187.96)
		(size 0.508)
		(drill 0.254)
		(layers "F.Cu" "B.Cu")
		(net "GND")
	)
	(via
		(at 238.76 -132.08)
		(size 0.508)
		(drill 0.254)
		(layers "F.Cu" "B.Cu")
		(net "GND")
	)
	(via
		(at 259.08 -167.64)
		(size 0.508)
		(drill 0.254)
		(layers "F.Cu" "B.Cu")
		(net "GND")
	)
	(via
		(at 96.52 -497.84)
		(size 0.508)
		(drill 0.254)
		(layers "F.Cu" "B.Cu")
		(net "GND")
	)
	(via
		(at 45.72 -147.32)
		(size 0.508)
		(drill 0.254)
		(layers "F.Cu" "B.Cu")
		(net "GND")
	)
	(via
		(at 40.6908 -434.4162)
		(size 0.508)
		(drill 0.254)
		(layers "F.Cu" "B.Cu")
		(net "GND")
	)
	(via
		(at 27.69362 -451.798944)
		(size 0.508)
		(drill 0.254)
		(layers "F.Cu" "B.Cu")
		(net "GND")
	)
	(via
		(at 233.68 -502.92)
		(size 0.508)
		(drill 0.254)
		(layers "F.Cu" "B.Cu")
		(net "GND")
	)
	(via
		(at 121.92 -45.72)
		(size 0.508)
		(drill 0.254)
		(layers "F.Cu" "B.Cu")
		(net "GND")
	)
	(via
		(at 37.61613 -262.189976)
		(size 0.508)
		(drill 0.254)
		(layers "F.Cu" "B.Cu")
		(net "GND")
	)
	(via
		(at 208.28 -15.24)
		(size 0.508)
		(drill 0.254)
		(layers "F.Cu" "B.Cu")
		(net "GND")
	)
	(via
		(at 221.5388 -300.2026)
		(size 0.508)
		(drill 0.254)
		(layers "F.Cu" "B.Cu")
		(net "GND")
	)
	(via
		(at 4.191 -399.542)
		(size 0.508)
		(drill 0.254)
		(layers "F.Cu" "B.Cu")
		(net "GND")
	)
	(via
		(at 60.96 -477.52)
		(size 0.508)
		(drill 0.254)
		(layers "F.Cu" "B.Cu")
		(net "GND")
	)
	(via
		(at 208.28 -314.96)
		(size 0.508)
		(drill 0.254)
		(layers "F.Cu" "B.Cu")
		(net "GND")
	)
	(via
		(at 259.08 -40.64)
		(size 0.508)
		(drill 0.254)
		(layers "F.Cu" "B.Cu")
		(net "GND")
	)
	(via
		(at 43.58513 -276.845014)
		(size 0.508)
		(drill 0.254)
		(layers "F.Cu" "B.Cu")
		(net "GND")
	)
	(via
		(at 4.064 -236.474)
		(size 0.508)
		(drill 0.254)
		(layers "F.Cu" "B.Cu")
		(net "GND")
	)
	(via
		(at 203.2 -152.4)
		(size 0.508)
		(drill 0.254)
		(layers "F.Cu" "B.Cu")
		(net "GND")
	)
	(via
		(at 182.88 -243.84)
		(size 0.508)
		(drill 0.254)
		(layers "F.Cu" "B.Cu")
		(net "GND")
	)
	(via
		(at 27.69616 -324.826884)
		(size 0.508)
		(drill 0.254)
		(layers "F.Cu" "B.Cu")
		(net "GND")
	)
	(via
		(at 233.68 -391.16)
		(size 0.508)
		(drill 0.254)
		(layers "F.Cu" "B.Cu")
		(net "GND")
	)
	(via
		(at 259.08 -25.4)
		(size 0.508)
		(drill 0.254)
		(layers "F.Cu" "B.Cu")
		(net "GND")
	)
	(via
		(at 254 -137.16)
		(size 0.508)
		(drill 0.254)
		(layers "F.Cu" "B.Cu")
		(net "GND")
	)
	(via
		(at 152.4 -421.64)
		(size 0.508)
		(drill 0.254)
		(layers "F.Cu" "B.Cu")
		(net "GND")
	)
	(via
		(at 218.313 -188.4172)
		(size 0.508)
		(drill 0.254)
		(layers "F.Cu" "B.Cu")
		(net "GND")
	)
	(via
		(at 121.92 -330.2)
		(size 0.508)
		(drill 0.254)
		(layers "F.Cu" "B.Cu")
		(net "GND")
	)
	(via
		(at 182.88 -360.68)
		(size 0.508)
		(drill 0.254)
		(layers "F.Cu" "B.Cu")
		(net "GND")
	)
	(via
		(at 217.297 -394.7922)
		(size 0.508)
		(drill 0.254)
		(layers "F.Cu" "B.Cu")
		(net "GND")
	)
	(via
		(at 66.04 -162.56)
		(size 0.508)
		(drill 0.254)
		(layers "F.Cu" "B.Cu")
		(net "GND")
	)
	(via
		(at 157.48 -360.68)
		(size 0.508)
		(drill 0.254)
		(layers "F.Cu" "B.Cu")
		(net "GND")
	)
	(via
		(at 37.2618 -309.7784)
		(size 0.508)
		(drill 0.254)
		(layers "F.Cu" "B.Cu")
		(net "GND")
	)
	(via
		(at 4.191 -307.090064)
		(size 0.508)
		(drill 0.254)
		(layers "F.Cu" "B.Cu")
		(net "GND")
	)
	(via
		(at 167.64 -71.12)
		(size 0.508)
		(drill 0.254)
		(layers "F.Cu" "B.Cu")
		(net "GND")
	)
	(via
		(at 259.08 -269.24)
		(size 0.508)
		(drill 0.254)
		(layers "F.Cu" "B.Cu")
		(net "GND")
	)
	(via
		(at 121.92 -497.84)
		(size 0.508)
		(drill 0.254)
		(layers "F.Cu" "B.Cu")
		(net "GND")
	)
	(via
		(at 116.84 -213.36)
		(size 0.508)
		(drill 0.254)
		(layers "F.Cu" "B.Cu")
		(net "GND")
	)
	(via
		(at 147.32 -345.44)
		(size 0.508)
		(drill 0.254)
		(layers "F.Cu" "B.Cu")
		(net "GND")
	)
	(via
		(at 86.36 -142.24)
		(size 0.508)
		(drill 0.254)
		(layers "F.Cu" "B.Cu")
		(net "GND")
	)
	(via
		(at 203.2 -314.96)
		(size 0.508)
		(drill 0.254)
		(layers "F.Cu" "B.Cu")
		(net "GND")
	)
	(via
		(at 71.12 -116.84)
		(size 0.508)
		(drill 0.254)
		(layers "F.Cu" "B.Cu")
		(net "GND")
	)
	(via
		(at 37.61613 -62.589918)
		(size 0.508)
		(drill 0.254)
		(layers "F.Cu" "B.Cu")
		(net "GND")
	)
	(via
		(at 193.04 -182.88)
		(size 0.508)
		(drill 0.254)
		(layers "F.Cu" "B.Cu")
		(net "GND")
	)
	(via
		(at 198.12 -487.68)
		(size 0.508)
		(drill 0.254)
		(layers "F.Cu" "B.Cu")
		(net "GND")
	)
	(via
		(at 6.223 -289.610038)
		(size 0.508)
		(drill 0.254)
		(layers "F.Cu" "B.Cu")
		(net "GND")
	)
	(via
		(at 238.76 -472.44)
		(size 0.508)
		(drill 0.254)
		(layers "F.Cu" "B.Cu")
		(net "GND")
	)
	(via
		(at 172.72 -375.92)
		(size 0.508)
		(drill 0.254)
		(layers "F.Cu" "B.Cu")
		(net "GND")
	)
	(via
		(at 213.36 -269.24)
		(size 0.508)
		(drill 0.254)
		(layers "F.Cu" "B.Cu")
		(net "GND")
	)
	(via
		(at 203.2 -121.92)
		(size 0.508)
		(drill 0.254)
		(layers "F.Cu" "B.Cu")
		(net "GND")
	)
	(via
		(at 49.657 -138.7475)
		(size 0.508)
		(drill 0.254)
		(layers "F.Cu" "B.Cu")
		(net "GND")
	)
	(via
		(at 111.76 -233.68)
		(size 0.508)
		(drill 0.254)
		(layers "F.Cu" "B.Cu")
		(net "GND")
	)
	(via
		(at 137.16 -71.12)
		(size 0.508)
		(drill 0.254)
		(layers "F.Cu" "B.Cu")
		(net "GND")
	)
	(via
		(at 88.4555 -418.846)
		(size 0.508)
		(drill 0.254)
		(layers "F.Cu" "B.Cu")
		(net "GND")
	)
	(via
		(at 172.72 -137.16)
		(size 0.508)
		(drill 0.254)
		(layers "F.Cu" "B.Cu")
		(net "GND")
	)
	(via
		(at 34.544 -299.8216)
		(size 0.508)
		(drill 0.254)
		(layers "F.Cu" "B.Cu")
		(net "GND")
	)
	(via
		(at 86.36 -254)
		(size 0.508)
		(drill 0.254)
		(layers "F.Cu" "B.Cu")
		(net "GND")
	)
	(via
		(at 238.76 -172.72)
		(size 0.508)
		(drill 0.254)
		(layers "F.Cu" "B.Cu")
		(net "GND")
	)
	(via
		(at 73.152 -442.595)
		(size 0.508)
		(drill 0.254)
		(layers "F.Cu" "B.Cu")
		(net "GND")
	)
	(via
		(at 132.08 -304.8)
		(size 0.508)
		(drill 0.254)
		(layers "F.Cu" "B.Cu")
		(net "GND")
	)
	(via
		(at 243.84 -441.96)
		(size 0.508)
		(drill 0.254)
		(layers "F.Cu" "B.Cu")
		(net "GND")
	)
	(via
		(at 167.64 -320.04)
		(size 0.508)
		(drill 0.254)
		(layers "F.Cu" "B.Cu")
		(net "GND")
	)
	(via
		(at 172.72 -121.92)
		(size 0.508)
		(drill 0.254)
		(layers "F.Cu" "B.Cu")
		(net "GND")
	)
	(via
		(at 167.64 -55.88)
		(size 0.508)
		(drill 0.254)
		(layers "F.Cu" "B.Cu")
		(net "GND")
	)
	(via
		(at 182.88 -50.8)
		(size 0.508)
		(drill 0.254)
		(layers "F.Cu" "B.Cu")
		(net "GND")
	)
	(via
		(at 193.04 -248.92)
		(size 0.508)
		(drill 0.254)
		(layers "F.Cu" "B.Cu")
		(net "GND")
	)
	(via
		(at 262.103108 -204.118464)
		(size 0.508)
		(drill 0.254)
		(layers "F.Cu" "B.Cu")
		(net "GND")
	)
	(via
		(at 111.76 -487.68)
		(size 0.508)
		(drill 0.254)
		(layers "F.Cu" "B.Cu")
		(net "GND")
	)
	(via
		(at 37.61613 -68.989956)
		(size 0.508)
		(drill 0.254)
		(layers "F.Cu" "B.Cu")
		(net "GND")
	)
	(via
		(at 28.575 -215.5698)
		(size 0.508)
		(drill 0.254)
		(layers "F.Cu" "B.Cu")
		(net "GND")
	)
	(via
		(at 77.5208 -306.9082)
		(size 0.508)
		(drill 0.254)
		(layers "F.Cu" "B.Cu")
		(net "GND")
	)
	(via
		(at 177.8 -233.68)
		(size 0.508)
		(drill 0.254)
		(layers "F.Cu" "B.Cu")
		(net "GND")
	)
	(via
		(at 242.57 -405.13)
		(size 0.7112)
		(drill 0.4064)
		(layers "F.Cu" "B.Cu")
		(net "GND")
	)
	(via
		(at 64.941196 -279.26538)
		(size 0.508)
		(drill 0.254)
		(layers "F.Cu" "B.Cu")
		(net "GND")
	)
	(via
		(at 29.7942 -430.911)
		(size 0.508)
		(drill 0.254)
		(layers "F.Cu" "B.Cu")
		(net "GND")
	)
	(via
		(at 132.08 -193.04)
		(size 0.508)
		(drill 0.254)
		(layers "F.Cu" "B.Cu")
		(net "GND")
	)
	(via
		(at 121.92 -325.12)
		(size 0.508)
		(drill 0.254)
		(layers "F.Cu" "B.Cu")
		(net "GND")
	)
	(via
		(at 106.68 -60.96)
		(size 0.508)
		(drill 0.254)
		(layers "F.Cu" "B.Cu")
		(net "GND")
	)
	(via
		(at 218.44 -121.92)
		(size 0.508)
		(drill 0.254)
		(layers "F.Cu" "B.Cu")
		(net "GND")
	)
	(via
		(at 142.24 -482.6)
		(size 0.508)
		(drill 0.254)
		(layers "F.Cu" "B.Cu")
		(net "GND")
	)
	(via
		(at 106.68 -218.44)
		(size 0.508)
		(drill 0.254)
		(layers "F.Cu" "B.Cu")
		(net "GND")
	)
	(via
		(at 6.223 -206.011526)
		(size 0.508)
		(drill 0.254)
		(layers "F.Cu" "B.Cu")
		(net "GND")
	)
	(via
		(at 254 -248.92)
		(size 0.508)
		(drill 0.254)
		(layers "F.Cu" "B.Cu")
		(net "GND")
	)
	(via
		(at 187.96 -284.48)
		(size 0.508)
		(drill 0.254)
		(layers "F.Cu" "B.Cu")
		(net "GND")
	)
	(via
		(at 203.2 -193.04)
		(size 0.508)
		(drill 0.254)
		(layers "F.Cu" "B.Cu")
		(net "GND")
	)
	(via
		(at 50.8 -193.04)
		(size 0.508)
		(drill 0.254)
		(layers "F.Cu" "B.Cu")
		(net "GND")
	)
	(via
		(at 162.56 -381)
		(size 0.508)
		(drill 0.254)
		(layers "F.Cu" "B.Cu")
		(net "GND")
	)
	(via
		(at 187.96 -157.48)
		(size 0.508)
		(drill 0.254)
		(layers "F.Cu" "B.Cu")
		(net "GND")
	)
	(via
		(at 259.08 -10.16)
		(size 0.508)
		(drill 0.254)
		(layers "F.Cu" "B.Cu")
		(net "GND")
	)
	(via
		(at 32.893 -340.492334)
		(size 0.508)
		(drill 0.254)
		(layers "F.Cu" "B.Cu")
		(net "GND")
	)
	(via
		(at 132.08 -208.28)
		(size 0.508)
		(drill 0.254)
		(layers "F.Cu" "B.Cu")
		(net "GND")
	)
	(via
		(at 6.223 -171.523914)
		(size 0.508)
		(drill 0.254)
		(layers "F.Cu" "B.Cu")
		(net "GND")
	)
	(via
		(at 259.08 -482.6)
		(size 0.508)
		(drill 0.254)
		(layers "F.Cu" "B.Cu")
		(net "GND")
	)
	(via
		(at 198.12 -106.68)
		(size 0.508)
		(drill 0.254)
		(layers "F.Cu" "B.Cu")
		(net "GND")
	)
	(via
		(at 37.61613 -365.190024)
		(size 0.508)
		(drill 0.254)
		(layers "F.Cu" "B.Cu")
		(net "GND")
	)
	(via
		(at 6.223 -207.473042)
		(size 0.508)
		(drill 0.254)
		(layers "F.Cu" "B.Cu")
		(net "GND")
	)
	(via
		(at 177.8 -15.24)
		(size 0.508)
		(drill 0.254)
		(layers "F.Cu" "B.Cu")
		(net "GND")
	)
	(via
		(at 45.72 -330.2)
		(size 0.508)
		(drill 0.254)
		(layers "F.Cu" "B.Cu")
		(net "GND")
	)
	(via
		(at 17.145 -343.500964)
		(size 0.508)
		(drill 0.254)
		(layers "F.Cu" "B.Cu")
		(net "GND")
	)
	(via
		(at 18.415 -229.15499)
		(size 0.508)
		(drill 0.254)
		(layers "F.Cu" "B.Cu")
		(net "GND")
	)
	(via
		(at 28.194 -477.41078)
		(size 0.508)
		(drill 0.254)
		(layers "F.Cu" "B.Cu")
		(net "GND")
	)
	(via
		(at 233.68 -340.36)
		(size 0.508)
		(drill 0.254)
		(layers "F.Cu" "B.Cu")
		(net "GND")
	)
	(via
		(at 116.84 -40.64)
		(size 0.508)
		(drill 0.254)
		(layers "F.Cu" "B.Cu")
		(net "GND")
	)
	(via
		(at 222.616014 -277.390098)
		(size 0.508)
		(drill 0.254)
		(layers "F.Cu" "B.Cu")
		(net "GND")
	)
	(via
		(at 24.384 -322.010024)
		(size 0.508)
		(drill 0.254)
		(layers "F.Cu" "B.Cu")
		(net "GND")
	)
	(via
		(at 254 -289.56)
		(size 0.508)
		(drill 0.254)
		(layers "F.Cu" "B.Cu")
		(net "GND")
	)
	(via
		(at 218.44 -223.52)
		(size 0.508)
		(drill 0.254)
		(layers "F.Cu" "B.Cu")
		(net "GND")
	)
	(via
		(at 162.56 -330.2)
		(size 0.508)
		(drill 0.254)
		(layers "F.Cu" "B.Cu")
		(net "GND")
	)
	(via
		(at 248.92 -502.92)
		(size 0.508)
		(drill 0.254)
		(layers "F.Cu" "B.Cu")
		(net "GND")
	)
	(via
		(at 182.88 -335.28)
		(size 0.508)
		(drill 0.254)
		(layers "F.Cu" "B.Cu")
		(net "GND")
	)
	(via
		(at 86.36 -482.6)
		(size 0.508)
		(drill 0.254)
		(layers "F.Cu" "B.Cu")
		(net "GND")
	)
	(via
		(at 25.527 -412.115)
		(size 0.508)
		(drill 0.254)
		(layers "F.Cu" "B.Cu")
		(net "GND")
	)
	(via
		(at 24.638 -75.311)
		(size 0.508)
		(drill 0.254)
		(layers "F.Cu" "B.Cu")
		(net "GND")
	)
	(via
		(at 222.616014 -286.990028)
		(size 0.508)
		(drill 0.254)
		(layers "F.Cu" "B.Cu")
		(net "GND")
	)
	(via
		(at 259.08 -355.6)
		(size 0.508)
		(drill 0.254)
		(layers "F.Cu" "B.Cu")
		(net "GND")
	)
	(via
		(at 109.224572 -1.397)
		(size 0.508)
		(drill 0.254)
		(layers "F.Cu" "B.Cu")
		(net "GND")
	)
	(via
		(at 76.2 -15.24)
		(size 0.508)
		(drill 0.254)
		(layers "F.Cu" "B.Cu")
		(net "GND")
	)
	(via
		(at 121.92 -121.92)
		(size 0.508)
		(drill 0.254)
		(layers "F.Cu" "B.Cu")
		(net "GND")
	)
	(via
		(at 8.331454 -386.492242)
		(size 0.508)
		(drill 0.254)
		(layers "F.Cu" "B.Cu")
		(net "GND")
	)
	(via
		(at 152.4 -203.2)
		(size 0.508)
		(drill 0.254)
		(layers "F.Cu" "B.Cu")
		(net "GND")
	)
	(via
		(at 147.32 -233.68)
		(size 0.508)
		(drill 0.254)
		(layers "F.Cu" "B.Cu")
		(net "GND")
	)
	(via
		(at 254 -345.44)
		(size 0.508)
		(drill 0.254)
		(layers "F.Cu" "B.Cu")
		(net "GND")
	)
	(via
		(at 137.16 -441.96)
		(size 0.508)
		(drill 0.254)
		(layers "F.Cu" "B.Cu")
		(net "GND")
	)
	(via
		(at 4.191 -386.341874)
		(size 0.508)
		(drill 0.254)
		(layers "F.Cu" "B.Cu")
		(net "GND")
	)
	(via
		(at 182.88 -147.32)
		(size 0.508)
		(drill 0.254)
		(layers "F.Cu" "B.Cu")
		(net "GND")
	)
	(via
		(at 213.36 -203.2)
		(size 0.508)
		(drill 0.254)
		(layers "F.Cu" "B.Cu")
		(net "GND")
	)
	(via
		(at 30.8864 -13.8938)
		(size 0.508)
		(drill 0.254)
		(layers "F.Cu" "B.Cu")
		(net "GND")
	)
	(via
		(at 222.616014 -373.990108)
		(size 0.508)
		(drill 0.254)
		(layers "F.Cu" "B.Cu")
		(net "GND")
	)
	(via
		(at 254 -284.48)
		(size 0.508)
		(drill 0.254)
		(layers "F.Cu" "B.Cu")
		(net "GND")
	)
	(via
		(at 6.223 -312.010044)
		(size 0.508)
		(drill 0.254)
		(layers "F.Cu" "B.Cu")
		(net "GND")
	)
	(via
		(at 162.56 -182.88)
		(size 0.508)
		(drill 0.254)
		(layers "F.Cu" "B.Cu")
		(net "GND")
	)
	(via
		(at 4.191 -318.290194)
		(size 0.508)
		(drill 0.254)
		(layers "F.Cu" "B.Cu")
		(net "GND")
	)
	(via
		(at 223.52 -10.16)
		(size 0.508)
		(drill 0.254)
		(layers "F.Cu" "B.Cu")
		(net "GND")
	)
	(via
		(at 162.56 -248.92)
		(size 0.508)
		(drill 0.254)
		(layers "F.Cu" "B.Cu")
		(net "GND")
	)
	(via
		(at 76.2 -111.76)
		(size 0.508)
		(drill 0.254)
		(layers "F.Cu" "B.Cu")
		(net "GND")
	)
	(via
		(at 182.88 -492.76)
		(size 0.508)
		(drill 0.254)
		(layers "F.Cu" "B.Cu")
		(net "GND")
	)
	(via
		(at 71.12 -10.16)
		(size 0.508)
		(drill 0.254)
		(layers "F.Cu" "B.Cu")
		(net "GND")
	)
	(via
		(at 213.2076 -501.269)
		(size 0.508)
		(drill 0.254)
		(layers "F.Cu" "B.Cu")
		(net "GND")
	)
	(via
		(at 4.191 -323.166232)
		(size 0.508)
		(drill 0.254)
		(layers "F.Cu" "B.Cu")
		(net "GND")
	)
	(via
		(at 208.28 -340.36)
		(size 0.508)
		(drill 0.254)
		(layers "F.Cu" "B.Cu")
		(net "GND")
	)
	(via
		(at 5.08 -50.8)
		(size 0.508)
		(drill 0.254)
		(layers "F.Cu" "B.Cu")
		(net "GND")
	)
	(via
		(at 81.661 -104.902)
		(size 0.508)
		(drill 0.254)
		(layers "F.Cu" "B.Cu")
		(net "GND")
	)
	(via
		(at 228.6 -218.44)
		(size 0.508)
		(drill 0.254)
		(layers "F.Cu" "B.Cu")
		(net "GND")
	)
	(via
		(at 6.223 -161.923984)
		(size 0.508)
		(drill 0.254)
		(layers "F.Cu" "B.Cu")
		(net "GND")
	)
	(via
		(at 198.12 -365.76)
		(size 0.508)
		(drill 0.254)
		(layers "F.Cu" "B.Cu")
		(net "GND")
	)
	(via
		(at 86.36 -177.8)
		(size 0.508)
		(drill 0.254)
		(layers "F.Cu" "B.Cu")
		(net "GND")
	)
	(via
		(at 203.2 -132.08)
		(size 0.508)
		(drill 0.254)
		(layers "F.Cu" "B.Cu")
		(net "GND")
	)
	(via
		(at 92.583 -434.594)
		(size 0.508)
		(drill 0.254)
		(layers "F.Cu" "B.Cu")
		(net "GND")
	)
	(via
		(at 162.56 -208.28)
		(size 0.508)
		(drill 0.254)
		(layers "F.Cu" "B.Cu")
		(net "GND")
	)
	(via
		(at 187.96 -71.12)
		(size 0.508)
		(drill 0.254)
		(layers "F.Cu" "B.Cu")
		(net "GND")
	)
	(via
		(at 34.28873 -385.649216)
		(size 0.508)
		(drill 0.254)
		(layers "F.Cu" "B.Cu")
		(net "GND")
	)
	(via
		(at 259.08 -20.32)
		(size 0.508)
		(drill 0.254)
		(layers "F.Cu" "B.Cu")
		(net "GND")
	)
	(via
		(at 248.92 -441.96)
		(size 0.508)
		(drill 0.254)
		(layers "F.Cu" "B.Cu")
		(net "GND")
	)
	(via
		(at 127 -172.72)
		(size 0.508)
		(drill 0.254)
		(layers "F.Cu" "B.Cu")
		(net "GND")
	)
	(via
		(at 219.314014 -483.7811)
		(size 0.508)
		(drill 0.254)
		(layers "F.Cu" "B.Cu")
		(net "GND")
	)
	(via
		(at 4.191 -359.090214)
		(size 0.508)
		(drill 0.254)
		(layers "F.Cu" "B.Cu")
		(net "GND")
	)
	(via
		(at 23.509986 -504.603004)
		(size 0.508)
		(drill 0.254)
		(layers "F.Cu" "B.Cu")
		(net "GND")
	)
	(via
		(at 4.191 -302.366172)
		(size 0.508)
		(drill 0.254)
		(layers "F.Cu" "B.Cu")
		(net "GND")
	)
	(via
		(at 152.4 -167.64)
		(size 0.508)
		(drill 0.254)
		(layers "F.Cu" "B.Cu")
		(net "GND")
	)
	(via
		(at 177.8 -447.04)
		(size 0.508)
		(drill 0.254)
		(layers "F.Cu" "B.Cu")
		(net "GND")
	)
	(via
		(at 132.08 -60.96)
		(size 0.508)
		(drill 0.254)
		(layers "F.Cu" "B.Cu")
		(net "GND")
	)
	(via
		(at 213.36 -213.36)
		(size 0.508)
		(drill 0.254)
		(layers "F.Cu" "B.Cu")
		(net "GND")
	)
	(via
		(at 219.314014 -260.128004)
		(size 0.508)
		(drill 0.254)
		(layers "F.Cu" "B.Cu")
		(net "GND")
	)
	(via
		(at 96.52 -330.2)
		(size 0.508)
		(drill 0.254)
		(layers "F.Cu" "B.Cu")
		(net "GND")
	)
	(via
		(at 262.103108 -102.518464)
		(size 0.508)
		(drill 0.254)
		(layers "F.Cu" "B.Cu")
		(net "GND")
	)
	(via
		(at 4.191 -389.89)
		(size 0.508)
		(drill 0.254)
		(layers "F.Cu" "B.Cu")
		(net "GND")
	)
	(via
		(at 45.72 -279.4)
		(size 0.508)
		(drill 0.254)
		(layers "F.Cu" "B.Cu")
		(net "GND")
	)
	(via
		(at 116.84 -248.92)
		(size 0.508)
		(drill 0.254)
		(layers "F.Cu" "B.Cu")
		(net "GND")
	)
	(via
		(at 24.384 -134.409942)
		(size 0.508)
		(drill 0.254)
		(layers "F.Cu" "B.Cu")
		(net "GND")
	)
	(via
		(at 213.36 -375.92)
		(size 0.508)
		(drill 0.254)
		(layers "F.Cu" "B.Cu")
		(net "GND")
	)
	(via
		(at 152.4 -243.84)
		(size 0.508)
		(drill 0.254)
		(layers "F.Cu" "B.Cu")
		(net "GND")
	)
	(via
		(at 198.12 -177.8)
		(size 0.508)
		(drill 0.254)
		(layers "F.Cu" "B.Cu")
		(net "GND")
	)
	(via
		(at 106.68 -467.36)
		(size 0.508)
		(drill 0.254)
		(layers "F.Cu" "B.Cu")
		(net "GND")
	)
	(via
		(at 127 -248.92)
		(size 0.508)
		(drill 0.254)
		(layers "F.Cu" "B.Cu")
		(net "GND")
	)
	(via
		(at 228.6 -208.28)
		(size 0.508)
		(drill 0.254)
		(layers "F.Cu" "B.Cu")
		(net "GND")
	)
	(via
		(at 254 -5.08)
		(size 0.508)
		(drill 0.254)
		(layers "F.Cu" "B.Cu")
		(net "GND")
	)
	(via
		(at 96.52 -238.76)
		(size 0.508)
		(drill 0.254)
		(layers "F.Cu" "B.Cu")
		(net "GND")
	)
	(via
		(at 37.61613 -387.59003)
		(size 0.508)
		(drill 0.254)
		(layers "F.Cu" "B.Cu")
		(net "GND")
	)
	(via
		(at 18.415 -21.884894)
		(size 0.508)
		(drill 0.254)
		(layers "F.Cu" "B.Cu")
		(net "GND")
	)
	(via
		(at 27.686 -329.601068)
		(size 0.508)
		(drill 0.254)
		(layers "F.Cu" "B.Cu")
		(net "GND")
	)
	(via
		(at 187.96 -248.92)
		(size 0.508)
		(drill 0.254)
		(layers "F.Cu" "B.Cu")
		(net "GND")
	)
	(via
		(at 127 -360.68)
		(size 0.508)
		(drill 0.254)
		(layers "F.Cu" "B.Cu")
		(net "GND")
	)
	(via
		(at 127 -365.76)
		(size 0.508)
		(drill 0.254)
		(layers "F.Cu" "B.Cu")
		(net "GND")
	)
	(via
		(at 172.72 -335.28)
		(size 0.508)
		(drill 0.254)
		(layers "F.Cu" "B.Cu")
		(net "GND")
	)
	(via
		(at 27.733498 -232.918)
		(size 0.508)
		(drill 0.254)
		(layers "F.Cu" "B.Cu")
		(net "GND")
	)
	(via
		(at 97.8535 -199.5678)
		(size 0.508)
		(drill 0.254)
		(layers "F.Cu" "B.Cu")
		(net "GND")
	)
	(via
		(at 66.04 -269.24)
		(size 0.508)
		(drill 0.254)
		(layers "F.Cu" "B.Cu")
		(net "GND")
	)
	(via
		(at 66.04 -86.36)
		(size 0.508)
		(drill 0.254)
		(layers "F.Cu" "B.Cu")
		(net "GND")
	)
	(via
		(at 33.6169 -143.1925)
		(size 0.508)
		(drill 0.254)
		(layers "F.Cu" "B.Cu")
		(net "GND")
	)
	(via
		(at 162.56 -20.32)
		(size 0.508)
		(drill 0.254)
		(layers "F.Cu" "B.Cu")
		(net "GND")
	)
	(via
		(at 240.03 -392.43)
		(size 0.7112)
		(drill 0.4064)
		(layers "F.Cu" "B.Cu")
		(net "GND")
	)
	(via
		(at 157.48 -121.92)
		(size 0.508)
		(drill 0.254)
		(layers "F.Cu" "B.Cu")
		(net "GND")
	)
	(via
		(at 203.2 -223.52)
		(size 0.508)
		(drill 0.254)
		(layers "F.Cu" "B.Cu")
		(net "GND")
	)
	(via
		(at 121.92 -482.6)
		(size 0.508)
		(drill 0.254)
		(layers "F.Cu" "B.Cu")
		(net "GND")
	)
	(via
		(at 132.08 -325.12)
		(size 0.508)
		(drill 0.254)
		(layers "F.Cu" "B.Cu")
		(net "GND")
	)
	(via
		(at 247.029986 -504.603004)
		(size 0.508)
		(drill 0.254)
		(layers "F.Cu" "B.Cu")
		(net "GND")
	)
	(via
		(at 259.08 -96.52)
		(size 0.508)
		(drill 0.254)
		(layers "F.Cu" "B.Cu")
		(net "GND")
	)
	(via
		(at 157.48 -132.08)
		(size 0.508)
		(drill 0.254)
		(layers "F.Cu" "B.Cu")
		(net "GND")
	)
	(via
		(at 43.58513 -484.11511)
		(size 0.508)
		(drill 0.254)
		(layers "F.Cu" "B.Cu")
		(net "GND")
	)
	(via
		(at 4.191 -192.290192)
		(size 0.508)
		(drill 0.254)
		(layers "F.Cu" "B.Cu")
		(net "GND")
	)
	(via
		(at 233.68 -30.48)
		(size 0.508)
		(drill 0.254)
		(layers "F.Cu" "B.Cu")
		(net "GND")
	)
	(via
		(at 83.7184 -148.1328)
		(size 0.508)
		(drill 0.254)
		(layers "F.Cu" "B.Cu")
		(net "GND")
	)
	(via
		(at 101.981 -212.344)
		(size 0.508)
		(drill 0.254)
		(layers "F.Cu" "B.Cu")
		(net "GND")
	)
	(via
		(at 1.397 -35.809428)
		(size 0.508)
		(drill 0.254)
		(layers "F.Cu" "B.Cu")
		(net "GND")
	)
	(via
		(at 262.103108 -484.116126)
		(size 0.508)
		(drill 0.254)
		(layers "F.Cu" "B.Cu")
		(net "GND")
	)
	(via
		(at 72.136 -439.7375)
		(size 0.508)
		(drill 0.254)
		(layers "F.Cu" "B.Cu")
		(net "GND")
	)
	(via
		(at 147.32 -177.8)
		(size 0.508)
		(drill 0.254)
		(layers "F.Cu" "B.Cu")
		(net "GND")
	)
	(via
		(at 262.103108 -199.038464)
		(size 0.508)
		(drill 0.254)
		(layers "F.Cu" "B.Cu")
		(net "GND")
	)
	(via
		(at 167.64 -50.8)
		(size 0.508)
		(drill 0.254)
		(layers "F.Cu" "B.Cu")
		(net "GND")
	)
	(via
		(at 111.76 -238.76)
		(size 0.508)
		(drill 0.254)
		(layers "F.Cu" "B.Cu")
		(net "GND")
	)
	(via
		(at 51.308 -389.636)
		(size 0.508)
		(drill 0.254)
		(layers "F.Cu" "B.Cu")
		(net "GND")
	)
	(via
		(at 9.779 -475.3229)
		(size 0.508)
		(drill 0.254)
		(layers "F.Cu" "B.Cu")
		(net "GND")
	)
	(via
		(at 96.52 -279.4)
		(size 0.508)
		(drill 0.254)
		(layers "F.Cu" "B.Cu")
		(net "GND")
	)
	(via
		(at 23.14575 -397.7386)
		(size 0.508)
		(drill 0.254)
		(layers "F.Cu" "B.Cu")
		(net "GND")
	)
	(via
		(at 111.76 -320.04)
		(size 0.508)
		(drill 0.254)
		(layers "F.Cu" "B.Cu")
		(net "GND")
	)
	(via
		(at 162.56 -86.36)
		(size 0.508)
		(drill 0.254)
		(layers "F.Cu" "B.Cu")
		(net "GND")
	)
	(via
		(at 81.28 -320.04)
		(size 0.508)
		(drill 0.254)
		(layers "F.Cu" "B.Cu")
		(net "GND")
	)
	(via
		(at 262.103108 -479.036126)
		(size 0.508)
		(drill 0.254)
		(layers "F.Cu" "B.Cu")
		(net "GND")
	)
	(via
		(at 127 -269.24)
		(size 0.508)
		(drill 0.254)
		(layers "F.Cu" "B.Cu")
		(net "GND")
	)
	(via
		(at 233.426 -474.483938)
		(size 0.508)
		(drill 0.254)
		(layers "F.Cu" "B.Cu")
		(net "GND")
	)
	(via
		(at 84.455 -151.638)
		(size 0.508)
		(drill 0.254)
		(layers "F.Cu" "B.Cu")
		(net "GND")
	)
	(via
		(at 36.957 -459.105)
		(size 0.508)
		(drill 0.254)
		(layers "F.Cu" "B.Cu")
		(net "GND")
	)
	(via
		(at 111.76 -325.12)
		(size 0.508)
		(drill 0.254)
		(layers "F.Cu" "B.Cu")
		(net "GND")
	)
	(via
		(at 193.04 -284.48)
		(size 0.508)
		(drill 0.254)
		(layers "F.Cu" "B.Cu")
		(net "GND")
	)
	(via
		(at 259.08 -213.36)
		(size 0.508)
		(drill 0.254)
		(layers "F.Cu" "B.Cu")
		(net "GND")
	)
	(via
		(at 27.69362 -450.221096)
		(size 0.508)
		(drill 0.254)
		(layers "F.Cu" "B.Cu")
		(net "GND")
	)
	(via
		(at 37.61613 -174.39005)
		(size 0.508)
		(drill 0.254)
		(layers "F.Cu" "B.Cu")
		(net "GND")
	)
	(via
		(at 259.08 -294.64)
		(size 0.508)
		(drill 0.254)
		(layers "F.Cu" "B.Cu")
		(net "GND")
	)
	(via
		(at 198.12 -243.84)
		(size 0.508)
		(drill 0.254)
		(layers "F.Cu" "B.Cu")
		(net "GND")
	)
	(via
		(at 127 -294.64)
		(size 0.508)
		(drill 0.254)
		(layers "F.Cu" "B.Cu")
		(net "GND")
	)
	(via
		(at 222.616014 -474.59011)
		(size 0.508)
		(drill 0.254)
		(layers "F.Cu" "B.Cu")
		(net "GND")
	)
	(via
		(at 106.68 -167.64)
		(size 0.508)
		(drill 0.254)
		(layers "F.Cu" "B.Cu")
		(net "GND")
	)
	(via
		(at 222.631 -403.606)
		(size 0.508)
		(drill 0.254)
		(layers "F.Cu" "B.Cu")
		(net "GND")
	)
	(via
		(at 137.16 -309.88)
		(size 0.508)
		(drill 0.254)
		(layers "F.Cu" "B.Cu")
		(net "GND")
	)
	(via
		(at 4.191 -184.290208)
		(size 0.508)
		(drill 0.254)
		(layers "F.Cu" "B.Cu")
		(net "GND")
	)
	(via
		(at 101.6 -55.88)
		(size 0.508)
		(drill 0.254)
		(layers "F.Cu" "B.Cu")
		(net "GND")
	)
	(via
		(at 24.384 -246.210074)
		(size 0.508)
		(drill 0.254)
		(layers "F.Cu" "B.Cu")
		(net "GND")
	)
	(via
		(at 162.56 -269.24)
		(size 0.508)
		(drill 0.254)
		(layers "F.Cu" "B.Cu")
		(net "GND")
	)
	(via
		(at 96.52 -401.32)
		(size 0.508)
		(drill 0.254)
		(layers "F.Cu" "B.Cu")
		(net "GND")
	)
	(via
		(at 1.397 -127.249428)
		(size 0.508)
		(drill 0.254)
		(layers "F.Cu" "B.Cu")
		(net "GND")
	)
	(via
		(at 193.04 -187.96)
		(size 0.508)
		(drill 0.254)
		(layers "F.Cu" "B.Cu")
		(net "GND")
	)
	(via
		(at 222.616014 -272.590006)
		(size 0.508)
		(drill 0.254)
		(layers "F.Cu" "B.Cu")
		(net "GND")
	)
	(via
		(at 89.535 -17.399)
		(size 0.508)
		(drill 0.254)
		(layers "F.Cu" "B.Cu")
		(net "GND")
	)
	(via
		(at 37.61613 -375.590054)
		(size 0.508)
		(drill 0.254)
		(layers "F.Cu" "B.Cu")
		(net "GND")
	)
	(via
		(at 76.2 -121.92)
		(size 0.508)
		(drill 0.254)
		(layers "F.Cu" "B.Cu")
		(net "GND")
	)
	(via
		(at 213.36 -502.92)
		(size 0.508)
		(drill 0.254)
		(layers "F.Cu" "B.Cu")
		(net "GND")
	)
	(via
		(at 254 -162.56)
		(size 0.508)
		(drill 0.254)
		(layers "F.Cu" "B.Cu")
		(net "GND")
	)
	(via
		(at 248.92 -152.4)
		(size 0.508)
		(drill 0.254)
		(layers "F.Cu" "B.Cu")
		(net "GND")
	)
	(via
		(at 127 -487.68)
		(size 0.508)
		(drill 0.254)
		(layers "F.Cu" "B.Cu")
		(net "GND")
	)
	(via
		(at 96.52 -157.48)
		(size 0.508)
		(drill 0.254)
		(layers "F.Cu" "B.Cu")
		(net "GND")
	)
	(via
		(at 99.822 -437.769)
		(size 0.508)
		(drill 0.254)
		(layers "F.Cu" "B.Cu")
		(net "GND")
	)
	(via
		(at 10.16 -35.56)
		(size 0.508)
		(drill 0.254)
		(layers "F.Cu" "B.Cu")
		(net "GND")
	)
	(via
		(at 219.314014 -55.85206)
		(size 0.508)
		(drill 0.254)
		(layers "F.Cu" "B.Cu")
		(net "GND")
	)
	(via
		(at 147.32 -436.88)
		(size 0.508)
		(drill 0.254)
		(layers "F.Cu" "B.Cu")
		(net "GND")
	)
	(via
		(at 227.457 -433.832)
		(size 0.508)
		(drill 0.254)
		(layers "F.Cu" "B.Cu")
		(net "GND")
	)
	(via
		(at 229.828852 -161.699702)
		(size 0.508)
		(drill 0.254)
		(layers "F.Cu" "B.Cu")
		(net "GND")
	)
	(via
		(at 6.223 -414.690052)
		(size 0.508)
		(drill 0.254)
		(layers "F.Cu" "B.Cu")
		(net "GND")
	)
	(via
		(at 68.2752 -450.7484)
		(size 0.508)
		(drill 0.254)
		(layers "F.Cu" "B.Cu")
		(net "GND")
	)
	(via
		(at 218.44 -60.96)
		(size 0.508)
		(drill 0.254)
		(layers "F.Cu" "B.Cu")
		(net "GND")
	)
	(via
		(at 162.56 -325.12)
		(size 0.508)
		(drill 0.254)
		(layers "F.Cu" "B.Cu")
		(net "GND")
	)
	(via
		(at 34.288222 -179.64912)
		(size 0.508)
		(drill 0.254)
		(layers "F.Cu" "B.Cu")
		(net "GND")
	)
	(via
		(at 46.355 -412.115)
		(size 0.508)
		(drill 0.254)
		(layers "F.Cu" "B.Cu")
		(net "GND")
	)
	(via
		(at 132.08 -218.44)
		(size 0.508)
		(drill 0.254)
		(layers "F.Cu" "B.Cu")
		(net "GND")
	)
	(via
		(at 60.96 -5.08)
		(size 0.508)
		(drill 0.254)
		(layers "F.Cu" "B.Cu")
		(net "GND")
	)
	(via
		(at 4.191 -171.490132)
		(size 0.508)
		(drill 0.254)
		(layers "F.Cu" "B.Cu")
		(net "GND")
	)
	(via
		(at 121.92 -370.84)
		(size 0.508)
		(drill 0.254)
		(layers "F.Cu" "B.Cu")
		(net "GND")
	)
	(via
		(at 137.16 -91.44)
		(size 0.508)
		(drill 0.254)
		(layers "F.Cu" "B.Cu")
		(net "GND")
	)
	(via
		(at 1.397 -106.929428)
		(size 0.508)
		(drill 0.254)
		(layers "F.Cu" "B.Cu")
		(net "GND")
	)
	(via
		(at 259.08 -472.44)
		(size 0.508)
		(drill 0.254)
		(layers "F.Cu" "B.Cu")
		(net "GND")
	)
	(via
		(at 147.32 -76.2)
		(size 0.508)
		(drill 0.254)
		(layers "F.Cu" "B.Cu")
		(net "GND")
	)
	(via
		(at 33.782 -502.1834)
		(size 0.508)
		(drill 0.254)
		(layers "F.Cu" "B.Cu")
		(net "GND")
	)
	(via
		(at 162.56 -447.04)
		(size 0.508)
		(drill 0.254)
		(layers "F.Cu" "B.Cu")
		(net "GND")
	)
	(via
		(at 95.377 -98.806)
		(size 0.508)
		(drill 0.254)
		(layers "F.Cu" "B.Cu")
		(net "GND")
	)
	(via
		(at 238.76 -20.32)
		(size 0.508)
		(drill 0.254)
		(layers "F.Cu" "B.Cu")
		(net "GND")
	)
	(via
		(at 91.44 -391.16)
		(size 0.508)
		(drill 0.254)
		(layers "F.Cu" "B.Cu")
		(net "GND")
	)
	(via
		(at 182.88 -60.96)
		(size 0.508)
		(drill 0.254)
		(layers "F.Cu" "B.Cu")
		(net "GND")
	)
	(via
		(at 231.144572 -1.397)
		(size 0.508)
		(drill 0.254)
		(layers "F.Cu" "B.Cu")
		(net "GND")
	)
	(via
		(at 111.76 -467.36)
		(size 0.508)
		(drill 0.254)
		(layers "F.Cu" "B.Cu")
		(net "GND")
	)
	(via
		(at 137.16 -25.4)
		(size 0.508)
		(drill 0.254)
		(layers "F.Cu" "B.Cu")
		(net "GND")
	)
	(via
		(at 121.92 -355.6)
		(size 0.508)
		(drill 0.254)
		(layers "F.Cu" "B.Cu")
		(net "GND")
	)
	(via
		(at 262.103108 -51.718464)
		(size 0.508)
		(drill 0.254)
		(layers "F.Cu" "B.Cu")
		(net "GND")
	)
	(via
		(at 121.92 -223.52)
		(size 0.508)
		(drill 0.254)
		(layers "F.Cu" "B.Cu")
		(net "GND")
	)
	(via
		(at 6.223 -327.87463)
		(size 0.508)
		(drill 0.254)
		(layers "F.Cu" "B.Cu")
		(net "GND")
	)
	(via
		(at 167.64 -426.72)
		(size 0.508)
		(drill 0.254)
		(layers "F.Cu" "B.Cu")
		(net "GND")
	)
	(via
		(at 96.52 -360.68)
		(size 0.508)
		(drill 0.254)
		(layers "F.Cu" "B.Cu")
		(net "GND")
	)
	(via
		(at 222.616014 -78.589886)
		(size 0.508)
		(drill 0.254)
		(layers "F.Cu" "B.Cu")
		(net "GND")
	)
	(via
		(at 238.76 -274.32)
		(size 0.508)
		(drill 0.254)
		(layers "F.Cu" "B.Cu")
		(net "GND")
	)
	(via
		(at 137.16 -152.4)
		(size 0.508)
		(drill 0.254)
		(layers "F.Cu" "B.Cu")
		(net "GND")
	)
	(via
		(at 25.4 -489.712)
		(size 0.508)
		(drill 0.254)
		(layers "F.Cu" "B.Cu")
		(net "GND")
	)
	(via
		(at 167.64 -381)
		(size 0.508)
		(drill 0.254)
		(layers "F.Cu" "B.Cu")
		(net "GND")
	)
	(via
		(at 127 -198.12)
		(size 0.508)
		(drill 0.254)
		(layers "F.Cu" "B.Cu")
		(net "GND")
	)
	(via
		(at 162.56 -35.56)
		(size 0.508)
		(drill 0.254)
		(layers "F.Cu" "B.Cu")
		(net "GND")
	)
	(via
		(at 116.84 -452.12)
		(size 0.508)
		(drill 0.254)
		(layers "F.Cu" "B.Cu")
		(net "GND")
	)
	(via
		(at 172.72 -35.56)
		(size 0.508)
		(drill 0.254)
		(layers "F.Cu" "B.Cu")
		(net "GND")
	)
	(via
		(at 198.12 -386.08)
		(size 0.508)
		(drill 0.254)
		(layers "F.Cu" "B.Cu")
		(net "GND")
	)
	(via
		(at 27.686 -20.600924)
		(size 0.508)
		(drill 0.254)
		(layers "F.Cu" "B.Cu")
		(net "GND")
	)
	(via
		(at 221.71025 -342.007952)
		(size 0.508)
		(drill 0.254)
		(layers "F.Cu" "B.Cu")
		(net "GND")
	)
	(via
		(at 213.36 -106.68)
		(size 0.508)
		(drill 0.254)
		(layers "F.Cu" "B.Cu")
		(net "GND")
	)
	(via
		(at 177.8 -426.72)
		(size 0.508)
		(drill 0.254)
		(layers "F.Cu" "B.Cu")
		(net "GND")
	)
	(via
		(at 45.72 -274.32)
		(size 0.508)
		(drill 0.254)
		(layers "F.Cu" "B.Cu")
		(net "GND")
	)
	(via
		(at 172.72 -309.88)
		(size 0.508)
		(drill 0.254)
		(layers "F.Cu" "B.Cu")
		(net "GND")
	)
	(via
		(at 24.384 -31.409894)
		(size 0.508)
		(drill 0.254)
		(layers "F.Cu" "B.Cu")
		(net "GND")
	)
	(via
		(at 15.24 -482.6)
		(size 0.508)
		(drill 0.254)
		(layers "F.Cu" "B.Cu")
		(net "GND")
	)
	(via
		(at 225.1964 -446.0494)
		(size 0.508)
		(drill 0.254)
		(layers "F.Cu" "B.Cu")
		(net "GND")
	)
	(via
		(at 116.84 -254)
		(size 0.508)
		(drill 0.254)
		(layers "F.Cu" "B.Cu")
		(net "GND")
	)
	(via
		(at 127 -436.88)
		(size 0.508)
		(drill 0.254)
		(layers "F.Cu" "B.Cu")
		(net "GND")
	)
	(via
		(at 11.4808 -467.1822)
		(size 0.508)
		(drill 0.254)
		(layers "F.Cu" "B.Cu")
		(net "GND")
	)
	(via
		(at 106.68 -193.04)
		(size 0.508)
		(drill 0.254)
		(layers "F.Cu" "B.Cu")
		(net "GND")
	)
	(via
		(at 66.04 -330.2)
		(size 0.508)
		(drill 0.254)
		(layers "F.Cu" "B.Cu")
		(net "GND")
	)
	(via
		(at 165.749986 -504.603004)
		(size 0.508)
		(drill 0.254)
		(layers "F.Cu" "B.Cu")
		(net "GND")
	)
	(via
		(at 241.681 -421.132)
		(size 0.508)
		(drill 0.254)
		(layers "F.Cu" "B.Cu")
		(net "GND")
	)
	(via
		(at 43.942 -79.375)
		(size 0.508)
		(drill 0.254)
		(layers "F.Cu" "B.Cu")
		(net "GND")
	)
	(via
		(at 213.36 -340.36)
		(size 0.508)
		(drill 0.254)
		(layers "F.Cu" "B.Cu")
		(net "GND")
	)
	(via
		(at 6.223 -357.609902)
		(size 0.508)
		(drill 0.254)
		(layers "F.Cu" "B.Cu")
		(net "GND")
	)
	(via
		(at 172.72 -426.72)
		(size 0.508)
		(drill 0.254)
		(layers "F.Cu" "B.Cu")
		(net "GND")
	)
	(via
		(at 39.374572 -1.397)
		(size 0.508)
		(drill 0.254)
		(layers "F.Cu" "B.Cu")
		(net "GND")
	)
	(via
		(at 76.835 -148.082)
		(size 0.508)
		(drill 0.254)
		(layers "F.Cu" "B.Cu")
		(net "GND")
	)
	(via
		(at 18.415 -450.395086)
		(size 0.508)
		(drill 0.254)
		(layers "F.Cu" "B.Cu")
		(net "GND")
	)
	(via
		(at 213.36 -177.8)
		(size 0.508)
		(drill 0.254)
		(layers "F.Cu" "B.Cu")
		(net "GND")
	)
	(via
		(at 96.52 -462.28)
		(size 0.508)
		(drill 0.254)
		(layers "F.Cu" "B.Cu")
		(net "GND")
	)
	(via
		(at 6.223 -339.925406)
		(size 0.508)
		(drill 0.254)
		(layers "F.Cu" "B.Cu")
		(net "GND")
	)
	(via
		(at 60.96 -274.32)
		(size 0.508)
		(drill 0.254)
		(layers "F.Cu" "B.Cu")
		(net "GND")
	)
	(via
		(at 96.774 -208.026)
		(size 0.508)
		(drill 0.254)
		(layers "F.Cu" "B.Cu")
		(net "GND")
	)
	(via
		(at 222.616014 -76.18984)
		(size 0.508)
		(drill 0.254)
		(layers "F.Cu" "B.Cu")
		(net "GND")
	)
	(via
		(at 6.223 -292.80993)
		(size 0.508)
		(drill 0.254)
		(layers "F.Cu" "B.Cu")
		(net "GND")
	)
	(via
		(at 243.84 -66.04)
		(size 0.508)
		(drill 0.254)
		(layers "F.Cu" "B.Cu")
		(net "GND")
	)
	(via
		(at 101.6 -345.44)
		(size 0.508)
		(drill 0.254)
		(layers "F.Cu" "B.Cu")
		(net "GND")
	)
	(via
		(at 37.592 -453.898)
		(size 0.508)
		(drill 0.254)
		(layers "F.Cu" "B.Cu")
		(net "GND")
	)
	(via
		(at 26.416 -134.874)
		(size 0.508)
		(drill 0.254)
		(layers "F.Cu" "B.Cu")
		(net "GND")
	)
	(via
		(at 132.08 -248.92)
		(size 0.508)
		(drill 0.254)
		(layers "F.Cu" "B.Cu")
		(net "GND")
	)
	(via
		(at 132.08 -320.04)
		(size 0.508)
		(drill 0.254)
		(layers "F.Cu" "B.Cu")
		(net "GND")
	)
	(via
		(at 106.68 -447.04)
		(size 0.508)
		(drill 0.254)
		(layers "F.Cu" "B.Cu")
		(net "GND")
	)
	(via
		(at 116.84 -314.96)
		(size 0.508)
		(drill 0.254)
		(layers "F.Cu" "B.Cu")
		(net "GND")
	)
	(via
		(at 247.65 -387.35)
		(size 0.7112)
		(drill 0.4064)
		(layers "F.Cu" "B.Cu")
		(net "GND")
	)
	(via
		(at 198.12 -132.08)
		(size 0.508)
		(drill 0.254)
		(layers "F.Cu" "B.Cu")
		(net "GND")
	)
	(via
		(at 111.76 -137.16)
		(size 0.508)
		(drill 0.254)
		(layers "F.Cu" "B.Cu")
		(net "GND")
	)
	(via
		(at 228.6 -320.04)
		(size 0.508)
		(drill 0.254)
		(layers "F.Cu" "B.Cu")
		(net "GND")
	)
	(via
		(at 208.28 -152.4)
		(size 0.508)
		(drill 0.254)
		(layers "F.Cu" "B.Cu")
		(net "GND")
	)
	(via
		(at 187.96 -233.68)
		(size 0.508)
		(drill 0.254)
		(layers "F.Cu" "B.Cu")
		(net "GND")
	)
	(via
		(at 101.6 -401.32)
		(size 0.508)
		(drill 0.254)
		(layers "F.Cu" "B.Cu")
		(net "GND")
	)
	(via
		(at 219.314014 -363.128052)
		(size 0.508)
		(drill 0.254)
		(layers "F.Cu" "B.Cu")
		(net "GND")
	)
	(via
		(at 152.4 -127)
		(size 0.508)
		(drill 0.254)
		(layers "F.Cu" "B.Cu")
		(net "GND")
	)
	(via
		(at 4.191 -352.690176)
		(size 0.508)
		(drill 0.254)
		(layers "F.Cu" "B.Cu")
		(net "GND")
	)
	(via
		(at 121.92 -492.76)
		(size 0.508)
		(drill 0.254)
		(layers "F.Cu" "B.Cu")
		(net "GND")
	)
	(via
		(at 262.103108 -463.796126)
		(size 0.508)
		(drill 0.254)
		(layers "F.Cu" "B.Cu")
		(net "GND")
	)
	(via
		(at 116.84 -284.48)
		(size 0.508)
		(drill 0.254)
		(layers "F.Cu" "B.Cu")
		(net "GND")
	)
	(via
		(at 208.28 -320.04)
		(size 0.508)
		(drill 0.254)
		(layers "F.Cu" "B.Cu")
		(net "GND")
	)
	(via
		(at 162.56 -365.76)
		(size 0.508)
		(drill 0.254)
		(layers "F.Cu" "B.Cu")
		(net "GND")
	)
	(via
		(at 1.397 -15.489428)
		(size 0.508)
		(drill 0.254)
		(layers "F.Cu" "B.Cu")
		(net "GND")
	)
	(via
		(at 24.9682 -318.9986)
		(size 0.508)
		(drill 0.254)
		(layers "F.Cu" "B.Cu")
		(net "GND")
	)
	(via
		(at 193.04 -335.28)
		(size 0.508)
		(drill 0.254)
		(layers "F.Cu" "B.Cu")
		(net "GND")
	)
	(via
		(at 262.103108 -219.358464)
		(size 0.508)
		(drill 0.254)
		(layers "F.Cu" "B.Cu")
		(net "GND")
	)
	(via
		(at 40.5892 -439.42)
		(size 0.508)
		(drill 0.254)
		(layers "F.Cu" "B.Cu")
		(net "GND")
	)
	(via
		(at 187.96 -365.76)
		(size 0.508)
		(drill 0.254)
		(layers "F.Cu" "B.Cu")
		(net "GND")
	)
	(via
		(at 90.4875 -88.646)
		(size 0.508)
		(drill 0.254)
		(layers "F.Cu" "B.Cu")
		(net "GND")
	)
	(via
		(at 106.68 -370.84)
		(size 0.508)
		(drill 0.254)
		(layers "F.Cu" "B.Cu")
		(net "GND")
	)
	(via
		(at 27.686 -432.601116)
		(size 0.508)
		(drill 0.254)
		(layers "F.Cu" "B.Cu")
		(net "GND")
	)
	(via
		(at 71.12 -45.72)
		(size 0.508)
		(drill 0.254)
		(layers "F.Cu" "B.Cu")
		(net "GND")
	)
	(via
		(at 4.191 -427.52518)
		(size 0.508)
		(drill 0.254)
		(layers "F.Cu" "B.Cu")
		(net "GND")
	)
	(via
		(at 182.88 -386.08)
		(size 0.508)
		(drill 0.254)
		(layers "F.Cu" "B.Cu")
		(net "GND")
	)
	(via
		(at 53.344572 -1.397)
		(size 0.508)
		(drill 0.254)
		(layers "F.Cu" "B.Cu")
		(net "GND")
	)
	(via
		(at 101.6 -157.48)
		(size 0.508)
		(drill 0.254)
		(layers "F.Cu" "B.Cu")
		(net "GND")
	)
	(via
		(at 157.48 -76.2)
		(size 0.508)
		(drill 0.254)
		(layers "F.Cu" "B.Cu")
		(net "GND")
	)
	(via
		(at 142.24 -81.28)
		(size 0.508)
		(drill 0.254)
		(layers "F.Cu" "B.Cu")
		(net "GND")
	)
	(via
		(at 4.191 -341.566246)
		(size 0.508)
		(drill 0.254)
		(layers "F.Cu" "B.Cu")
		(net "GND")
	)
	(via
		(at 147.32 -370.84)
		(size 0.508)
		(drill 0.254)
		(layers "F.Cu" "B.Cu")
		(net "GND")
	)
	(via
		(at 238.76 -294.64)
		(size 0.508)
		(drill 0.254)
		(layers "F.Cu" "B.Cu")
		(net "GND")
	)
	(via
		(at 93.98 -104.394)
		(size 0.508)
		(drill 0.254)
		(layers "F.Cu" "B.Cu")
		(net "GND")
	)
	(via
		(at 91.44 -35.56)
		(size 0.508)
		(drill 0.254)
		(layers "F.Cu" "B.Cu")
		(net "GND")
	)
	(via
		(at 1.397 -117.089428)
		(size 0.508)
		(drill 0.254)
		(layers "F.Cu" "B.Cu")
		(net "GND")
	)
	(via
		(at 262.103108 -341.278464)
		(size 0.508)
		(drill 0.254)
		(layers "F.Cu" "B.Cu")
		(net "GND")
	)
	(via
		(at 238.76 -50.8)
		(size 0.508)
		(drill 0.254)
		(layers "F.Cu" "B.Cu")
		(net "GND")
	)
	(via
		(at 121.92 -431.8)
		(size 0.508)
		(drill 0.254)
		(layers "F.Cu" "B.Cu")
		(net "GND")
	)
	(via
		(at 121.92 -218.44)
		(size 0.508)
		(drill 0.254)
		(layers "F.Cu" "B.Cu")
		(net "GND")
	)
	(via
		(at 35.56 -20.32)
		(size 0.508)
		(drill 0.254)
		(layers "F.Cu" "B.Cu")
		(net "GND")
	)
	(via
		(at 120.029986 -504.603004)
		(size 0.508)
		(drill 0.254)
		(layers "F.Cu" "B.Cu")
		(net "GND")
	)
	(via
		(at 259.08 -162.56)
		(size 0.508)
		(drill 0.254)
		(layers "F.Cu" "B.Cu")
		(net "GND")
	)
	(via
		(at 187.96 -132.08)
		(size 0.508)
		(drill 0.254)
		(layers "F.Cu" "B.Cu")
		(net "GND")
	)
	(via
		(at 230.503222 -137.67435)
		(size 0.508)
		(drill 0.254)
		(layers "F.Cu" "B.Cu")
		(net "GND")
	)
	(via
		(at 259.08 -452.12)
		(size 0.508)
		(drill 0.254)
		(layers "F.Cu" "B.Cu")
		(net "GND")
	)
	(via
		(at 157.48 -477.52)
		(size 0.508)
		(drill 0.254)
		(layers "F.Cu" "B.Cu")
		(net "GND")
	)
	(via
		(at 18.415 -435.155086)
		(size 0.508)
		(drill 0.254)
		(layers "F.Cu" "B.Cu")
		(net "GND")
	)
	(via
		(at 6.223 -303.874678)
		(size 0.508)
		(drill 0.254)
		(layers "F.Cu" "B.Cu")
		(net "GND")
	)
	(via
		(at 106.68 -360.68)
		(size 0.508)
		(drill 0.254)
		(layers "F.Cu" "B.Cu")
		(net "GND")
	)
	(via
		(at 6.223 -223.43491)
		(size 0.508)
		(drill 0.254)
		(layers "F.Cu" "B.Cu")
		(net "GND")
	)
	(via
		(at 243.84 -340.36)
		(size 0.508)
		(drill 0.254)
		(layers "F.Cu" "B.Cu")
		(net "GND")
	)
	(via
		(at 162.56 -304.8)
		(size 0.508)
		(drill 0.254)
		(layers "F.Cu" "B.Cu")
		(net "GND")
	)
	(via
		(at 167.64 -294.64)
		(size 0.508)
		(drill 0.254)
		(layers "F.Cu" "B.Cu")
		(net "GND")
	)
	(via
		(at 198.12 -121.92)
		(size 0.508)
		(drill 0.254)
		(layers "F.Cu" "B.Cu")
		(net "GND")
	)
	(via
		(at 157.48 -213.36)
		(size 0.508)
		(drill 0.254)
		(layers "F.Cu" "B.Cu")
		(net "GND")
	)
	(via
		(at 187.96 -375.92)
		(size 0.508)
		(drill 0.254)
		(layers "F.Cu" "B.Cu")
		(net "GND")
	)
	(via
		(at 27.686 -245.872)
		(size 0.508)
		(drill 0.254)
		(layers "F.Cu" "B.Cu")
		(net "GND")
	)
	(via
		(at 43.66133 -368.415062)
		(size 0.508)
		(drill 0.254)
		(layers "F.Cu" "B.Cu")
		(net "GND")
	)
	(via
		(at 203.2 -101.6)
		(size 0.508)
		(drill 0.254)
		(layers "F.Cu" "B.Cu")
		(net "GND")
	)
	(via
		(at 162.56 -335.28)
		(size 0.508)
		(drill 0.254)
		(layers "F.Cu" "B.Cu")
		(net "GND")
	)
	(via
		(at 193.04 -60.96)
		(size 0.508)
		(drill 0.254)
		(layers "F.Cu" "B.Cu")
		(net "GND")
	)
	(via
		(at 142.24 -365.76)
		(size 0.508)
		(drill 0.254)
		(layers "F.Cu" "B.Cu")
		(net "GND")
	)
	(via
		(at 248.92 -487.68)
		(size 0.508)
		(drill 0.254)
		(layers "F.Cu" "B.Cu")
		(net "GND")
	)
	(via
		(at 157.48 -482.6)
		(size 0.508)
		(drill 0.254)
		(layers "F.Cu" "B.Cu")
		(net "GND")
	)
	(via
		(at 31.242 -432.308)
		(size 0.508)
		(drill 0.254)
		(layers "F.Cu" "B.Cu")
		(net "GND")
	)
	(via
		(at 198.12 -269.24)
		(size 0.508)
		(drill 0.254)
		(layers "F.Cu" "B.Cu")
		(net "GND")
	)
	(via
		(at 95.377 -433.197)
		(size 0.508)
		(drill 0.254)
		(layers "F.Cu" "B.Cu")
		(net "GND")
	)
	(via
		(at 6.223 -305.610006)
		(size 0.508)
		(drill 0.254)
		(layers "F.Cu" "B.Cu")
		(net "GND")
	)
	(via
		(at 243.84 -492.76)
		(size 0.508)
		(drill 0.254)
		(layers "F.Cu" "B.Cu")
		(net "GND")
	)
	(via
		(at 254 -182.88)
		(size 0.508)
		(drill 0.254)
		(layers "F.Cu" "B.Cu")
		(net "GND")
	)
	(via
		(at 121.92 -284.48)
		(size 0.508)
		(drill 0.254)
		(layers "F.Cu" "B.Cu")
		(net "GND")
	)
	(via
		(at 137.16 -106.68)
		(size 0.508)
		(drill 0.254)
		(layers "F.Cu" "B.Cu")
		(net "GND")
	)
	(via
		(at 172.72 -248.92)
		(size 0.508)
		(drill 0.254)
		(layers "F.Cu" "B.Cu")
		(net "GND")
	)
	(via
		(at 4.445 -461.391)
		(size 0.7112)
		(drill 0.4064)
		(layers "F.Cu" "B.Cu")
		(net "GND")
	)
	(via
		(at 132.08 -182.88)
		(size 0.508)
		(drill 0.254)
		(layers "F.Cu" "B.Cu")
		(net "GND")
	)
	(via
		(at 77.356462 -95.016574)
		(size 0.508)
		(drill 0.254)
		(layers "F.Cu" "B.Cu")
		(net "GND")
	)
	(via
		(at 106.68 -66.04)
		(size 0.508)
		(drill 0.254)
		(layers "F.Cu" "B.Cu")
		(net "GND")
	)
	(via
		(at 238.76 -502.92)
		(size 0.508)
		(drill 0.254)
		(layers "F.Cu" "B.Cu")
		(net "GND")
	)
	(via
		(at 248.92 -447.04)
		(size 0.508)
		(drill 0.254)
		(layers "F.Cu" "B.Cu")
		(net "GND")
	)
	(via
		(at 34.290254 -284.131004)
		(size 0.508)
		(drill 0.254)
		(layers "F.Cu" "B.Cu")
		(net "GND")
	)
	(via
		(at 222.616014 -365.190024)
		(size 0.508)
		(drill 0.254)
		(layers "F.Cu" "B.Cu")
		(net "GND")
	)
	(via
		(at 182.88 -375.92)
		(size 0.508)
		(drill 0.254)
		(layers "F.Cu" "B.Cu")
		(net "GND")
	)
	(via
		(at 203.2 -111.76)
		(size 0.508)
		(drill 0.254)
		(layers "F.Cu" "B.Cu")
		(net "GND")
	)
	(via
		(at 101.6 -264.16)
		(size 0.508)
		(drill 0.254)
		(layers "F.Cu" "B.Cu")
		(net "GND")
	)
	(via
		(at 167.64 -279.4)
		(size 0.508)
		(drill 0.254)
		(layers "F.Cu" "B.Cu")
		(net "GND")
	)
	(via
		(at 22.864572 -1.397)
		(size 0.508)
		(drill 0.254)
		(layers "F.Cu" "B.Cu")
		(net "GND")
	)
	(via
		(at 147.32 -111.76)
		(size 0.508)
		(drill 0.254)
		(layers "F.Cu" "B.Cu")
		(net "GND")
	)
	(via
		(at 182.88 -66.04)
		(size 0.508)
		(drill 0.254)
		(layers "F.Cu" "B.Cu")
		(net "GND")
	)
	(via
		(at 66.04 -218.44)
		(size 0.508)
		(drill 0.254)
		(layers "F.Cu" "B.Cu")
		(net "GND")
	)
	(via
		(at 243.84 -167.64)
		(size 0.508)
		(drill 0.254)
		(layers "F.Cu" "B.Cu")
		(net "GND")
	)
	(via
		(at 97.4725 -88.646)
		(size 0.508)
		(drill 0.254)
		(layers "F.Cu" "B.Cu")
		(net "GND")
	)
	(via
		(at 243.84 -299.72)
		(size 0.508)
		(drill 0.254)
		(layers "F.Cu" "B.Cu")
		(net "GND")
	)
	(via
		(at 81.28 -60.96)
		(size 0.508)
		(drill 0.254)
		(layers "F.Cu" "B.Cu")
		(net "GND")
	)
	(via
		(at 228.585014 -364.605062)
		(size 0.508)
		(drill 0.254)
		(layers "F.Cu" "B.Cu")
		(net "GND")
	)
	(via
		(at 182.88 -182.88)
		(size 0.508)
		(drill 0.254)
		(layers "F.Cu" "B.Cu")
		(net "GND")
	)
	(via
		(at 73.025 -455.93)
		(size 0.508)
		(drill 0.254)
		(layers "F.Cu" "B.Cu")
		(net "GND")
	)
	(via
		(at 20.701 -308.102)
		(size 0.508)
		(drill 0.254)
		(layers "F.Cu" "B.Cu")
		(net "GND")
	)
	(via
		(at 63.504572 -1.397)
		(size 0.508)
		(drill 0.254)
		(layers "F.Cu" "B.Cu")
		(net "GND")
	)
	(via
		(at 259.08 -284.48)
		(size 0.508)
		(drill 0.254)
		(layers "F.Cu" "B.Cu")
		(net "GND")
	)
	(via
		(at 30.48 -325.12)
		(size 0.508)
		(drill 0.254)
		(layers "F.Cu" "B.Cu")
		(net "GND")
	)
	(via
		(at 132.08 -132.08)
		(size 0.508)
		(drill 0.254)
		(layers "F.Cu" "B.Cu")
		(net "GND")
	)
	(via
		(at 84.201 -99.822)
		(size 0.508)
		(drill 0.254)
		(layers "F.Cu" "B.Cu")
		(net "GND")
	)
	(via
		(at 81.28 -289.56)
		(size 0.508)
		(drill 0.254)
		(layers "F.Cu" "B.Cu")
		(net "GND")
	)
	(via
		(at 34.6964 -427.2026)
		(size 0.508)
		(drill 0.254)
		(layers "F.Cu" "B.Cu")
		(net "GND")
	)
	(via
		(at 180.989986 -504.603004)
		(size 0.508)
		(drill 0.254)
		(layers "F.Cu" "B.Cu")
		(net "GND")
	)
	(via
		(at 152.4 -360.68)
		(size 0.508)
		(drill 0.254)
		(layers "F.Cu" "B.Cu")
		(net "GND")
	)
	(via
		(at 262.103108 -494.276126)
		(size 0.508)
		(drill 0.254)
		(layers "F.Cu" "B.Cu")
		(net "GND")
	)
	(via
		(at 208.28 -116.84)
		(size 0.508)
		(drill 0.254)
		(layers "F.Cu" "B.Cu")
		(net "GND")
	)
	(via
		(at 45.72 -309.88)
		(size 0.508)
		(drill 0.254)
		(layers "F.Cu" "B.Cu")
		(net "GND")
	)
	(via
		(at 259.08 -187.96)
		(size 0.508)
		(drill 0.254)
		(layers "F.Cu" "B.Cu")
		(net "GND")
	)
	(via
		(at 86.36 -137.16)
		(size 0.508)
		(drill 0.254)
		(layers "F.Cu" "B.Cu")
		(net "GND")
	)
	(via
		(at 111.76 -340.36)
		(size 0.508)
		(drill 0.254)
		(layers "F.Cu" "B.Cu")
		(net "GND")
	)
	(via
		(at 208.28 -487.68)
		(size 0.508)
		(drill 0.254)
		(layers "F.Cu" "B.Cu")
		(net "GND")
	)
	(via
		(at 237.49 -402.59)
		(size 0.7112)
		(drill 0.4064)
		(layers "F.Cu" "B.Cu")
		(net "GND")
	)
	(via
		(at 37.61613 -385.189984)
		(size 0.508)
		(drill 0.254)
		(layers "F.Cu" "B.Cu")
		(net "GND")
	)
	(via
		(at 5.08 -60.96)
		(size 0.508)
		(drill 0.254)
		(layers "F.Cu" "B.Cu")
		(net "GND")
	)
	(via
		(at 193.04 -142.24)
		(size 0.508)
		(drill 0.254)
		(layers "F.Cu" "B.Cu")
		(net "GND")
	)
	(via
		(at 182.88 -340.36)
		(size 0.508)
		(drill 0.254)
		(layers "F.Cu" "B.Cu")
		(net "GND")
	)
	(via
		(at 60.96 -487.68)
		(size 0.508)
		(drill 0.254)
		(layers "F.Cu" "B.Cu")
		(net "GND")
	)
	(via
		(at 1.397 -86.609428)
		(size 0.508)
		(drill 0.254)
		(layers "F.Cu" "B.Cu")
		(net "GND")
	)
	(via
		(at 10.16 -5.08)
		(size 0.508)
		(drill 0.254)
		(layers "F.Cu" "B.Cu")
		(net "GND")
	)
	(via
		(at 172.72 -152.4)
		(size 0.508)
		(drill 0.254)
		(layers "F.Cu" "B.Cu")
		(net "GND")
	)
	(via
		(at 193.04 -375.92)
		(size 0.508)
		(drill 0.254)
		(layers "F.Cu" "B.Cu")
		(net "GND")
	)
	(via
		(at 5.08 -30.48)
		(size 0.508)
		(drill 0.254)
		(layers "F.Cu" "B.Cu")
		(net "GND")
	)
	(via
		(at 50.8 -396.24)
		(size 0.508)
		(drill 0.254)
		(layers "F.Cu" "B.Cu")
		(net "GND")
	)
	(via
		(at 43.58513 -55.604918)
		(size 0.508)
		(drill 0.254)
		(layers "F.Cu" "B.Cu")
		(net "GND")
	)
	(via
		(at 132.08 -223.52)
		(size 0.508)
		(drill 0.254)
		(layers "F.Cu" "B.Cu")
		(net "GND")
	)
	(via
		(at 213.36 -44.2595)
		(size 0.508)
		(drill 0.254)
		(layers "F.Cu" "B.Cu")
		(net "GND")
	)
	(via
		(at 230.798116 -58.70067)
		(size 0.508)
		(drill 0.254)
		(layers "F.Cu" "B.Cu")
		(net "GND")
	)
	(via
		(at 121.92 -111.76)
		(size 0.508)
		(drill 0.254)
		(layers "F.Cu" "B.Cu")
		(net "GND")
	)
	(via
		(at 237.49 -389.89)
		(size 0.7112)
		(drill 0.4064)
		(layers "F.Cu" "B.Cu")
		(net "GND")
	)
	(via
		(at 127 -30.48)
		(size 0.508)
		(drill 0.254)
		(layers "F.Cu" "B.Cu")
		(net "GND")
	)
	(via
		(at 30.81528 -362.050584)
		(size 0.508)
		(drill 0.254)
		(layers "F.Cu" "B.Cu")
		(net "GND")
	)
	(via
		(at 1.397 -101.849428)
		(size 0.508)
		(drill 0.254)
		(layers "F.Cu" "B.Cu")
		(net "GND")
	)
	(via
		(at 142.24 -472.44)
		(size 0.508)
		(drill 0.254)
		(layers "F.Cu" "B.Cu")
		(net "GND")
	)
	(via
		(at 124.464572 -1.397)
		(size 0.508)
		(drill 0.254)
		(layers "F.Cu" "B.Cu")
		(net "GND")
	)
	(via
		(at 60.96 -66.04)
		(size 0.508)
		(drill 0.254)
		(layers "F.Cu" "B.Cu")
		(net "GND")
	)
	(via
		(at 243.84 -330.2)
		(size 0.508)
		(drill 0.254)
		(layers "F.Cu" "B.Cu")
		(net "GND")
	)
	(via
		(at 137.16 -45.72)
		(size 0.508)
		(drill 0.254)
		(layers "F.Cu" "B.Cu")
		(net "GND")
	)
	(via
		(at 127 -55.88)
		(size 0.508)
		(drill 0.254)
		(layers "F.Cu" "B.Cu")
		(net "GND")
	)
	(via
		(at 45.72 -45.72)
		(size 0.508)
		(drill 0.254)
		(layers "F.Cu" "B.Cu")
		(net "GND")
	)
	(via
		(at 91.44 -381)
		(size 0.508)
		(drill 0.254)
		(layers "F.Cu" "B.Cu")
		(net "GND")
	)
	(via
		(at 116.84 -167.64)
		(size 0.508)
		(drill 0.254)
		(layers "F.Cu" "B.Cu")
		(net "GND")
	)
	(via
		(at 121.92 -213.36)
		(size 0.508)
		(drill 0.254)
		(layers "F.Cu" "B.Cu")
		(net "GND")
	)
	(via
		(at 198.12 -304.8)
		(size 0.508)
		(drill 0.254)
		(layers "F.Cu" "B.Cu")
		(net "GND")
	)
	(via
		(at 240.03 -402.59)
		(size 0.7112)
		(drill 0.4064)
		(layers "F.Cu" "B.Cu")
		(net "GND")
	)
	(via
		(at 177.8 -264.16)
		(size 0.508)
		(drill 0.254)
		(layers "F.Cu" "B.Cu")
		(net "GND")
	)
	(via
		(at 182.88 -320.04)
		(size 0.508)
		(drill 0.254)
		(layers "F.Cu" "B.Cu")
		(net "GND")
	)
	(via
		(at 167.64 -497.84)
		(size 0.508)
		(drill 0.254)
		(layers "F.Cu" "B.Cu")
		(net "GND")
	)
	(via
		(at 76.2 -223.52)
		(size 0.508)
		(drill 0.254)
		(layers "F.Cu" "B.Cu")
		(net "GND")
	)
	(via
		(at 96.774 -101.6)
		(size 0.508)
		(drill 0.254)
		(layers "F.Cu" "B.Cu")
		(net "GND")
	)
	(via
		(at 96.52 -482.6)
		(size 0.508)
		(drill 0.254)
		(layers "F.Cu" "B.Cu")
		(net "GND")
	)
	(via
		(at 182.88 -213.36)
		(size 0.508)
		(drill 0.254)
		(layers "F.Cu" "B.Cu")
		(net "GND")
	)
	(via
		(at 218.44 -401.32)
		(size 0.508)
		(drill 0.254)
		(layers "F.Cu" "B.Cu")
		(net "GND")
	)
	(via
		(at 219.280232 -274.498308)
		(size 0.508)
		(drill 0.254)
		(layers "F.Cu" "B.Cu")
		(net "GND")
	)
	(via
		(at 147.32 -279.4)
		(size 0.508)
		(drill 0.254)
		(layers "F.Cu" "B.Cu")
		(net "GND")
	)
	(via
		(at 106.68 -335.28)
		(size 0.508)
		(drill 0.254)
		(layers "F.Cu" "B.Cu")
		(net "GND")
	)
	(via
		(at 213.36 -20.32)
		(size 0.508)
		(drill 0.254)
		(layers "F.Cu" "B.Cu")
		(net "GND")
	)
	(via
		(at 91.44 -477.52)
		(size 0.508)
		(drill 0.254)
		(layers "F.Cu" "B.Cu")
		(net "GND")
	)
	(via
		(at 216.636092 -317.253366)
		(size 0.7112)
		(drill 0.3556)
		(layers "F.Cu" "B.Cu")
		(net "GND")
	)
	(via
		(at 50.8 -482.6)
		(size 0.508)
		(drill 0.254)
		(layers "F.Cu" "B.Cu")
		(net "GND")
	)
	(via
		(at 4.191 -221.966282)
		(size 0.508)
		(drill 0.254)
		(layers "F.Cu" "B.Cu")
		(net "GND")
	)
	(via
		(at 64.149986 -504.603004)
		(size 0.508)
		(drill 0.254)
		(layers "F.Cu" "B.Cu")
		(net "GND")
	)
	(via
		(at 262.103108 -178.718464)
		(size 0.508)
		(drill 0.254)
		(layers "F.Cu" "B.Cu")
		(net "GND")
	)
	(via
		(at 35.56 -371.856)
		(size 0.508)
		(drill 0.254)
		(layers "F.Cu" "B.Cu")
		(net "GND")
	)
	(via
		(at 121.92 -30.48)
		(size 0.508)
		(drill 0.254)
		(layers "F.Cu" "B.Cu")
		(net "GND")
	)
	(via
		(at 116.84 -71.12)
		(size 0.508)
		(drill 0.254)
		(layers "F.Cu" "B.Cu")
		(net "GND")
	)
	(via
		(at 4.191 -231.566212)
		(size 0.508)
		(drill 0.254)
		(layers "F.Cu" "B.Cu")
		(net "GND")
	)
	(via
		(at 36.449 -299.8216)
		(size 0.508)
		(drill 0.254)
		(layers "F.Cu" "B.Cu")
		(net "GND")
	)
	(via
		(at 6.223 -197.211442)
		(size 0.508)
		(drill 0.254)
		(layers "F.Cu" "B.Cu")
		(net "GND")
	)
	(via
		(at 248.92 -436.88)
		(size 0.508)
		(drill 0.254)
		(layers "F.Cu" "B.Cu")
		(net "GND")
	)
	(via
		(at 222.616014 -282.189936)
		(size 0.508)
		(drill 0.254)
		(layers "F.Cu" "B.Cu")
		(net "GND")
	)
	(via
		(at 105.231946 -437.3245)
		(size 0.508)
		(drill 0.254)
		(layers "F.Cu" "B.Cu")
		(net "GND")
	)
	(via
		(at 152.4 -375.92)
		(size 0.508)
		(drill 0.254)
		(layers "F.Cu" "B.Cu")
		(net "GND")
	)
	(via
		(at 142.24 -228.6)
		(size 0.508)
		(drill 0.254)
		(layers "F.Cu" "B.Cu")
		(net "GND")
	)
	(via
		(at 147.32 -375.92)
		(size 0.508)
		(drill 0.254)
		(layers "F.Cu" "B.Cu")
		(net "GND")
	)
	(via
		(at 85.725 -212.4075)
		(size 0.508)
		(drill 0.254)
		(layers "F.Cu" "B.Cu")
		(net "GND")
	)
	(via
		(at 218.44 -360.68)
		(size 0.508)
		(drill 0.254)
		(layers "F.Cu" "B.Cu")
		(net "GND")
	)
	(via
		(at 157.48 -350.52)
		(size 0.508)
		(drill 0.254)
		(layers "F.Cu" "B.Cu")
		(net "GND")
	)
	(via
		(at 104.789986 -504.603004)
		(size 0.508)
		(drill 0.254)
		(layers "F.Cu" "B.Cu")
		(net "GND")
	)
	(via
		(at 91.44 -162.56)
		(size 0.508)
		(drill 0.254)
		(layers "F.Cu" "B.Cu")
		(net "GND")
	)
	(via
		(at 45.72 -431.8)
		(size 0.508)
		(drill 0.254)
		(layers "F.Cu" "B.Cu")
		(net "GND")
	)
	(via
		(at 39.96055 -310.8579)
		(size 0.508)
		(drill 0.254)
		(layers "F.Cu" "B.Cu")
		(net "GND")
	)
	(via
		(at 127 -152.4)
		(size 0.508)
		(drill 0.254)
		(layers "F.Cu" "B.Cu")
		(net "GND")
	)
	(via
		(at 147.32 -426.72)
		(size 0.508)
		(drill 0.254)
		(layers "F.Cu" "B.Cu")
		(net "GND")
	)
	(via
		(at 187.96 -96.52)
		(size 0.508)
		(drill 0.254)
		(layers "F.Cu" "B.Cu")
		(net "GND")
	)
	(via
		(at 262.103108 -122.838464)
		(size 0.508)
		(drill 0.254)
		(layers "F.Cu" "B.Cu")
		(net "GND")
	)
	(via
		(at 66.04 -396.24)
		(size 0.508)
		(drill 0.254)
		(layers "F.Cu" "B.Cu")
		(net "GND")
	)
	(via
		(at 259.08 -502.92)
		(size 0.508)
		(drill 0.254)
		(layers "F.Cu" "B.Cu")
		(net "GND")
	)
	(via
		(at 137.16 -436.88)
		(size 0.508)
		(drill 0.254)
		(layers "F.Cu" "B.Cu")
		(net "GND")
	)
	(via
		(at 254 -30.48)
		(size 0.508)
		(drill 0.254)
		(layers "F.Cu" "B.Cu")
		(net "GND")
	)
	(via
		(at 6.223 -283.2608)
		(size 0.508)
		(drill 0.254)
		(layers "F.Cu" "B.Cu")
		(net "GND")
	)
	(via
		(at 137.16 -325.12)
		(size 0.508)
		(drill 0.254)
		(layers "F.Cu" "B.Cu")
		(net "GND")
	)
	(via
		(at 233.68 -101.6)
		(size 0.508)
		(drill 0.254)
		(layers "F.Cu" "B.Cu")
		(net "GND")
	)
	(via
		(at 76.2 -254)
		(size 0.508)
		(drill 0.254)
		(layers "F.Cu" "B.Cu")
		(net "GND")
	)
	(via
		(at 17.145 -237.518194)
		(size 0.508)
		(drill 0.254)
		(layers "F.Cu" "B.Cu")
		(net "GND")
	)
	(via
		(at 193.04 -325.12)
		(size 0.508)
		(drill 0.254)
		(layers "F.Cu" "B.Cu")
		(net "GND")
	)
	(via
		(at 228.6 -152.4)
		(size 0.508)
		(drill 0.254)
		(layers "F.Cu" "B.Cu")
		(net "GND")
	)
	(via
		(at 96.52 -254)
		(size 0.508)
		(drill 0.254)
		(layers "F.Cu" "B.Cu")
		(net "GND")
	)
	(via
		(at 210.312 -51.562)
		(size 0.508)
		(drill 0.254)
		(layers "F.Cu" "B.Cu")
		(net "GND")
	)
	(via
		(at 142.24 -111.76)
		(size 0.508)
		(drill 0.254)
		(layers "F.Cu" "B.Cu")
		(net "GND")
	)
	(via
		(at 69.229986 -504.603004)
		(size 0.508)
		(drill 0.254)
		(layers "F.Cu" "B.Cu")
		(net "GND")
	)
	(via
		(at 114.304572 -1.397)
		(size 0.508)
		(drill 0.254)
		(layers "F.Cu" "B.Cu")
		(net "GND")
	)
	(via
		(at 203.2 -274.32)
		(size 0.508)
		(drill 0.254)
		(layers "F.Cu" "B.Cu")
		(net "GND")
	)
	(via
		(at 40.64 -132.08)
		(size 0.508)
		(drill 0.254)
		(layers "F.Cu" "B.Cu")
		(net "GND")
	)
	(via
		(at 162.56 -284.48)
		(size 0.508)
		(drill 0.254)
		(layers "F.Cu" "B.Cu")
		(net "GND")
	)
	(via
		(at 187.96 -193.04)
		(size 0.508)
		(drill 0.254)
		(layers "F.Cu" "B.Cu")
		(net "GND")
	)
	(via
		(at 66.04 -116.84)
		(size 0.508)
		(drill 0.254)
		(layers "F.Cu" "B.Cu")
		(net "GND")
	)
	(via
		(at 262.103108 -153.318464)
		(size 0.508)
		(drill 0.254)
		(layers "F.Cu" "B.Cu")
		(net "GND")
	)
	(via
		(at 18.203164 -498.17655)
		(size 0.508)
		(drill 0.254)
		(layers "F.Cu" "B.Cu")
		(net "GND")
	)
	(via
		(at 248.92 -10.16)
		(size 0.508)
		(drill 0.254)
		(layers "F.Cu" "B.Cu")
		(net "GND")
	)
	(via
		(at 75.0316 -297.85437)
		(size 0.508)
		(drill 0.254)
		(layers "F.Cu" "B.Cu")
		(net "GND")
	)
	(via
		(at 28.7528 -420.7002)
		(size 0.508)
		(drill 0.254)
		(layers "F.Cu" "B.Cu")
		(net "GND")
	)
	(via
		(at 152.4 -467.36)
		(size 0.508)
		(drill 0.254)
		(layers "F.Cu" "B.Cu")
		(net "GND")
	)
	(via
		(at 34.31413 -363.128052)
		(size 0.508)
		(drill 0.254)
		(layers "F.Cu" "B.Cu")
		(net "GND")
	)
	(via
		(at 193.04 -25.4)
		(size 0.508)
		(drill 0.254)
		(layers "F.Cu" "B.Cu")
		(net "GND")
	)
	(via
		(at 116.84 -218.44)
		(size 0.508)
		(drill 0.254)
		(layers "F.Cu" "B.Cu")
		(net "GND")
	)
	(via
		(at 160.669986 -504.603004)
		(size 0.508)
		(drill 0.254)
		(layers "F.Cu" "B.Cu")
		(net "GND")
	)
	(via
		(at 121.92 -76.2)
		(size 0.508)
		(drill 0.254)
		(layers "F.Cu" "B.Cu")
		(net "GND")
	)
	(via
		(at 259.08 -279.4)
		(size 0.508)
		(drill 0.254)
		(layers "F.Cu" "B.Cu")
		(net "GND")
	)
	(via
		(at 248.92 -264.16)
		(size 0.508)
		(drill 0.254)
		(layers "F.Cu" "B.Cu")
		(net "GND")
	)
	(via
		(at 60.96 -355.6)
		(size 0.508)
		(drill 0.254)
		(layers "F.Cu" "B.Cu")
		(net "GND")
	)
	(via
		(at 76.2 -30.48)
		(size 0.508)
		(drill 0.254)
		(layers "F.Cu" "B.Cu")
		(net "GND")
	)
	(via
		(at 6.223 -320.010028)
		(size 0.508)
		(drill 0.254)
		(layers "F.Cu" "B.Cu")
		(net "GND")
	)
	(via
		(at 6.223 -338.460842)
		(size 0.508)
		(drill 0.254)
		(layers "F.Cu" "B.Cu")
		(net "GND")
	)
	(via
		(at 106.68 -462.28)
		(size 0.508)
		(drill 0.254)
		(layers "F.Cu" "B.Cu")
		(net "GND")
	)
	(via
		(at 142.24 -101.6)
		(size 0.508)
		(drill 0.254)
		(layers "F.Cu" "B.Cu")
		(net "GND")
	)
	(via
		(at 98.7425 -424.942)
		(size 0.508)
		(drill 0.254)
		(layers "F.Cu" "B.Cu")
		(net "GND")
	)
	(via
		(at 231.789986 -504.603004)
		(size 0.508)
		(drill 0.254)
		(layers "F.Cu" "B.Cu")
		(net "GND")
	)
	(via
		(at 167.64 -447.04)
		(size 0.508)
		(drill 0.254)
		(layers "F.Cu" "B.Cu")
		(net "GND")
	)
	(via
		(at 27.72664 -26.8986)
		(size 0.508)
		(drill 0.254)
		(layers "F.Cu" "B.Cu")
		(net "GND")
	)
	(via
		(at 65.151 -477.52)
		(size 0.508)
		(drill 0.254)
		(layers "F.Cu" "B.Cu")
		(net "GND")
	)
	(via
		(at 162.56 -233.68)
		(size 0.508)
		(drill 0.254)
		(layers "F.Cu" "B.Cu")
		(net "GND")
	)
	(via
		(at 252.704092 -418.109908)
		(size 0.508)
		(drill 0.254)
		(layers "F.Cu" "B.Cu")
		(net "GND")
	)
	(via
		(at 198.12 -96.52)
		(size 0.508)
		(drill 0.254)
		(layers "F.Cu" "B.Cu")
		(net "GND")
	)
	(via
		(at 147.32 -360.68)
		(size 0.508)
		(drill 0.254)
		(layers "F.Cu" "B.Cu")
		(net "GND")
	)
	(via
		(at 25.4 -446.786)
		(size 0.508)
		(drill 0.254)
		(layers "F.Cu" "B.Cu")
		(net "GND")
	)
	(via
		(at 142.24 -467.36)
		(size 0.508)
		(drill 0.254)
		(layers "F.Cu" "B.Cu")
		(net "GND")
	)
	(via
		(at 254 -264.16)
		(size 0.508)
		(drill 0.254)
		(layers "F.Cu" "B.Cu")
		(net "GND")
	)
	(via
		(at 177.8 -314.96)
		(size 0.508)
		(drill 0.254)
		(layers "F.Cu" "B.Cu")
		(net "GND")
	)
	(via
		(at 24.9682 -216.0016)
		(size 0.508)
		(drill 0.254)
		(layers "F.Cu" "B.Cu")
		(net "GND")
	)
	(via
		(at 91.186 -98.806)
		(size 0.508)
		(drill 0.254)
		(layers "F.Cu" "B.Cu")
		(net "GND")
	)
	(via
		(at 162.56 -137.16)
		(size 0.508)
		(drill 0.254)
		(layers "F.Cu" "B.Cu")
		(net "GND")
	)
	(via
		(at 210.185 -461.518)
		(size 0.508)
		(drill 0.254)
		(layers "F.Cu" "B.Cu")
		(net "GND")
	)
	(via
		(at 101.6 -172.72)
		(size 0.508)
		(drill 0.254)
		(layers "F.Cu" "B.Cu")
		(net "GND")
	)
	(via
		(at 245.11 -385.064)
		(size 0.7112)
		(drill 0.4064)
		(layers "F.Cu" "B.Cu")
		(net "GND")
	)
	(via
		(at 172.72 -116.84)
		(size 0.508)
		(drill 0.254)
		(layers "F.Cu" "B.Cu")
		(net "GND")
	)
	(via
		(at 157.48 -330.2)
		(size 0.508)
		(drill 0.254)
		(layers "F.Cu" "B.Cu")
		(net "GND")
	)
	(via
		(at 103.251 -441.071)
		(size 0.508)
		(drill 0.254)
		(layers "F.Cu" "B.Cu")
		(net "GND")
	)
	(via
		(at 25.5524 -206.0702)
		(size 0.508)
		(drill 0.254)
		(layers "F.Cu" "B.Cu")
		(net "GND")
	)
	(via
		(at 152.4 -60.96)
		(size 0.508)
		(drill 0.254)
		(layers "F.Cu" "B.Cu")
		(net "GND")
	)
	(via
		(at 259.08 -208.28)
		(size 0.508)
		(drill 0.254)
		(layers "F.Cu" "B.Cu")
		(net "GND")
	)
	(via
		(at 167.64 -208.28)
		(size 0.508)
		(drill 0.254)
		(layers "F.Cu" "B.Cu")
		(net "GND")
	)
	(via
		(at 172.72 -365.76)
		(size 0.508)
		(drill 0.254)
		(layers "F.Cu" "B.Cu")
		(net "GND")
	)
	(via
		(at 86.233 -436.0545)
		(size 0.508)
		(drill 0.254)
		(layers "F.Cu" "B.Cu")
		(net "GND")
	)
	(via
		(at 44.828968 -58.700162)
		(size 0.508)
		(drill 0.254)
		(layers "F.Cu" "B.Cu")
		(net "GND")
	)
	(via
		(at 147.32 -304.8)
		(size 0.508)
		(drill 0.254)
		(layers "F.Cu" "B.Cu")
		(net "GND")
	)
	(via
		(at 27.664918 -38.147752)
		(size 0.508)
		(drill 0.254)
		(layers "F.Cu" "B.Cu")
		(net "GND")
	)
	(via
		(at 66.04 -325.12)
		(size 0.508)
		(drill 0.254)
		(layers "F.Cu" "B.Cu")
		(net "GND")
	)
	(via
		(at 222.616014 -174.39005)
		(size 0.508)
		(drill 0.254)
		(layers "F.Cu" "B.Cu")
		(net "GND")
	)
	(via
		(at 147.32 -472.44)
		(size 0.508)
		(drill 0.254)
		(layers "F.Cu" "B.Cu")
		(net "GND")
	)
	(via
		(at 259.08 -45.72)
		(size 0.508)
		(drill 0.254)
		(layers "F.Cu" "B.Cu")
		(net "GND")
	)
	(via
		(at 175.264572 -1.397)
		(size 0.508)
		(drill 0.254)
		(layers "F.Cu" "B.Cu")
		(net "GND")
	)
	(via
		(at 106.68 -45.72)
		(size 0.508)
		(drill 0.254)
		(layers "F.Cu" "B.Cu")
		(net "GND")
	)
	(via
		(at 242.57 -397.51)
		(size 0.7112)
		(drill 0.4064)
		(layers "F.Cu" "B.Cu")
		(net "GND")
	)
	(via
		(at 106.68 -482.6)
		(size 0.508)
		(drill 0.254)
		(layers "F.Cu" "B.Cu")
		(net "GND")
	)
	(via
		(at 228.6 -106.68)
		(size 0.508)
		(drill 0.254)
		(layers "F.Cu" "B.Cu")
		(net "GND")
	)
	(via
		(at 259.08 -345.44)
		(size 0.508)
		(drill 0.254)
		(layers "F.Cu" "B.Cu")
		(net "GND")
	)
	(via
		(at 127 -203.2)
		(size 0.508)
		(drill 0.254)
		(layers "F.Cu" "B.Cu")
		(net "GND")
	)
	(via
		(at 208.28 -335.28)
		(size 0.508)
		(drill 0.254)
		(layers "F.Cu" "B.Cu")
		(net "GND")
	)
	(via
		(at 60.96 -360.68)
		(size 0.508)
		(drill 0.254)
		(layers "F.Cu" "B.Cu")
		(net "GND")
	)
	(via
		(at 219.314014 -467.852252)
		(size 0.508)
		(drill 0.254)
		(layers "F.Cu" "B.Cu")
		(net "GND")
	)
	(via
		(at 233.68 -5.08)
		(size 0.508)
		(drill 0.254)
		(layers "F.Cu" "B.Cu")
		(net "GND")
	)
	(via
		(at 137.16 -487.68)
		(size 0.508)
		(drill 0.254)
		(layers "F.Cu" "B.Cu")
		(net "GND")
	)
	(via
		(at 187.96 -340.36)
		(size 0.508)
		(drill 0.254)
		(layers "F.Cu" "B.Cu")
		(net "GND")
	)
	(via
		(at 17.145 -446.503044)
		(size 0.508)
		(drill 0.254)
		(layers "F.Cu" "B.Cu")
		(net "GND")
	)
	(via
		(at 93.98 -306.578)
		(size 0.508)
		(drill 0.254)
		(layers "F.Cu" "B.Cu")
		(net "GND")
	)
	(via
		(at 259.08 -330.2)
		(size 0.508)
		(drill 0.254)
		(layers "F.Cu" "B.Cu")
		(net "GND")
	)
	(via
		(at 223.52 -203.2)
		(size 0.508)
		(drill 0.254)
		(layers "F.Cu" "B.Cu")
		(net "GND")
	)
	(via
		(at 226.3775 -342.519)
		(size 0.508)
		(drill 0.254)
		(layers "F.Cu" "B.Cu")
		(net "GND")
	)
	(via
		(at 203.2 -218.44)
		(size 0.508)
		(drill 0.254)
		(layers "F.Cu" "B.Cu")
		(net "GND")
	)
	(via
		(at 157.48 -86.36)
		(size 0.508)
		(drill 0.254)
		(layers "F.Cu" "B.Cu")
		(net "GND")
	)
	(via
		(at 187.96 -345.44)
		(size 0.508)
		(drill 0.254)
		(layers "F.Cu" "B.Cu")
		(net "GND")
	)
	(via
		(at 121.92 -55.88)
		(size 0.508)
		(drill 0.254)
		(layers "F.Cu" "B.Cu")
		(net "GND")
	)
	(via
		(at 86.36 -152.4)
		(size 0.508)
		(drill 0.254)
		(layers "F.Cu" "B.Cu")
		(net "GND")
	)
	(via
		(at 76.2 -330.2)
		(size 0.508)
		(drill 0.254)
		(layers "F.Cu" "B.Cu")
		(net "GND")
	)
	(via
		(at 127 -91.44)
		(size 0.508)
		(drill 0.254)
		(layers "F.Cu" "B.Cu")
		(net "GND")
	)
	(via
		(at 31.75 -79.248)
		(size 0.508)
		(drill 0.254)
		(layers "F.Cu" "B.Cu")
		(net "GND")
	)
	(via
		(at 233.68 -330.2)
		(size 0.508)
		(drill 0.254)
		(layers "F.Cu" "B.Cu")
		(net "GND")
	)
	(via
		(at 91.44 -5.08)
		(size 0.508)
		(drill 0.254)
		(layers "F.Cu" "B.Cu")
		(net "GND")
	)
	(via
		(at 243.84 -228.6)
		(size 0.508)
		(drill 0.254)
		(layers "F.Cu" "B.Cu")
		(net "GND")
	)
	(via
		(at 210.2866 -501.2436)
		(size 0.508)
		(drill 0.254)
		(layers "F.Cu" "B.Cu")
		(net "GND")
	)
	(via
		(at 20.32 -487.68)
		(size 0.508)
		(drill 0.254)
		(layers "F.Cu" "B.Cu")
		(net "GND")
	)
	(via
		(at 233.68 -218.44)
		(size 0.508)
		(drill 0.254)
		(layers "F.Cu" "B.Cu")
		(net "GND")
	)
	(via
		(at 142.24 -203.2)
		(size 0.508)
		(drill 0.254)
		(layers "F.Cu" "B.Cu")
		(net "GND")
	)
	(via
		(at 106.68 -30.48)
		(size 0.508)
		(drill 0.254)
		(layers "F.Cu" "B.Cu")
		(net "GND")
	)
	(via
		(at 79.502 -141.986)
		(size 0.508)
		(drill 0.254)
		(layers "F.Cu" "B.Cu")
		(net "GND")
	)
	(via
		(at 222.616014 -262.189976)
		(size 0.508)
		(drill 0.254)
		(layers "F.Cu" "B.Cu")
		(net "GND")
	)
	(via
		(at 195.386706 -496.767104)
		(size 0.508)
		(drill 0.254)
		(layers "F.Cu" "B.Cu")
		(net "GND")
	)
	(via
		(at 157.48 -147.32)
		(size 0.508)
		(drill 0.254)
		(layers "F.Cu" "B.Cu")
		(net "GND")
	)
	(via
		(at 243.84 -482.6)
		(size 0.508)
		(drill 0.254)
		(layers "F.Cu" "B.Cu")
		(net "GND")
	)
	(via
		(at 193.04 -365.76)
		(size 0.508)
		(drill 0.254)
		(layers "F.Cu" "B.Cu")
		(net "GND")
	)
	(via
		(at 213.36 -304.8)
		(size 0.508)
		(drill 0.254)
		(layers "F.Cu" "B.Cu")
		(net "GND")
	)
	(via
		(at 228.6 -10.16)
		(size 0.508)
		(drill 0.254)
		(layers "F.Cu" "B.Cu")
		(net "GND")
	)
	(via
		(at 36.449 -412.877)
		(size 0.508)
		(drill 0.254)
		(layers "F.Cu" "B.Cu")
		(net "GND")
	)
	(via
		(at 187.96 -198.12)
		(size 0.508)
		(drill 0.254)
		(layers "F.Cu" "B.Cu")
		(net "GND")
	)
	(via
		(at 182.88 -121.92)
		(size 0.508)
		(drill 0.254)
		(layers "F.Cu" "B.Cu")
		(net "GND")
	)
	(via
		(at 162.56 -487.68)
		(size 0.508)
		(drill 0.254)
		(layers "F.Cu" "B.Cu")
		(net "GND")
	)
	(via
		(at 86.36 -40.64)
		(size 0.508)
		(drill 0.254)
		(layers "F.Cu" "B.Cu")
		(net "GND")
	)
	(via
		(at 50.8 -365.76)
		(size 0.508)
		(drill 0.254)
		(layers "F.Cu" "B.Cu")
		(net "GND")
	)
	(via
		(at 172.72 -193.04)
		(size 0.508)
		(drill 0.254)
		(layers "F.Cu" "B.Cu")
		(net "GND")
	)
	(via
		(at 182.88 -502.92)
		(size 0.508)
		(drill 0.254)
		(layers "F.Cu" "B.Cu")
		(net "GND")
	)
	(via
		(at 259.08 -340.36)
		(size 0.508)
		(drill 0.254)
		(layers "F.Cu" "B.Cu")
		(net "GND")
	)
	(via
		(at 18.36039 -346.870782)
		(size 0.508)
		(drill 0.254)
		(layers "F.Cu" "B.Cu")
		(net "GND")
	)
	(via
		(at 198.12 -30.48)
		(size 0.508)
		(drill 0.254)
		(layers "F.Cu" "B.Cu")
		(net "GND")
	)
	(via
		(at 157.48 -309.88)
		(size 0.508)
		(drill 0.254)
		(layers "F.Cu" "B.Cu")
		(net "GND")
	)
	(via
		(at 81.28 -5.08)
		(size 0.508)
		(drill 0.254)
		(layers "F.Cu" "B.Cu")
		(net "GND")
	)
	(via
		(at 182.88 -30.48)
		(size 0.508)
		(drill 0.254)
		(layers "F.Cu" "B.Cu")
		(net "GND")
	)
	(via
		(at 157.48 -426.72)
		(size 0.508)
		(drill 0.254)
		(layers "F.Cu" "B.Cu")
		(net "GND")
	)
	(via
		(at 262.103108 -310.798464)
		(size 0.508)
		(drill 0.254)
		(layers "F.Cu" "B.Cu")
		(net "GND")
	)
	(via
		(at 132.08 -203.2)
		(size 0.508)
		(drill 0.254)
		(layers "F.Cu" "B.Cu")
		(net "GND")
	)
	(via
		(at 240.03 -397.51)
		(size 0.7112)
		(drill 0.4064)
		(layers "F.Cu" "B.Cu")
		(net "GND")
	)
	(via
		(at 262.103108 -346.358464)
		(size 0.508)
		(drill 0.254)
		(layers "F.Cu" "B.Cu")
		(net "GND")
	)
	(via
		(at 262.103108 -138.078464)
		(size 0.508)
		(drill 0.254)
		(layers "F.Cu" "B.Cu")
		(net "GND")
	)
	(via
		(at 228.6 -223.52)
		(size 0.508)
		(drill 0.254)
		(layers "F.Cu" "B.Cu")
		(net "GND")
	)
	(via
		(at 106.68 -320.04)
		(size 0.508)
		(drill 0.254)
		(layers "F.Cu" "B.Cu")
		(net "GND")
	)
	(via
		(at 96.52 -5.08)
		(size 0.508)
		(drill 0.254)
		(layers "F.Cu" "B.Cu")
		(net "GND")
	)
	(via
		(at 57.658 -345.313)
		(size 0.508)
		(drill 0.254)
		(layers "F.Cu" "B.Cu")
		(net "GND")
	)
	(via
		(at 1.397 -496.23599)
		(size 0.508)
		(drill 0.254)
		(layers "F.Cu" "B.Cu")
		(net "GND")
	)
	(via
		(at 6.223 -154.062176)
		(size 0.508)
		(drill 0.254)
		(layers "F.Cu" "B.Cu")
		(net "GND")
	)
	(via
		(at 71.12 -223.52)
		(size 0.508)
		(drill 0.254)
		(layers "F.Cu" "B.Cu")
		(net "GND")
	)
	(via
		(at 142.24 -381)
		(size 0.508)
		(drill 0.254)
		(layers "F.Cu" "B.Cu")
		(net "GND")
	)
	(via
		(at 262.103108 -209.198464)
		(size 0.508)
		(drill 0.254)
		(layers "F.Cu" "B.Cu")
		(net "GND")
	)
	(via
		(at 177.8 -335.28)
		(size 0.508)
		(drill 0.254)
		(layers "F.Cu" "B.Cu")
		(net "GND")
	)
	(via
		(at 121.92 -441.96)
		(size 0.508)
		(drill 0.254)
		(layers "F.Cu" "B.Cu")
		(net "GND")
	)
	(via
		(at 101.6 -40.64)
		(size 0.508)
		(drill 0.254)
		(layers "F.Cu" "B.Cu")
		(net "GND")
	)
	(via
		(at 172.72 -360.68)
		(size 0.508)
		(drill 0.254)
		(layers "F.Cu" "B.Cu")
		(net "GND")
	)
	(via
		(at 230.798116 -367.700814)
		(size 0.508)
		(drill 0.254)
		(layers "F.Cu" "B.Cu")
		(net "GND")
	)
	(via
		(at 147.32 -355.6)
		(size 0.508)
		(drill 0.254)
		(layers "F.Cu" "B.Cu")
		(net "GND")
	)
	(via
		(at 76.5302 -208.9277)
		(size 0.508)
		(drill 0.254)
		(layers "F.Cu" "B.Cu")
		(net "GND")
	)
	(via
		(at 254 -299.72)
		(size 0.508)
		(drill 0.254)
		(layers "F.Cu" "B.Cu")
		(net "GND")
	)
	(via
		(at 177.8 -274.32)
		(size 0.508)
		(drill 0.254)
		(layers "F.Cu" "B.Cu")
		(net "GND")
	)
	(via
		(at 18.415 -137.584942)
		(size 0.508)
		(drill 0.254)
		(layers "F.Cu" "B.Cu")
		(net "GND")
	)
	(via
		(at 248.92 -91.44)
		(size 0.508)
		(drill 0.254)
		(layers "F.Cu" "B.Cu")
		(net "GND")
	)
	(via
		(at 55.88 -182.88)
		(size 0.508)
		(drill 0.254)
		(layers "F.Cu" "B.Cu")
		(net "GND")
	)
	(via
		(at 83.824572 -1.397)
		(size 0.508)
		(drill 0.254)
		(layers "F.Cu" "B.Cu")
		(net "GND")
	)
	(via
		(at 142.24 -330.2)
		(size 0.508)
		(drill 0.254)
		(layers "F.Cu" "B.Cu")
		(net "GND")
	)
	(via
		(at 101.6 -243.84)
		(size 0.508)
		(drill 0.254)
		(layers "F.Cu" "B.Cu")
		(net "GND")
	)
	(via
		(at 34.31413 -382.399032)
		(size 0.508)
		(drill 0.254)
		(layers "F.Cu" "B.Cu")
		(net "GND")
	)
	(via
		(at 102.108 -432.054)
		(size 0.508)
		(drill 0.254)
		(layers "F.Cu" "B.Cu")
		(net "GND")
	)
	(via
		(at 142.24 -35.56)
		(size 0.508)
		(drill 0.254)
		(layers "F.Cu" "B.Cu")
		(net "GND")
	)
	(via
		(at 223.52 -325.12)
		(size 0.508)
		(drill 0.254)
		(layers "F.Cu" "B.Cu")
		(net "GND")
	)
	(via
		(at 96.774 -431.8)
		(size 0.508)
		(drill 0.254)
		(layers "F.Cu" "B.Cu")
		(net "GND")
	)
	(via
		(at 218.44 -477.52)
		(size 0.508)
		(drill 0.254)
		(layers "F.Cu" "B.Cu")
		(net "GND")
	)
	(via
		(at 222.616014 -161.589974)
		(size 0.508)
		(drill 0.254)
		(layers "F.Cu" "B.Cu")
		(net "GND")
	)
	(via
		(at 198.12 -15.24)
		(size 0.508)
		(drill 0.254)
		(layers "F.Cu" "B.Cu")
		(net "GND")
	)
	(via
		(at 162.56 -15.24)
		(size 0.508)
		(drill 0.254)
		(layers "F.Cu" "B.Cu")
		(net "GND")
	)
	(via
		(at 101.6 -187.96)
		(size 0.508)
		(drill 0.254)
		(layers "F.Cu" "B.Cu")
		(net "GND")
	)
	(via
		(at 60.96 -386.08)
		(size 0.508)
		(drill 0.254)
		(layers "F.Cu" "B.Cu")
		(net "GND")
	)
	(via
		(at 6.223 -152.3238)
		(size 0.508)
		(drill 0.254)
		(layers "F.Cu" "B.Cu")
		(net "GND")
	)
	(via
		(at 50.8 -274.32)
		(size 0.508)
		(drill 0.254)
		(layers "F.Cu" "B.Cu")
		(net "GND")
	)
	(via
		(at 142.24 -116.84)
		(size 0.508)
		(drill 0.254)
		(layers "F.Cu" "B.Cu")
		(net "GND")
	)
	(via
		(at 187.96 -462.28)
		(size 0.508)
		(drill 0.254)
		(layers "F.Cu" "B.Cu")
		(net "GND")
	)
	(via
		(at 193.04 -116.84)
		(size 0.508)
		(drill 0.254)
		(layers "F.Cu" "B.Cu")
		(net "GND")
	)
	(via
		(at 218.1352 -495.6302)
		(size 0.508)
		(drill 0.254)
		(layers "F.Cu" "B.Cu")
		(net "GND")
	)
	(via
		(at 33.401 -155.067)
		(size 0.508)
		(drill 0.254)
		(layers "F.Cu" "B.Cu")
		(net "GND")
	)
	(via
		(at 33.3756 -187.5028)
		(size 0.508)
		(drill 0.254)
		(layers "F.Cu" "B.Cu")
		(net "GND")
	)
	(via
		(at 6.223 -348.009972)
		(size 0.508)
		(drill 0.254)
		(layers "F.Cu" "B.Cu")
		(net "GND")
	)
	(via
		(at 142.24 -223.52)
		(size 0.508)
		(drill 0.254)
		(layers "F.Cu" "B.Cu")
		(net "GND")
	)
	(via
		(at 193.04 -502.92)
		(size 0.508)
		(drill 0.254)
		(layers "F.Cu" "B.Cu")
		(net "GND")
	)
	(via
		(at 254 -66.04)
		(size 0.508)
		(drill 0.254)
		(layers "F.Cu" "B.Cu")
		(net "GND")
	)
	(via
		(at 39.0398 -414.9344)
		(size 0.508)
		(drill 0.254)
		(layers "F.Cu" "B.Cu")
		(net "GND")
	)
	(via
		(at 4.191 -432.435)
		(size 0.508)
		(drill 0.254)
		(layers "F.Cu" "B.Cu")
		(net "GND")
	)
	(via
		(at 116.84 -228.6)
		(size 0.508)
		(drill 0.254)
		(layers "F.Cu" "B.Cu")
		(net "GND")
	)
	(via
		(at 34.275014 -274.479004)
		(size 0.508)
		(drill 0.254)
		(layers "F.Cu" "B.Cu")
		(net "GND")
	)
	(via
		(at 50.8 -386.08)
		(size 0.508)
		(drill 0.254)
		(layers "F.Cu" "B.Cu")
		(net "GND")
	)
	(via
		(at 221.986348 -428.117)
		(size 0.508)
		(drill 0.254)
		(layers "F.Cu" "B.Cu")
		(net "GND")
	)
	(via
		(at 219.274898 -171.478956)
		(size 0.508)
		(drill 0.254)
		(layers "F.Cu" "B.Cu")
		(net "GND")
	)
	(via
		(at 15.621 -173.355)
		(size 0.508)
		(drill 0.254)
		(layers "F.Cu" "B.Cu")
		(net "GND")
	)
	(via
		(at 101.6 -121.92)
		(size 0.508)
		(drill 0.254)
		(layers "F.Cu" "B.Cu")
		(net "GND")
	)
	(via
		(at 175.909986 -504.603004)
		(size 0.508)
		(drill 0.254)
		(layers "F.Cu" "B.Cu")
		(net "GND")
	)
	(via
		(at 162.56 -452.12)
		(size 0.508)
		(drill 0.254)
		(layers "F.Cu" "B.Cu")
		(net "GND")
	)
	(via
		(at 15.7226 -148.4122)
		(size 0.508)
		(drill 0.254)
		(layers "F.Cu" "B.Cu")
		(net "GND")
	)
	(via
		(at 193.04 -50.8)
		(size 0.508)
		(drill 0.254)
		(layers "F.Cu" "B.Cu")
		(net "GND")
	)
	(via
		(at 207.10525 -195.1355)
		(size 0.508)
		(drill 0.254)
		(layers "F.Cu" "B.Cu")
		(net "GND")
	)
	(via
		(at 111.76 -213.36)
		(size 0.508)
		(drill 0.254)
		(layers "F.Cu" "B.Cu")
		(net "GND")
	)
	(via
		(at 213.36 -320.04)
		(size 0.508)
		(drill 0.254)
		(layers "F.Cu" "B.Cu")
		(net "GND")
	)
	(via
		(at 259.08 -487.68)
		(size 0.508)
		(drill 0.254)
		(layers "F.Cu" "B.Cu")
		(net "GND")
	)
	(via
		(at 30.0355 -318.0207)
		(size 0.508)
		(drill 0.254)
		(layers "F.Cu" "B.Cu")
		(net "GND")
	)
	(via
		(at 16.383 -401.701)
		(size 0.508)
		(drill 0.254)
		(layers "F.Cu" "B.Cu")
		(net "GND")
	)
	(via
		(at 95.377 -209.423)
		(size 0.508)
		(drill 0.254)
		(layers "F.Cu" "B.Cu")
		(net "GND")
	)
	(via
		(at 24.384 -334.01)
		(size 0.508)
		(drill 0.254)
		(layers "F.Cu" "B.Cu")
		(net "GND")
	)
	(via
		(at 142.24 -264.16)
		(size 0.508)
		(drill 0.254)
		(layers "F.Cu" "B.Cu")
		(net "GND")
	)
	(via
		(at 6.223 -287.87471)
		(size 0.508)
		(drill 0.254)
		(layers "F.Cu" "B.Cu")
		(net "GND")
	)
	(via
		(at 245.872 -357.886)
		(size 0.508)
		(drill 0.254)
		(layers "F.Cu" "B.Cu")
		(net "GND")
	)
	(via
		(at 177.8 -187.96)
		(size 0.508)
		(drill 0.254)
		(layers "F.Cu" "B.Cu")
		(net "GND")
	)
	(via
		(at 172.72 -228.6)
		(size 0.508)
		(drill 0.254)
		(layers "F.Cu" "B.Cu")
		(net "GND")
	)
	(via
		(at 116.84 -381)
		(size 0.508)
		(drill 0.254)
		(layers "F.Cu" "B.Cu")
		(net "GND")
	)
	(via
		(at 208.026 -453.39)
		(size 0.508)
		(drill 0.254)
		(layers "F.Cu" "B.Cu")
		(net "GND")
	)
	(via
		(at 157.48 -365.76)
		(size 0.508)
		(drill 0.254)
		(layers "F.Cu" "B.Cu")
		(net "GND")
	)
	(via
		(at 242.57 -385.064)
		(size 0.7112)
		(drill 0.4064)
		(layers "F.Cu" "B.Cu")
		(net "GND")
	)
	(via
		(at 6.223 -411.489906)
		(size 0.508)
		(drill 0.254)
		(layers "F.Cu" "B.Cu")
		(net "GND")
	)
	(via
		(at 116.84 -472.44)
		(size 0.508)
		(drill 0.254)
		(layers "F.Cu" "B.Cu")
		(net "GND")
	)
	(via
		(at 116.84 -101.6)
		(size 0.508)
		(drill 0.254)
		(layers "F.Cu" "B.Cu")
		(net "GND")
	)
	(via
		(at 139.704572 -1.397)
		(size 0.508)
		(drill 0.254)
		(layers "F.Cu" "B.Cu")
		(net "GND")
	)
	(via
		(at 75.65136 -204.356208)
		(size 0.508)
		(drill 0.254)
		(layers "F.Cu" "B.Cu")
		(net "GND")
	)
	(via
		(at 96.52 -264.16)
		(size 0.508)
		(drill 0.254)
		(layers "F.Cu" "B.Cu")
		(net "GND")
	)
	(via
		(at 203.2 -462.28)
		(size 0.508)
		(drill 0.254)
		(layers "F.Cu" "B.Cu")
		(net "GND")
	)
	(via
		(at 16.0274 -200.3552)
		(size 0.508)
		(drill 0.254)
		(layers "F.Cu" "B.Cu")
		(net "GND")
	)
	(via
		(at 92.583 -212.217)
		(size 0.508)
		(drill 0.254)
		(layers "F.Cu" "B.Cu")
		(net "GND")
	)
	(via
		(at 167.64 -172.72)
		(size 0.508)
		(drill 0.254)
		(layers "F.Cu" "B.Cu")
		(net "GND")
	)
	(via
		(at 228.6 -121.92)
		(size 0.508)
		(drill 0.254)
		(layers "F.Cu" "B.Cu")
		(net "GND")
	)
	(via
		(at 60.96 -330.2)
		(size 0.508)
		(drill 0.254)
		(layers "F.Cu" "B.Cu")
		(net "GND")
	)
	(via
		(at 81.28 -279.4)
		(size 0.508)
		(drill 0.254)
		(layers "F.Cu" "B.Cu")
		(net "GND")
	)
	(via
		(at 55.88 -330.2)
		(size 0.508)
		(drill 0.254)
		(layers "F.Cu" "B.Cu")
		(net "GND")
	)
	(via
		(at 248.92 -30.48)
		(size 0.508)
		(drill 0.254)
		(layers "F.Cu" "B.Cu")
		(net "GND")
	)
	(via
		(at 111.76 -106.68)
		(size 0.508)
		(drill 0.254)
		(layers "F.Cu" "B.Cu")
		(net "GND")
	)
	(via
		(at 121.92 -304.8)
		(size 0.508)
		(drill 0.254)
		(layers "F.Cu" "B.Cu")
		(net "GND")
	)
	(via
		(at 222.616014 -156.789882)
		(size 0.508)
		(drill 0.254)
		(layers "F.Cu" "B.Cu")
		(net "GND")
	)
	(via
		(at 60.96 -375.92)
		(size 0.508)
		(drill 0.254)
		(layers "F.Cu" "B.Cu")
		(net "GND")
	)
	(via
		(at 24.384 -22.60981)
		(size 0.508)
		(drill 0.254)
		(layers "F.Cu" "B.Cu")
		(net "GND")
	)
	(via
		(at 32.11703 -85.9282)
		(size 0.508)
		(drill 0.254)
		(layers "F.Cu" "B.Cu")
		(net "GND")
	)
	(via
		(at 132.08 -177.8)
		(size 0.508)
		(drill 0.254)
		(layers "F.Cu" "B.Cu")
		(net "GND")
	)
	(via
		(at 208.28 -106.68)
		(size 0.508)
		(drill 0.254)
		(layers "F.Cu" "B.Cu")
		(net "GND")
	)
	(via
		(at 1.397 -25.649428)
		(size 0.508)
		(drill 0.254)
		(layers "F.Cu" "B.Cu")
		(net "GND")
	)
	(via
		(at 71.12 -299.72)
		(size 0.508)
		(drill 0.254)
		(layers "F.Cu" "B.Cu")
		(net "GND")
	)
	(via
		(at 15.621 -189.992)
		(size 0.508)
		(drill 0.254)
		(layers "F.Cu" "B.Cu")
		(net "GND")
	)
	(via
		(at 223.52 -223.52)
		(size 0.508)
		(drill 0.254)
		(layers "F.Cu" "B.Cu")
		(net "GND")
	)
	(via
		(at 147.32 -20.32)
		(size 0.508)
		(drill 0.254)
		(layers "F.Cu" "B.Cu")
		(net "GND")
	)
	(via
		(at 101.6 -274.32)
		(size 0.508)
		(drill 0.254)
		(layers "F.Cu" "B.Cu")
		(net "GND")
	)
	(via
		(at 17.272 -419.481)
		(size 0.508)
		(drill 0.254)
		(layers "F.Cu" "B.Cu")
		(net "GND")
	)
	(via
		(at 157.48 -447.04)
		(size 0.508)
		(drill 0.254)
		(layers "F.Cu" "B.Cu")
		(net "GND")
	)
	(via
		(at 71.12 -5.08)
		(size 0.508)
		(drill 0.254)
		(layers "F.Cu" "B.Cu")
		(net "GND")
	)
	(via
		(at 101.6 -462.28)
		(size 0.508)
		(drill 0.254)
		(layers "F.Cu" "B.Cu")
		(net "GND")
	)
	(via
		(at 76.2 -279.4)
		(size 0.508)
		(drill 0.254)
		(layers "F.Cu" "B.Cu")
		(net "GND")
	)
	(via
		(at 74.2188 -428.9806)
		(size 0.508)
		(drill 0.254)
		(layers "F.Cu" "B.Cu")
		(net "GND")
	)
	(via
		(at 71.12 -411.48)
		(size 0.508)
		(drill 0.254)
		(layers "F.Cu" "B.Cu")
		(net "GND")
	)
	(via
		(at 81.28 -254)
		(size 0.508)
		(drill 0.254)
		(layers "F.Cu" "B.Cu")
		(net "GND")
	)
	(via
		(at 18.415 -141.394942)
		(size 0.508)
		(drill 0.254)
		(layers "F.Cu" "B.Cu")
		(net "GND")
	)
	(via
		(at 6.223 -157.249622)
		(size 0.508)
		(drill 0.254)
		(layers "F.Cu" "B.Cu")
		(net "GND")
	)
	(via
		(at 92.583 -307.975)
		(size 0.508)
		(drill 0.254)
		(layers "F.Cu" "B.Cu")
		(net "GND")
	)
	(via
		(at 48.3616 -371.484144)
		(size 0.508)
		(drill 0.254)
		(layers "F.Cu" "B.Cu")
		(net "GND")
	)
	(via
		(at 234.0356 -59.690508)
		(size 0.508)
		(drill 0.254)
		(layers "F.Cu" "B.Cu")
		(net "GND")
	)
	(via
		(at 132.08 -228.6)
		(size 0.508)
		(drill 0.254)
		(layers "F.Cu" "B.Cu")
		(net "GND")
	)
	(via
		(at 254 -81.28)
		(size 0.508)
		(drill 0.254)
		(layers "F.Cu" "B.Cu")
		(net "GND")
	)
	(via
		(at 37.61613 -58.589926)
		(size 0.508)
		(drill 0.254)
		(layers "F.Cu" "B.Cu")
		(net "GND")
	)
	(via
		(at 1.397 -5.329428)
		(size 0.508)
		(drill 0.254)
		(layers "F.Cu" "B.Cu")
		(net "GND")
	)
	(via
		(at 243.84 -259.08)
		(size 0.508)
		(drill 0.254)
		(layers "F.Cu" "B.Cu")
		(net "GND")
	)
	(via
		(at 259.08 -86.36)
		(size 0.508)
		(drill 0.254)
		(layers "F.Cu" "B.Cu")
		(net "GND")
	)
	(via
		(at 222.4278 -300.2026)
		(size 0.508)
		(drill 0.254)
		(layers "F.Cu" "B.Cu")
		(net "GND")
	)
	(via
		(at 9.7028 -478.4852)
		(size 0.508)
		(drill 0.254)
		(layers "F.Cu" "B.Cu")
		(net "GND")
	)
	(via
		(at 43.58513 -265.415014)
		(size 0.508)
		(drill 0.254)
		(layers "F.Cu" "B.Cu")
		(net "GND")
	)
	(via
		(at 137.16 -497.84)
		(size 0.508)
		(drill 0.254)
		(layers "F.Cu" "B.Cu")
		(net "GND")
	)
	(via
		(at 1.397 -264.235946)
		(size 0.508)
		(drill 0.254)
		(layers "F.Cu" "B.Cu")
		(net "GND")
	)
	(via
		(at 208.28 -375.92)
		(size 0.508)
		(drill 0.254)
		(layers "F.Cu" "B.Cu")
		(net "GND")
	)
	(via
		(at 48.4124 -265.487404)
		(size 0.508)
		(drill 0.254)
		(layers "F.Cu" "B.Cu")
		(net "GND")
	)
	(via
		(at 198.12 -86.36)
		(size 0.508)
		(drill 0.254)
		(layers "F.Cu" "B.Cu")
		(net "GND")
	)
	(via
		(at 19.431 -168.91)
		(size 0.508)
		(drill 0.254)
		(layers "F.Cu" "B.Cu")
		(net "GND")
	)
	(via
		(at 218.44 -416.56)
		(size 0.508)
		(drill 0.254)
		(layers "F.Cu" "B.Cu")
		(net "GND")
	)
	(via
		(at 96.52 -167.64)
		(size 0.508)
		(drill 0.254)
		(layers "F.Cu" "B.Cu")
		(net "GND")
	)
	(via
		(at 162.56 -152.4)
		(size 0.508)
		(drill 0.254)
		(layers "F.Cu" "B.Cu")
		(net "GND")
	)
	(via
		(at 27.686 -226.60102)
		(size 0.508)
		(drill 0.254)
		(layers "F.Cu" "B.Cu")
		(net "GND")
	)
	(via
		(at 81.28 -20.32)
		(size 0.508)
		(drill 0.254)
		(layers "F.Cu" "B.Cu")
		(net "GND")
	)
	(via
		(at 55.88 -116.84)
		(size 0.508)
		(drill 0.254)
		(layers "F.Cu" "B.Cu")
		(net "GND")
	)
	(via
		(at 147.32 -152.4)
		(size 0.508)
		(drill 0.254)
		(layers "F.Cu" "B.Cu")
		(net "GND")
	)
	(via
		(at 75.565 -149.352)
		(size 0.508)
		(drill 0.254)
		(layers "F.Cu" "B.Cu")
		(net "GND")
	)
	(via
		(at 121.92 -86.36)
		(size 0.508)
		(drill 0.254)
		(layers "F.Cu" "B.Cu")
		(net "GND")
	)
	(via
		(at 37.61613 -470.590118)
		(size 0.508)
		(drill 0.254)
		(layers "F.Cu" "B.Cu")
		(net "GND")
	)
	(via
		(at 40.64 -436.88)
		(size 0.508)
		(drill 0.254)
		(layers "F.Cu" "B.Cu")
		(net "GND")
	)
	(via
		(at 95.377 -104.394)
		(size 0.508)
		(drill 0.254)
		(layers "F.Cu" "B.Cu")
		(net "GND")
	)
	(via
		(at 208.28 -269.24)
		(size 0.508)
		(drill 0.254)
		(layers "F.Cu" "B.Cu")
		(net "GND")
	)
	(via
		(at 222.0468 -290.576)
		(size 0.508)
		(drill 0.254)
		(layers "F.Cu" "B.Cu")
		(net "GND")
	)
	(via
		(at 24.384 -425.010072)
		(size 0.508)
		(drill 0.254)
		(layers "F.Cu" "B.Cu")
		(net "GND")
	)
	(via
		(at 259.08 -147.32)
		(size 0.508)
		(drill 0.254)
		(layers "F.Cu" "B.Cu")
		(net "GND")
	)
	(via
		(at 24.0538 -152.3492)
		(size 0.508)
		(drill 0.254)
		(layers "F.Cu" "B.Cu")
		(net "GND")
	)
	(via
		(at 152.4 -238.76)
		(size 0.508)
		(drill 0.254)
		(layers "F.Cu" "B.Cu")
		(net "GND")
	)
	(via
		(at 177.8 -172.72)
		(size 0.508)
		(drill 0.254)
		(layers "F.Cu" "B.Cu")
		(net "GND")
	)
	(via
		(at 213.36 -330.2)
		(size 0.508)
		(drill 0.254)
		(layers "F.Cu" "B.Cu")
		(net "GND")
	)
	(via
		(at 43.942 -285.369)
		(size 0.508)
		(drill 0.254)
		(layers "F.Cu" "B.Cu")
		(net "GND")
	)
	(via
		(at 248.92 -431.8)
		(size 0.508)
		(drill 0.254)
		(layers "F.Cu" "B.Cu")
		(net "GND")
	)
	(via
		(at 116.84 -335.28)
		(size 0.508)
		(drill 0.254)
		(layers "F.Cu" "B.Cu")
		(net "GND")
	)
	(via
		(at 157.48 -193.04)
		(size 0.508)
		(drill 0.254)
		(layers "F.Cu" "B.Cu")
		(net "GND")
	)
	(via
		(at 95.377 -302.387)
		(size 0.508)
		(drill 0.254)
		(layers "F.Cu" "B.Cu")
		(net "GND")
	)
	(via
		(at 94.234 -296.672)
		(size 0.508)
		(drill 0.254)
		(layers "F.Cu" "B.Cu")
		(net "GND")
	)
	(via
		(at 238.76 -487.68)
		(size 0.508)
		(drill 0.254)
		(layers "F.Cu" "B.Cu")
		(net "GND")
	)
	(via
		(at 24.384 -439.410094)
		(size 0.508)
		(drill 0.254)
		(layers "F.Cu" "B.Cu")
		(net "GND")
	)
	(via
		(at 233.68 -203.2)
		(size 0.508)
		(drill 0.254)
		(layers "F.Cu" "B.Cu")
		(net "GND")
	)
	(via
		(at 137.16 -50.8)
		(size 0.508)
		(drill 0.254)
		(layers "F.Cu" "B.Cu")
		(net "GND")
	)
	(via
		(at 228.6 -228.6)
		(size 0.508)
		(drill 0.254)
		(layers "F.Cu" "B.Cu")
		(net "GND")
	)
	(via
		(at 52.22875 -9.8425)
		(size 0.508)
		(drill 0.254)
		(layers "F.Cu" "B.Cu")
		(net "GND")
	)
	(via
		(at 111.76 -365.76)
		(size 0.508)
		(drill 0.254)
		(layers "F.Cu" "B.Cu")
		(net "GND")
	)
	(via
		(at 91.44 -172.72)
		(size 0.508)
		(drill 0.254)
		(layers "F.Cu" "B.Cu")
		(net "GND")
	)
	(via
		(at 4.191 -160.366202)
		(size 0.508)
		(drill 0.254)
		(layers "F.Cu" "B.Cu")
		(net "GND")
	)
	(via
		(at 71.12 -248.92)
		(size 0.508)
		(drill 0.254)
		(layers "F.Cu" "B.Cu")
		(net "GND")
	)
	(via
		(at 96.774 -102.997)
		(size 0.508)
		(drill 0.254)
		(layers "F.Cu" "B.Cu")
		(net "GND")
	)
	(via
		(at 137.16 -248.92)
		(size 0.508)
		(drill 0.254)
		(layers "F.Cu" "B.Cu")
		(net "GND")
	)
	(via
		(at 127 -304.8)
		(size 0.508)
		(drill 0.254)
		(layers "F.Cu" "B.Cu")
		(net "GND")
	)
	(via
		(at 116.84 -370.84)
		(size 0.508)
		(drill 0.254)
		(layers "F.Cu" "B.Cu")
		(net "GND")
	)
	(via
		(at 49.43348 -472.261692)
		(size 0.508)
		(drill 0.254)
		(layers "F.Cu" "B.Cu")
		(net "GND")
	)
	(via
		(at 24.384 -344.41003)
		(size 0.508)
		(drill 0.254)
		(layers "F.Cu" "B.Cu")
		(net "GND")
	)
	(via
		(at 93.98 -433.197)
		(size 0.508)
		(drill 0.254)
		(layers "F.Cu" "B.Cu")
		(net "GND")
	)
	(via
		(at 162.56 -91.44)
		(size 0.508)
		(drill 0.254)
		(layers "F.Cu" "B.Cu")
		(net "GND")
	)
	(via
		(at 182.88 -76.2)
		(size 0.508)
		(drill 0.254)
		(layers "F.Cu" "B.Cu")
		(net "GND")
	)
	(via
		(at 43.58513 -463.79511)
		(size 0.508)
		(drill 0.254)
		(layers "F.Cu" "B.Cu")
		(net "GND")
	)
	(via
		(at 81.28 -162.56)
		(size 0.508)
		(drill 0.254)
		(layers "F.Cu" "B.Cu")
		(net "GND")
	)
	(via
		(at 187.96 -162.56)
		(size 0.508)
		(drill 0.254)
		(layers "F.Cu" "B.Cu")
		(net "GND")
	)
	(via
		(at 203.2 -20.32)
		(size 0.508)
		(drill 0.254)
		(layers "F.Cu" "B.Cu")
		(net "GND")
	)
	(via
		(at 218.44 -20.32)
		(size 0.508)
		(drill 0.254)
		(layers "F.Cu" "B.Cu")
		(net "GND")
	)
	(via
		(at 233.68 -264.16)
		(size 0.508)
		(drill 0.254)
		(layers "F.Cu" "B.Cu")
		(net "GND")
	)
	(via
		(at 6.223 -318.2747)
		(size 0.508)
		(drill 0.254)
		(layers "F.Cu" "B.Cu")
		(net "GND")
	)
	(via
		(at 198.12 -233.68)
		(size 0.508)
		(drill 0.254)
		(layers "F.Cu" "B.Cu")
		(net "GND")
	)
	(via
		(at 24.384 -243.810028)
		(size 0.508)
		(drill 0.254)
		(layers "F.Cu" "B.Cu")
		(net "GND")
	)
	(via
		(at 76.2 -25.4)
		(size 0.508)
		(drill 0.254)
		(layers "F.Cu" "B.Cu")
		(net "GND")
	)
	(via
		(at 34.30651 -466.201252)
		(size 0.508)
		(drill 0.254)
		(layers "F.Cu" "B.Cu")
		(net "GND")
	)
	(via
		(at 45.798232 -470.699084)
		(size 0.508)
		(drill 0.254)
		(layers "F.Cu" "B.Cu")
		(net "GND")
	)
	(via
		(at 6.223 -201.073004)
		(size 0.508)
		(drill 0.254)
		(layers "F.Cu" "B.Cu")
		(net "GND")
	)
	(via
		(at 81.28 -40.64)
		(size 0.508)
		(drill 0.254)
		(layers "F.Cu" "B.Cu")
		(net "GND")
	)
	(via
		(at 106.68 -152.4)
		(size 0.508)
		(drill 0.254)
		(layers "F.Cu" "B.Cu")
		(net "GND")
	)
	(via
		(at 81.28 -182.88)
		(size 0.508)
		(drill 0.254)
		(layers "F.Cu" "B.Cu")
		(net "GND")
	)
	(via
		(at 121.92 -238.76)
		(size 0.508)
		(drill 0.254)
		(layers "F.Cu" "B.Cu")
		(net "GND")
	)
	(via
		(at 66.04 -421.64)
		(size 0.508)
		(drill 0.254)
		(layers "F.Cu" "B.Cu")
		(net "GND")
	)
	(via
		(at 157.48 -304.8)
		(size 0.508)
		(drill 0.254)
		(layers "F.Cu" "B.Cu")
		(net "GND")
	)
	(via
		(at 167.64 -30.48)
		(size 0.508)
		(drill 0.254)
		(layers "F.Cu" "B.Cu")
		(net "GND")
	)
	(via
		(at 93.98 -303.784)
		(size 0.508)
		(drill 0.254)
		(layers "F.Cu" "B.Cu")
		(net "GND")
	)
	(via
		(at 172.72 -482.6)
		(size 0.508)
		(drill 0.254)
		(layers "F.Cu" "B.Cu")
		(net "GND")
	)
	(via
		(at 91.44 -345.44)
		(size 0.508)
		(drill 0.254)
		(layers "F.Cu" "B.Cu")
		(net "GND")
	)
	(via
		(at 127 -502.92)
		(size 0.508)
		(drill 0.254)
		(layers "F.Cu" "B.Cu")
		(net "GND")
	)
	(via
		(at 94.080838 -111.536988)
		(size 0.508)
		(drill 0.254)
		(layers "F.Cu" "B.Cu")
		(net "GND")
	)
	(via
		(at 233.68 -325.12)
		(size 0.508)
		(drill 0.254)
		(layers "F.Cu" "B.Cu")
		(net "GND")
	)
	(via
		(at 111.76 -264.16)
		(size 0.508)
		(drill 0.254)
		(layers "F.Cu" "B.Cu")
		(net "GND")
	)
	(via
		(at 121.92 -81.28)
		(size 0.508)
		(drill 0.254)
		(layers "F.Cu" "B.Cu")
		(net "GND")
	)
	(via
		(at 91.44 -492.76)
		(size 0.508)
		(drill 0.254)
		(layers "F.Cu" "B.Cu")
		(net "GND")
	)
	(via
		(at 152.4 -152.4)
		(size 0.508)
		(drill 0.254)
		(layers "F.Cu" "B.Cu")
		(net "GND")
	)
	(via
		(at 27.432 -412.115)
		(size 0.508)
		(drill 0.254)
		(layers "F.Cu" "B.Cu")
		(net "GND")
	)
	(via
		(at 45.72 -20.32)
		(size 0.508)
		(drill 0.254)
		(layers "F.Cu" "B.Cu")
		(net "GND")
	)
	(via
		(at 6.223 -194.01155)
		(size 0.508)
		(drill 0.254)
		(layers "F.Cu" "B.Cu")
		(net "GND")
	)
	(via
		(at 10.16 -60.96)
		(size 0.508)
		(drill 0.254)
		(layers "F.Cu" "B.Cu")
		(net "GND")
	)
	(via
		(at 152.4 -381)
		(size 0.508)
		(drill 0.254)
		(layers "F.Cu" "B.Cu")
		(net "GND")
	)
	(via
		(at 228.6 -335.28)
		(size 0.508)
		(drill 0.254)
		(layers "F.Cu" "B.Cu")
		(net "GND")
	)
	(via
		(at 218.44 -340.36)
		(size 0.508)
		(drill 0.254)
		(layers "F.Cu" "B.Cu")
		(net "GND")
	)
	(via
		(at 34.31413 -71.780908)
		(size 0.508)
		(drill 0.254)
		(layers "F.Cu" "B.Cu")
		(net "GND")
	)
	(via
		(at 45.72 -482.6)
		(size 0.508)
		(drill 0.254)
		(layers "F.Cu" "B.Cu")
		(net "GND")
	)
	(via
		(at 193.04 -309.88)
		(size 0.508)
		(drill 0.254)
		(layers "F.Cu" "B.Cu")
		(net "GND")
	)
	(via
		(at 6.223 -426.042836)
		(size 0.508)
		(drill 0.254)
		(layers "F.Cu" "B.Cu")
		(net "GND")
	)
	(via
		(at 127 -452.12)
		(size 0.508)
		(drill 0.254)
		(layers "F.Cu" "B.Cu")
		(net "GND")
	)
	(via
		(at 37.61613 -64.989964)
		(size 0.508)
		(drill 0.254)
		(layers "F.Cu" "B.Cu")
		(net "GND")
	)
	(via
		(at 219.279978 -68.498212)
		(size 0.508)
		(drill 0.254)
		(layers "F.Cu" "B.Cu")
		(net "GND")
	)
	(via
		(at 228.6 -314.96)
		(size 0.508)
		(drill 0.254)
		(layers "F.Cu" "B.Cu")
		(net "GND")
	)
	(via
		(at 18.3134 -390.2456)
		(size 0.508)
		(drill 0.254)
		(layers "F.Cu" "B.Cu")
		(net "GND")
	)
	(via
		(at 116.84 -121.92)
		(size 0.508)
		(drill 0.254)
		(layers "F.Cu" "B.Cu")
		(net "GND")
	)
	(via
		(at 198.12 -76.2)
		(size 0.508)
		(drill 0.254)
		(layers "F.Cu" "B.Cu")
		(net "GND")
	)
	(via
		(at 31.5214 -299.98035)
		(size 0.508)
		(drill 0.254)
		(layers "F.Cu" "B.Cu")
		(net "GND")
	)
	(via
		(at 121.92 -116.84)
		(size 0.508)
		(drill 0.254)
		(layers "F.Cu" "B.Cu")
		(net "GND")
	)
	(via
		(at 142.24 -447.04)
		(size 0.508)
		(drill 0.254)
		(layers "F.Cu" "B.Cu")
		(net "GND")
	)
	(via
		(at 96.52 -243.84)
		(size 0.508)
		(drill 0.254)
		(layers "F.Cu" "B.Cu")
		(net "GND")
	)
	(via
		(at 6.223 -416.394392)
		(size 0.508)
		(drill 0.254)
		(layers "F.Cu" "B.Cu")
		(net "GND")
	)
	(via
		(at 187.96 -5.08)
		(size 0.508)
		(drill 0.254)
		(layers "F.Cu" "B.Cu")
		(net "GND")
	)
	(via
		(at 86.36 -350.52)
		(size 0.508)
		(drill 0.254)
		(layers "F.Cu" "B.Cu")
		(net "GND")
	)
	(via
		(at 233.68 -406.4)
		(size 0.508)
		(drill 0.254)
		(layers "F.Cu" "B.Cu")
		(net "GND")
	)
	(via
		(at 86.36 -198.12)
		(size 0.508)
		(drill 0.254)
		(layers "F.Cu" "B.Cu")
		(net "GND")
	)
	(via
		(at 137.16 -299.72)
		(size 0.508)
		(drill 0.254)
		(layers "F.Cu" "B.Cu")
		(net "GND")
	)
	(via
		(at 222.616014 -385.189984)
		(size 0.508)
		(drill 0.254)
		(layers "F.Cu" "B.Cu")
		(net "GND")
	)
	(via
		(at 220.984572 -1.397)
		(size 0.508)
		(drill 0.254)
		(layers "F.Cu" "B.Cu")
		(net "GND")
	)
	(via
		(at 18.3134 -383.5146)
		(size 0.508)
		(drill 0.254)
		(layers "F.Cu" "B.Cu")
		(net "GND")
	)
	(via
		(at 219.289884 -76.649072)
		(size 0.508)
		(drill 0.254)
		(layers "F.Cu" "B.Cu")
		(net "GND")
	)
	(via
		(at 262.103108 -265.078464)
		(size 0.508)
		(drill 0.254)
		(layers "F.Cu" "B.Cu")
		(net "GND")
	)
	(via
		(at 106.68 -421.64)
		(size 0.508)
		(drill 0.254)
		(layers "F.Cu" "B.Cu")
		(net "GND")
	)
	(via
		(at 37.61613 -171.990004)
		(size 0.508)
		(drill 0.254)
		(layers "F.Cu" "B.Cu")
		(net "GND")
	)
	(via
		(at 106.68 -254)
		(size 0.508)
		(drill 0.254)
		(layers "F.Cu" "B.Cu")
		(net "GND")
	)
	(via
		(at 132.08 -5.08)
		(size 0.508)
		(drill 0.254)
		(layers "F.Cu" "B.Cu")
		(net "GND")
	)
	(via
		(at 243.84 -152.4)
		(size 0.508)
		(drill 0.254)
		(layers "F.Cu" "B.Cu")
		(net "GND")
	)
	(via
		(at 172.72 -340.36)
		(size 0.508)
		(drill 0.254)
		(layers "F.Cu" "B.Cu")
		(net "GND")
	)
	(via
		(at 262.103108 -229.518464)
		(size 0.508)
		(drill 0.254)
		(layers "F.Cu" "B.Cu")
		(net "GND")
	)
	(via
		(at 96.52 -492.76)
		(size 0.508)
		(drill 0.254)
		(layers "F.Cu" "B.Cu")
		(net "GND")
	)
	(via
		(at 4.191 -413.131)
		(size 0.508)
		(drill 0.254)
		(layers "F.Cu" "B.Cu")
		(net "GND")
	)
	(via
		(at 121.92 -502.92)
		(size 0.508)
		(drill 0.254)
		(layers "F.Cu" "B.Cu")
		(net "GND")
	)
	(via
		(at 241.3 -393.7)
		(size 0.7112)
		(drill 0.3556)
		(layers "F.Cu" "B.Cu")
		(net "GND")
	)
	(via
		(at 193.04 -81.28)
		(size 0.508)
		(drill 0.254)
		(layers "F.Cu" "B.Cu")
		(net "GND")
	)
	(via
		(at 132.08 -487.68)
		(size 0.508)
		(drill 0.254)
		(layers "F.Cu" "B.Cu")
		(net "GND")
	)
	(via
		(at 177.8 -142.24)
		(size 0.508)
		(drill 0.254)
		(layers "F.Cu" "B.Cu")
		(net "GND")
	)
	(via
		(at 187.96 -182.88)
		(size 0.508)
		(drill 0.254)
		(layers "F.Cu" "B.Cu")
		(net "GND")
	)
	(via
		(at 222.616014 -490.590078)
		(size 0.508)
		(drill 0.254)
		(layers "F.Cu" "B.Cu")
		(net "GND")
	)
	(via
		(at 71.12 -111.76)
		(size 0.508)
		(drill 0.254)
		(layers "F.Cu" "B.Cu")
		(net "GND")
	)
	(via
		(at 43.58513 -51.794918)
		(size 0.508)
		(drill 0.254)
		(layers "F.Cu" "B.Cu")
		(net "GND")
	)
	(via
		(at 55.88 -436.88)
		(size 0.508)
		(drill 0.254)
		(layers "F.Cu" "B.Cu")
		(net "GND")
	)
	(via
		(at 30.361636 -205.98765)
		(size 0.508)
		(drill 0.254)
		(layers "F.Cu" "B.Cu")
		(net "GND")
	)
	(via
		(at 228.981 -491.363)
		(size 0.508)
		(drill 0.254)
		(layers "F.Cu" "B.Cu")
		(net "GND")
	)
	(via
		(at 6.223 -225.173286)
		(size 0.508)
		(drill 0.254)
		(layers "F.Cu" "B.Cu")
		(net "GND")
	)
	(via
		(at 45.72 -325.12)
		(size 0.508)
		(drill 0.254)
		(layers "F.Cu" "B.Cu")
		(net "GND")
	)
	(via
		(at 37.0332 -84.4296)
		(size 0.508)
		(drill 0.254)
		(layers "F.Cu" "B.Cu")
		(net "GND")
	)
	(via
		(at 26.5684 -206.0702)
		(size 0.508)
		(drill 0.254)
		(layers "F.Cu" "B.Cu")
		(net "GND")
	)
	(via
		(at 222.616014 -492.990124)
		(size 0.508)
		(drill 0.254)
		(layers "F.Cu" "B.Cu")
		(net "GND")
	)
	(via
		(at 120.4722 -107.616752)
		(size 0.7112)
		(drill 0.3556)
		(layers "F.Cu" "B.Cu")
		(net "GND")
	)
	(via
		(at 243.84 -132.08)
		(size 0.508)
		(drill 0.254)
		(layers "F.Cu" "B.Cu")
		(net "GND")
	)
	(via
		(at 96.774 -430.403)
		(size 0.508)
		(drill 0.254)
		(layers "F.Cu" "B.Cu")
		(net "GND")
	)
	(via
		(at 213.36 -182.88)
		(size 0.508)
		(drill 0.254)
		(layers "F.Cu" "B.Cu")
		(net "GND")
	)
	(via
		(at 248.92 -55.88)
		(size 0.508)
		(drill 0.254)
		(layers "F.Cu" "B.Cu")
		(net "GND")
	)
	(via
		(at 218.44 -228.6)
		(size 0.508)
		(drill 0.254)
		(layers "F.Cu" "B.Cu")
		(net "GND")
	)
	(via
		(at 101.6 -355.6)
		(size 0.508)
		(drill 0.254)
		(layers "F.Cu" "B.Cu")
		(net "GND")
	)
	(via
		(at 233.68 -497.84)
		(size 0.508)
		(drill 0.254)
		(layers "F.Cu" "B.Cu")
		(net "GND")
	)
	(via
		(at 233.68 -254)
		(size 0.508)
		(drill 0.254)
		(layers "F.Cu" "B.Cu")
		(net "GND")
	)
	(via
		(at 45.72 -467.36)
		(size 0.508)
		(drill 0.254)
		(layers "F.Cu" "B.Cu")
		(net "GND")
	)
	(via
		(at 55.88 -223.52)
		(size 0.508)
		(drill 0.254)
		(layers "F.Cu" "B.Cu")
		(net "GND")
	)
	(via
		(at 92.583 -102.997)
		(size 0.508)
		(drill 0.254)
		(layers "F.Cu" "B.Cu")
		(net "GND")
	)
	(via
		(at 86.36 -20.32)
		(size 0.508)
		(drill 0.254)
		(layers "F.Cu" "B.Cu")
		(net "GND")
	)
	(via
		(at 116.84 -208.28)
		(size 0.508)
		(drill 0.254)
		(layers "F.Cu" "B.Cu")
		(net "GND")
	)
	(via
		(at 95.377 -101.6)
		(size 0.508)
		(drill 0.254)
		(layers "F.Cu" "B.Cu")
		(net "GND")
	)
	(via
		(at 198.12 -111.76)
		(size 0.508)
		(drill 0.254)
		(layers "F.Cu" "B.Cu")
		(net "GND")
	)
	(via
		(at 200.664572 -1.397)
		(size 0.508)
		(drill 0.254)
		(layers "F.Cu" "B.Cu")
		(net "GND")
	)
	(via
		(at 256.544572 -1.397)
		(size 0.508)
		(drill 0.254)
		(layers "F.Cu" "B.Cu")
		(net "GND")
	)
	(via
		(at 106.68 -127)
		(size 0.508)
		(drill 0.254)
		(layers "F.Cu" "B.Cu")
		(net "GND")
	)
	(via
		(at 55.88 -340.36)
		(size 0.508)
		(drill 0.254)
		(layers "F.Cu" "B.Cu")
		(net "GND")
	)
	(via
		(at 3.189986 -504.603004)
		(size 0.508)
		(drill 0.254)
		(layers "F.Cu" "B.Cu")
		(net "GND")
	)
	(via
		(at 259.08 -5.08)
		(size 0.508)
		(drill 0.254)
		(layers "F.Cu" "B.Cu")
		(net "GND")
	)
	(via
		(at 35.3314 -502.1834)
		(size 0.508)
		(drill 0.254)
		(layers "F.Cu" "B.Cu")
		(net "GND")
	)
	(via
		(at 259.08 -335.28)
		(size 0.508)
		(drill 0.254)
		(layers "F.Cu" "B.Cu")
		(net "GND")
	)
	(via
		(at 222.616014 -279.78989)
		(size 0.508)
		(drill 0.254)
		(layers "F.Cu" "B.Cu")
		(net "GND")
	)
	(via
		(at 35.56 -228.6)
		(size 0.508)
		(drill 0.254)
		(layers "F.Cu" "B.Cu")
		(net "GND")
	)
	(via
		(at 127 -76.2)
		(size 0.508)
		(drill 0.254)
		(layers "F.Cu" "B.Cu")
		(net "GND")
	)
	(via
		(at 152.4 -482.6)
		(size 0.508)
		(drill 0.254)
		(layers "F.Cu" "B.Cu")
		(net "GND")
	)
	(via
		(at 248.92 -325.12)
		(size 0.508)
		(drill 0.254)
		(layers "F.Cu" "B.Cu")
		(net "GND")
	)
	(via
		(at 6.223 -326.410066)
		(size 0.508)
		(drill 0.254)
		(layers "F.Cu" "B.Cu")
		(net "GND")
	)
	(via
		(at 167.64 -228.6)
		(size 0.508)
		(drill 0.254)
		(layers "F.Cu" "B.Cu")
		(net "GND")
	)
	(via
		(at 177.8 -193.04)
		(size 0.508)
		(drill 0.254)
		(layers "F.Cu" "B.Cu")
		(net "GND")
	)
	(via
		(at 262.103108 -36.478464)
		(size 0.508)
		(drill 0.254)
		(layers "F.Cu" "B.Cu")
		(net "GND")
	)
	(via
		(at 106.68 -477.52)
		(size 0.508)
		(drill 0.254)
		(layers "F.Cu" "B.Cu")
		(net "GND")
	)
	(via
		(at 86.36 -279.4)
		(size 0.508)
		(drill 0.254)
		(layers "F.Cu" "B.Cu")
		(net "GND")
	)
	(via
		(at 248.92 -345.44)
		(size 0.508)
		(drill 0.254)
		(layers "F.Cu" "B.Cu")
		(net "GND")
	)
	(via
		(at 32.893 -478.409)
		(size 0.508)
		(drill 0.254)
		(layers "F.Cu" "B.Cu")
		(net "GND")
	)
	(via
		(at 76.835 -361.696)
		(size 0.508)
		(drill 0.254)
		(layers "F.Cu" "B.Cu")
		(net "GND")
	)
	(via
		(at 25.4 -452.12)
		(size 0.508)
		(drill 0.254)
		(layers "F.Cu" "B.Cu")
		(net "GND")
	)
	(via
		(at 177.419 -460.248)
		(size 0.7112)
		(drill 0.3556)
		(layers "F.Cu" "B.Cu")
		(net "GND")
	)
	(via
		(at 28.575 -214.6808)
		(size 0.508)
		(drill 0.254)
		(layers "F.Cu" "B.Cu")
		(net "GND")
	)
	(via
		(at 81.661 -308.483)
		(size 0.508)
		(drill 0.254)
		(layers "F.Cu" "B.Cu")
		(net "GND")
	)
	(via
		(at 10.16 -25.4)
		(size 0.508)
		(drill 0.254)
		(layers "F.Cu" "B.Cu")
		(net "GND")
	)
	(via
		(at 203.2 -106.68)
		(size 0.508)
		(drill 0.254)
		(layers "F.Cu" "B.Cu")
		(net "GND")
	)
	(via
		(at 230.798116 -264.700766)
		(size 0.508)
		(drill 0.254)
		(layers "F.Cu" "B.Cu")
		(net "GND")
	)
	(via
		(at 233.68 -274.32)
		(size 0.508)
		(drill 0.254)
		(layers "F.Cu" "B.Cu")
		(net "GND")
	)
	(via
		(at 81.28 -91.313)
		(size 0.508)
		(drill 0.254)
		(layers "F.Cu" "B.Cu")
		(net "GND")
	)
	(via
		(at 4.191 -351.166176)
		(size 0.508)
		(drill 0.254)
		(layers "F.Cu" "B.Cu")
		(net "GND")
	)
	(via
		(at 101.6 -340.36)
		(size 0.508)
		(drill 0.254)
		(layers "F.Cu" "B.Cu")
		(net "GND")
	)
	(via
		(at 37.61613 -286.990028)
		(size 0.508)
		(drill 0.254)
		(layers "F.Cu" "B.Cu")
		(net "GND")
	)
	(via
		(at 172.72 -472.44)
		(size 0.508)
		(drill 0.254)
		(layers "F.Cu" "B.Cu")
		(net "GND")
	)
	(via
		(at 152.4 -55.88)
		(size 0.508)
		(drill 0.254)
		(layers "F.Cu" "B.Cu")
		(net "GND")
	)
	(via
		(at 81.28 -264.16)
		(size 0.508)
		(drill 0.254)
		(layers "F.Cu" "B.Cu")
		(net "GND")
	)
	(via
		(at 89.973912 -295.715182)
		(size 0.508)
		(drill 0.254)
		(layers "F.Cu" "B.Cu")
		(net "GND")
	)
	(via
		(at 50.8 -45.72)
		(size 0.508)
		(drill 0.254)
		(layers "F.Cu" "B.Cu")
		(net "GND")
	)
	(via
		(at 4.191 -181.090062)
		(size 0.508)
		(drill 0.254)
		(layers "F.Cu" "B.Cu")
		(net "GND")
	)
	(via
		(at 34.5694 -197.0024)
		(size 0.508)
		(drill 0.254)
		(layers "F.Cu" "B.Cu")
		(net "GND")
	)
	(via
		(at 21.144992 -269.147544)
		(size 0.508)
		(drill 0.254)
		(layers "F.Cu" "B.Cu")
		(net "GND")
	)
	(via
		(at 172.72 -167.64)
		(size 0.508)
		(drill 0.254)
		(layers "F.Cu" "B.Cu")
		(net "GND")
	)
	(via
		(at 142.24 -309.88)
		(size 0.508)
		(drill 0.254)
		(layers "F.Cu" "B.Cu")
		(net "GND")
	)
	(via
		(at 60.96 -223.52)
		(size 0.508)
		(drill 0.254)
		(layers "F.Cu" "B.Cu")
		(net "GND")
	)
	(via
		(at 218.44 -25.4)
		(size 0.508)
		(drill 0.254)
		(layers "F.Cu" "B.Cu")
		(net "GND")
	)
	(via
		(at 243.84 -198.12)
		(size 0.508)
		(drill 0.254)
		(layers "F.Cu" "B.Cu")
		(net "GND")
	)
	(via
		(at 213.36 -116.84)
		(size 0.508)
		(drill 0.254)
		(layers "F.Cu" "B.Cu")
		(net "GND")
	)
	(via
		(at 24.6126 -103.124)
		(size 0.508)
		(drill 0.254)
		(layers "F.Cu" "B.Cu")
		(net "GND")
	)
	(via
		(at 248.92 -213.36)
		(size 0.508)
		(drill 0.254)
		(layers "F.Cu" "B.Cu")
		(net "GND")
	)
	(via
		(at 116.84 -401.32)
		(size 0.508)
		(drill 0.254)
		(layers "F.Cu" "B.Cu")
		(net "GND")
	)
	(via
		(at 116.84 -243.84)
		(size 0.508)
		(drill 0.254)
		(layers "F.Cu" "B.Cu")
		(net "GND")
	)
	(via
		(at 177.8 -492.76)
		(size 0.508)
		(drill 0.254)
		(layers "F.Cu" "B.Cu")
		(net "GND")
	)
	(via
		(at 177.8 -213.36)
		(size 0.508)
		(drill 0.254)
		(layers "F.Cu" "B.Cu")
		(net "GND")
	)
	(via
		(at 81.28 -116.84)
		(size 0.508)
		(drill 0.254)
		(layers "F.Cu" "B.Cu")
		(net "GND")
	)
	(via
		(at 95.377 -212.217)
		(size 0.508)
		(drill 0.254)
		(layers "F.Cu" "B.Cu")
		(net "GND")
	)
	(via
		(at 83.185 -94.742)
		(size 0.508)
		(drill 0.254)
		(layers "F.Cu" "B.Cu")
		(net "GND")
	)
	(via
		(at 106.68 -213.36)
		(size 0.508)
		(drill 0.254)
		(layers "F.Cu" "B.Cu")
		(net "GND")
	)
	(via
		(at 227.457 -434.848)
		(size 0.508)
		(drill 0.254)
		(layers "F.Cu" "B.Cu")
		(net "GND")
	)
	(via
		(at 132.08 -497.84)
		(size 0.508)
		(drill 0.254)
		(layers "F.Cu" "B.Cu")
		(net "GND")
	)
	(via
		(at 238.76 -162.56)
		(size 0.508)
		(drill 0.254)
		(layers "F.Cu" "B.Cu")
		(net "GND")
	)
	(via
		(at 81.28 -15.24)
		(size 0.508)
		(drill 0.254)
		(layers "F.Cu" "B.Cu")
		(net "GND")
	)
	(via
		(at 116.84 -233.68)
		(size 0.508)
		(drill 0.254)
		(layers "F.Cu" "B.Cu")
		(net "GND")
	)
	(via
		(at 27.69616 -429.393096)
		(size 0.508)
		(drill 0.254)
		(layers "F.Cu" "B.Cu")
		(net "GND")
	)
	(via
		(at 142.24 -360.68)
		(size 0.508)
		(drill 0.254)
		(layers "F.Cu" "B.Cu")
		(net "GND")
	)
	(via
		(at 219.314014 -277.781004)
		(size 0.508)
		(drill 0.254)
		(layers "F.Cu" "B.Cu")
		(net "GND")
	)
	(via
		(at 245.11 -394.97)
		(size 0.7112)
		(drill 0.4064)
		(layers "F.Cu" "B.Cu")
		(net "GND")
	)
	(via
		(at 208.28 -157.48)
		(size 0.508)
		(drill 0.254)
		(layers "F.Cu" "B.Cu")
		(net "GND")
	)
	(via
		(at 248.92 -5.08)
		(size 0.508)
		(drill 0.254)
		(layers "F.Cu" "B.Cu")
		(net "GND")
	)
	(via
		(at 198.12 -309.88)
		(size 0.508)
		(drill 0.254)
		(layers "F.Cu" "B.Cu")
		(net "GND")
	)
	(via
		(at 6.223 -310.274716)
		(size 0.508)
		(drill 0.254)
		(layers "F.Cu" "B.Cu")
		(net "GND")
	)
	(via
		(at 43.942 -182.372)
		(size 0.508)
		(drill 0.254)
		(layers "F.Cu" "B.Cu")
		(net "GND")
	)
	(via
		(at 25.0444 -421.5892)
		(size 0.508)
		(drill 0.254)
		(layers "F.Cu" "B.Cu")
		(net "GND")
	)
	(via
		(at 243.84 -76.2)
		(size 0.508)
		(drill 0.254)
		(layers "F.Cu" "B.Cu")
		(net "GND")
	)
	(via
		(at 182.88 -5.08)
		(size 0.508)
		(drill 0.254)
		(layers "F.Cu" "B.Cu")
		(net "GND")
	)
	(via
		(at 223.52 -406.146)
		(size 0.508)
		(drill 0.254)
		(layers "F.Cu" "B.Cu")
		(net "GND")
	)
	(via
		(at 162.56 -121.92)
		(size 0.508)
		(drill 0.254)
		(layers "F.Cu" "B.Cu")
		(net "GND")
	)
	(via
		(at 1.397 -477.69399)
		(size 0.508)
		(drill 0.254)
		(layers "F.Cu" "B.Cu")
		(net "GND")
	)
	(via
		(at 248.92 -254)
		(size 0.508)
		(drill 0.254)
		(layers "F.Cu" "B.Cu")
		(net "GND")
	)
	(via
		(at 259.08 -477.52)
		(size 0.508)
		(drill 0.254)
		(layers "F.Cu" "B.Cu")
		(net "GND")
	)
	(via
		(at 6.223 -445.938402)
		(size 0.508)
		(drill 0.254)
		(layers "F.Cu" "B.Cu")
		(net "GND")
	)
	(via
		(at 218.44 -203.2)
		(size 0.508)
		(drill 0.254)
		(layers "F.Cu" "B.Cu")
		(net "GND")
	)
	(via
		(at 209.648552 -441.833)
		(size 0.508)
		(drill 0.254)
		(layers "F.Cu" "B.Cu")
		(net "GND")
	)
	(via
		(at 127 -381)
		(size 0.508)
		(drill 0.254)
		(layers "F.Cu" "B.Cu")
		(net "GND")
	)
	(via
		(at 203.2 -60.96)
		(size 0.508)
		(drill 0.254)
		(layers "F.Cu" "B.Cu")
		(net "GND")
	)
	(via
		(at 132.08 -299.72)
		(size 0.508)
		(drill 0.254)
		(layers "F.Cu" "B.Cu")
		(net "GND")
	)
	(via
		(at 111.76 -223.52)
		(size 0.508)
		(drill 0.254)
		(layers "F.Cu" "B.Cu")
		(net "GND")
	)
	(via
		(at 24.384 -120.81002)
		(size 0.508)
		(drill 0.254)
		(layers "F.Cu" "B.Cu")
		(net "GND")
	)
	(via
		(at 193.04 -111.76)
		(size 0.508)
		(drill 0.254)
		(layers "F.Cu" "B.Cu")
		(net "GND")
	)
	(via
		(at 222.616014 -266.189968)
		(size 0.508)
		(drill 0.254)
		(layers "F.Cu" "B.Cu")
		(net "GND")
	)
	(via
		(at 6.223 -226.673156)
		(size 0.508)
		(drill 0.254)
		(layers "F.Cu" "B.Cu")
		(net "GND")
	)
	(via
		(at 127 -35.56)
		(size 0.508)
		(drill 0.254)
		(layers "F.Cu" "B.Cu")
		(net "GND")
	)
	(via
		(at 228.585014 -72.114918)
		(size 0.508)
		(drill 0.254)
		(layers "F.Cu" "B.Cu")
		(net "GND")
	)
	(via
		(at 212.725 -453.39)
		(size 0.508)
		(drill 0.254)
		(layers "F.Cu" "B.Cu")
		(net "GND")
	)
	(via
		(at 198.12 -116.84)
		(size 0.508)
		(drill 0.254)
		(layers "F.Cu" "B.Cu")
		(net "GND")
	)
	(via
		(at 27.697176 -118.826788)
		(size 0.508)
		(drill 0.254)
		(layers "F.Cu" "B.Cu")
		(net "GND")
	)
	(via
		(at 121.92 -381)
		(size 0.508)
		(drill 0.254)
		(layers "F.Cu" "B.Cu")
		(net "GND")
	)
	(via
		(at 245.11 -407.67)
		(size 0.7112)
		(drill 0.4064)
		(layers "F.Cu" "B.Cu")
		(net "GND")
	)
	(via
		(at 18.415 -124.884942)
		(size 0.508)
		(drill 0.254)
		(layers "F.Cu" "B.Cu")
		(net "GND")
	)
	(via
		(at 127 -421.64)
		(size 0.508)
		(drill 0.254)
		(layers "F.Cu" "B.Cu")
		(net "GND")
	)
	(via
		(at 162.56 -45.72)
		(size 0.508)
		(drill 0.254)
		(layers "F.Cu" "B.Cu")
		(net "GND")
	)
	(via
		(at 71.138034 -488.865418)
		(size 0.508)
		(drill 0.254)
		(layers "F.Cu" "B.Cu")
		(net "GND")
	)
	(via
		(at 6.223 -346.274644)
		(size 0.508)
		(drill 0.254)
		(layers "F.Cu" "B.Cu")
		(net "GND")
	)
	(via
		(at 162.56 -350.52)
		(size 0.508)
		(drill 0.254)
		(layers "F.Cu" "B.Cu")
		(net "GND")
	)
	(via
		(at 116.84 -355.6)
		(size 0.508)
		(drill 0.254)
		(layers "F.Cu" "B.Cu")
		(net "GND")
	)
	(via
		(at 228.585014 -154.794966)
		(size 0.508)
		(drill 0.254)
		(layers "F.Cu" "B.Cu")
		(net "GND")
	)
	(via
		(at 230.124 -435.229)
		(size 0.508)
		(drill 0.254)
		(layers "F.Cu" "B.Cu")
		(net "GND")
	)
	(via
		(at 233.68 -127)
		(size 0.508)
		(drill 0.254)
		(layers "F.Cu" "B.Cu")
		(net "GND")
	)
	(via
		(at 222.616014 -468.190072)
		(size 0.508)
		(drill 0.254)
		(layers "F.Cu" "B.Cu")
		(net "GND")
	)
	(via
		(at 254 -106.68)
		(size 0.508)
		(drill 0.254)
		(layers "F.Cu" "B.Cu")
		(net "GND")
	)
	(via
		(at 66.04 -264.16)
		(size 0.508)
		(drill 0.254)
		(layers "F.Cu" "B.Cu")
		(net "GND")
	)
	(via
		(at 213.36 -167.64)
		(size 0.508)
		(drill 0.254)
		(layers "F.Cu" "B.Cu")
		(net "GND")
	)
	(via
		(at 6.858 -111.76)
		(size 0.508)
		(drill 0.254)
		(layers "F.Cu" "B.Cu")
		(net "GND")
	)
	(via
		(at 222.616014 -274.990052)
		(size 0.508)
		(drill 0.254)
		(layers "F.Cu" "B.Cu")
		(net "GND")
	)
	(via
		(at 152.4 -304.8)
		(size 0.508)
		(drill 0.254)
		(layers "F.Cu" "B.Cu")
		(net "GND")
	)
	(via
		(at 121.92 -167.64)
		(size 0.508)
		(drill 0.254)
		(layers "F.Cu" "B.Cu")
		(net "GND")
	)
	(via
		(at 6.223 -170.062398)
		(size 0.508)
		(drill 0.254)
		(layers "F.Cu" "B.Cu")
		(net "GND")
	)
	(via
		(at 251.866908 -412.115)
		(size 0.508)
		(drill 0.254)
		(layers "F.Cu" "B.Cu")
		(net "GND")
	)
	(via
		(at 24.384 -138.409934)
		(size 0.508)
		(drill 0.254)
		(layers "F.Cu" "B.Cu")
		(net "GND")
	)
	(via
		(at 157.48 -345.44)
		(size 0.508)
		(drill 0.254)
		(layers "F.Cu" "B.Cu")
		(net "GND")
	)
	(via
		(at 243.84 -391.16)
		(size 0.7112)
		(drill 0.3556)
		(layers "F.Cu" "B.Cu")
		(net "GND")
	)
	(via
		(at 167.64 -492.76)
		(size 0.508)
		(drill 0.254)
		(layers "F.Cu" "B.Cu")
		(net "GND")
	)
	(via
		(at 262.103108 -107.598464)
		(size 0.508)
		(drill 0.254)
		(layers "F.Cu" "B.Cu")
		(net "GND")
	)
	(via
		(at 238.76 -325.12)
		(size 0.508)
		(drill 0.254)
		(layers "F.Cu" "B.Cu")
		(net "GND")
	)
	(via
		(at 193.04 -314.96)
		(size 0.508)
		(drill 0.254)
		(layers "F.Cu" "B.Cu")
		(net "GND")
	)
	(via
		(at 182.88 -228.6)
		(size 0.508)
		(drill 0.254)
		(layers "F.Cu" "B.Cu")
		(net "GND")
	)
	(via
		(at 6.223 -278.325326)
		(size 0.508)
		(drill 0.254)
		(layers "F.Cu" "B.Cu")
		(net "GND")
	)
	(via
		(at 262.103108 -300.638464)
		(size 0.508)
		(drill 0.254)
		(layers "F.Cu" "B.Cu")
		(net "GND")
	)
	(via
		(at 248.92 -304.8)
		(size 0.508)
		(drill 0.254)
		(layers "F.Cu" "B.Cu")
		(net "GND")
	)
	(via
		(at 167.64 -60.96)
		(size 0.508)
		(drill 0.254)
		(layers "F.Cu" "B.Cu")
		(net "GND")
	)
	(via
		(at 172.72 -132.08)
		(size 0.508)
		(drill 0.254)
		(layers "F.Cu" "B.Cu")
		(net "GND")
	)
	(via
		(at 152.4 -497.84)
		(size 0.508)
		(drill 0.254)
		(layers "F.Cu" "B.Cu")
		(net "GND")
	)
	(via
		(at 71.12 -86.36)
		(size 0.508)
		(drill 0.254)
		(layers "F.Cu" "B.Cu")
		(net "GND")
	)
	(via
		(at 147.32 -365.76)
		(size 0.508)
		(drill 0.254)
		(layers "F.Cu" "B.Cu")
		(net "GND")
	)
	(via
		(at 36.322 -420.624)
		(size 0.508)
		(drill 0.254)
		(layers "F.Cu" "B.Cu")
		(net "GND")
	)
	(via
		(at 262.103108 -280.318464)
		(size 0.508)
		(drill 0.254)
		(layers "F.Cu" "B.Cu")
		(net "GND")
	)
	(via
		(at 152.4 -20.32)
		(size 0.508)
		(drill 0.254)
		(layers "F.Cu" "B.Cu")
		(net "GND")
	)
	(via
		(at 222.616014 -478.590102)
		(size 0.508)
		(drill 0.254)
		(layers "F.Cu" "B.Cu")
		(net "GND")
	)
	(via
		(at 187.96 -152.4)
		(size 0.508)
		(drill 0.254)
		(layers "F.Cu" "B.Cu")
		(net "GND")
	)
	(via
		(at 220.599 -166.116)
		(size 0.508)
		(drill 0.254)
		(layers "F.Cu" "B.Cu")
		(net "GND")
	)
	(via
		(at 89.34196 -223.702118)
		(size 0.508)
		(drill 0.254)
		(layers "F.Cu" "B.Cu")
		(net "GND")
	)
	(via
		(at 157.48 -452.12)
		(size 0.508)
		(drill 0.254)
		(layers "F.Cu" "B.Cu")
		(net "GND")
	)
	(via
		(at 4.191 -441.071)
		(size 0.508)
		(drill 0.254)
		(layers "F.Cu" "B.Cu")
		(net "GND")
	)
	(via
		(at 152.4 -86.36)
		(size 0.508)
		(drill 0.254)
		(layers "F.Cu" "B.Cu")
		(net "GND")
	)
	(via
		(at 172.72 -452.12)
		(size 0.508)
		(drill 0.254)
		(layers "F.Cu" "B.Cu")
		(net "GND")
	)
	(via
		(at 172.72 -187.96)
		(size 0.508)
		(drill 0.254)
		(layers "F.Cu" "B.Cu")
		(net "GND")
	)
	(via
		(at 137.16 -243.84)
		(size 0.508)
		(drill 0.254)
		(layers "F.Cu" "B.Cu")
		(net "GND")
	)
	(via
		(at 195.584572 -1.397)
		(size 0.508)
		(drill 0.254)
		(layers "F.Cu" "B.Cu")
		(net "GND")
	)
	(via
		(at 132.08 -441.96)
		(size 0.508)
		(drill 0.254)
		(layers "F.Cu" "B.Cu")
		(net "GND")
	)
	(via
		(at 172.72 -279.4)
		(size 0.508)
		(drill 0.254)
		(layers "F.Cu" "B.Cu")
		(net "GND")
	)
	(via
		(at 262.103108 -295.558464)
		(size 0.508)
		(drill 0.254)
		(layers "F.Cu" "B.Cu")
		(net "GND")
	)
	(via
		(at 29.89326 -354.880672)
		(size 0.508)
		(drill 0.254)
		(layers "F.Cu" "B.Cu")
		(net "GND")
	)
	(via
		(at 6.223 -394.794232)
		(size 0.508)
		(drill 0.254)
		(layers "F.Cu" "B.Cu")
		(net "GND")
	)
	(via
		(at 137.16 -30.48)
		(size 0.508)
		(drill 0.254)
		(layers "F.Cu" "B.Cu")
		(net "GND")
	)
	(via
		(at 17.145 -134.5184)
		(size 0.508)
		(drill 0.254)
		(layers "F.Cu" "B.Cu")
		(net "GND")
	)
	(via
		(at 254 -76.2)
		(size 0.508)
		(drill 0.254)
		(layers "F.Cu" "B.Cu")
		(net "GND")
	)
	(via
		(at 28.6004 -317.7032)
		(size 0.508)
		(drill 0.254)
		(layers "F.Cu" "B.Cu")
		(net "GND")
	)
	(via
		(at 5.08 -127)
		(size 0.508)
		(drill 0.254)
		(layers "F.Cu" "B.Cu")
		(net "GND")
	)
	(via
		(at 66.04 -20.32)
		(size 0.508)
		(drill 0.254)
		(layers "F.Cu" "B.Cu")
		(net "GND")
	)
	(via
		(at 37.61613 -270.99006)
		(size 0.508)
		(drill 0.254)
		(layers "F.Cu" "B.Cu")
		(net "GND")
	)
	(via
		(at 245.11 -402.59)
		(size 0.7112)
		(drill 0.4064)
		(layers "F.Cu" "B.Cu")
		(net "GND")
	)
	(via
		(at 6.223 -405.089868)
		(size 0.508)
		(drill 0.254)
		(layers "F.Cu" "B.Cu")
		(net "GND")
	)
	(via
		(at 187.96 -142.24)
		(size 0.508)
		(drill 0.254)
		(layers "F.Cu" "B.Cu")
		(net "GND")
	)
	(via
		(at 132.08 -264.16)
		(size 0.508)
		(drill 0.254)
		(layers "F.Cu" "B.Cu")
		(net "GND")
	)
	(via
		(at 198.12 -452.12)
		(size 0.508)
		(drill 0.254)
		(layers "F.Cu" "B.Cu")
		(net "GND")
	)
	(via
		(at 4.191 -436.235348)
		(size 0.508)
		(drill 0.254)
		(layers "F.Cu" "B.Cu")
		(net "GND")
	)
	(via
		(at 187.96 -309.88)
		(size 0.508)
		(drill 0.254)
		(layers "F.Cu" "B.Cu")
		(net "GND")
	)
	(via
		(at 93.98 -208.026)
		(size 0.508)
		(drill 0.254)
		(layers "F.Cu" "B.Cu")
		(net "GND")
	)
	(via
		(at 77.5462 -435.7878)
		(size 0.508)
		(drill 0.254)
		(layers "F.Cu" "B.Cu")
		(net "GND")
	)
	(via
		(at 208.28 -248.92)
		(size 0.508)
		(drill 0.254)
		(layers "F.Cu" "B.Cu")
		(net "GND")
	)
	(via
		(at 101.6 -233.68)
		(size 0.508)
		(drill 0.254)
		(layers "F.Cu" "B.Cu")
		(net "GND")
	)
	(via
		(at 81.28 -81.28)
		(size 0.508)
		(drill 0.254)
		(layers "F.Cu" "B.Cu")
		(net "GND")
	)
	(via
		(at 24.384 -221.409768)
		(size 0.508)
		(drill 0.254)
		(layers "F.Cu" "B.Cu")
		(net "GND")
	)
	(via
		(at 91.44 -396.24)
		(size 0.508)
		(drill 0.254)
		(layers "F.Cu" "B.Cu")
		(net "GND")
	)
	(via
		(at 152.4 -457.2)
		(size 0.508)
		(drill 0.254)
		(layers "F.Cu" "B.Cu")
		(net "GND")
	)
	(via
		(at 101.6 -370.84)
		(size 0.508)
		(drill 0.254)
		(layers "F.Cu" "B.Cu")
		(net "GND")
	)
	(via
		(at 177.8 -243.84)
		(size 0.508)
		(drill 0.254)
		(layers "F.Cu" "B.Cu")
		(net "GND")
	)
	(via
		(at 233.68 -492.76)
		(size 0.508)
		(drill 0.254)
		(layers "F.Cu" "B.Cu")
		(net "GND")
	)
	(via
		(at 25.1714 -309.8292)
		(size 0.508)
		(drill 0.254)
		(layers "F.Cu" "B.Cu")
		(net "GND")
	)
	(via
		(at 172.72 -457.2)
		(size 0.508)
		(drill 0.254)
		(layers "F.Cu" "B.Cu")
		(net "GND")
	)
	(via
		(at 17.145 -240.50117)
		(size 0.508)
		(drill 0.254)
		(layers "F.Cu" "B.Cu")
		(net "GND")
	)
	(via
		(at 203.2 -91.44)
		(size 0.508)
		(drill 0.254)
		(layers "F.Cu" "B.Cu")
		(net "GND")
	)
	(via
		(at 50.8 -50.8)
		(size 0.508)
		(drill 0.254)
		(layers "F.Cu" "B.Cu")
		(net "GND")
	)
	(via
		(at 121.92 -477.52)
		(size 0.508)
		(drill 0.254)
		(layers "F.Cu" "B.Cu")
		(net "GND")
	)
	(via
		(at 187.96 -101.6)
		(size 0.508)
		(drill 0.254)
		(layers "F.Cu" "B.Cu")
		(net "GND")
	)
	(via
		(at 13.081 -192.405)
		(size 0.508)
		(drill 0.254)
		(layers "F.Cu" "B.Cu")
		(net "GND")
	)
	(via
		(at 101.981 -101.981)
		(size 0.508)
		(drill 0.254)
		(layers "F.Cu" "B.Cu")
		(net "GND")
	)
	(via
		(at 66.04 -248.92)
		(size 0.508)
		(drill 0.254)
		(layers "F.Cu" "B.Cu")
		(net "GND")
	)
	(via
		(at 157.48 -375.92)
		(size 0.508)
		(drill 0.254)
		(layers "F.Cu" "B.Cu")
		(net "GND")
	)
	(via
		(at 223.52 -152.4)
		(size 0.508)
		(drill 0.254)
		(layers "F.Cu" "B.Cu")
		(net "GND")
	)
	(via
		(at 116.84 -350.52)
		(size 0.508)
		(drill 0.254)
		(layers "F.Cu" "B.Cu")
		(net "GND")
	)
	(via
		(at 121.92 -254)
		(size 0.508)
		(drill 0.254)
		(layers "F.Cu" "B.Cu")
		(net "GND")
	)
	(via
		(at 91.186 -306.578)
		(size 0.508)
		(drill 0.254)
		(layers "F.Cu" "B.Cu")
		(net "GND")
	)
	(via
		(at 24.384 -226.210114)
		(size 0.508)
		(drill 0.254)
		(layers "F.Cu" "B.Cu")
		(net "GND")
	)
	(via
		(at 4.191 -207.490314)
		(size 0.508)
		(drill 0.254)
		(layers "F.Cu" "B.Cu")
		(net "GND")
	)
	(via
		(at 32.893 -343.489534)
		(size 0.508)
		(drill 0.254)
		(layers "F.Cu" "B.Cu")
		(net "GND")
	)
	(via
		(at 152.4 -172.72)
		(size 0.508)
		(drill 0.254)
		(layers "F.Cu" "B.Cu")
		(net "GND")
	)
	(via
		(at 111.76 -55.88)
		(size 0.508)
		(drill 0.254)
		(layers "F.Cu" "B.Cu")
		(net "GND")
	)
	(via
		(at 96.774 -213.614)
		(size 0.508)
		(drill 0.254)
		(layers "F.Cu" "B.Cu")
		(net "GND")
	)
	(via
		(at 6.223 -210.673188)
		(size 0.508)
		(drill 0.254)
		(layers "F.Cu" "B.Cu")
		(net "GND")
	)
	(via
		(at 137.16 -462.28)
		(size 0.508)
		(drill 0.254)
		(layers "F.Cu" "B.Cu")
		(net "GND")
	)
	(via
		(at 106.934 -206.4385)
		(size 0.508)
		(drill 0.254)
		(layers "F.Cu" "B.Cu")
		(net "GND")
	)
	(via
		(at 60.96 -365.76)
		(size 0.508)
		(drill 0.254)
		(layers "F.Cu" "B.Cu")
		(net "GND")
	)
	(via
		(at 222.616014 -380.390146)
		(size 0.508)
		(drill 0.254)
		(layers "F.Cu" "B.Cu")
		(net "GND")
	)
	(via
		(at 36.449 -93.98)
		(size 0.508)
		(drill 0.254)
		(layers "F.Cu" "B.Cu")
		(net "GND")
	)
	(via
		(at 132.08 -111.76)
		(size 0.508)
		(drill 0.254)
		(layers "F.Cu" "B.Cu")
		(net "GND")
	)
	(via
		(at 223.52 -20.32)
		(size 0.508)
		(drill 0.254)
		(layers "F.Cu" "B.Cu")
		(net "GND")
	)
	(via
		(at 24.384 -123.210066)
		(size 0.508)
		(drill 0.254)
		(layers "F.Cu" "B.Cu")
		(net "GND")
	)
	(via
		(at 93.98 -434.594)
		(size 0.508)
		(drill 0.254)
		(layers "F.Cu" "B.Cu")
		(net "GND")
	)
	(via
		(at 132.08 -274.32)
		(size 0.508)
		(drill 0.254)
		(layers "F.Cu" "B.Cu")
		(net "GND")
	)
	(via
		(at 116.84 -360.68)
		(size 0.508)
		(drill 0.254)
		(layers "F.Cu" "B.Cu")
		(net "GND")
	)
	(via
		(at 152.4 -340.36)
		(size 0.508)
		(drill 0.254)
		(layers "F.Cu" "B.Cu")
		(net "GND")
	)
	(via
		(at 100.838 -105.3465)
		(size 0.508)
		(drill 0.254)
		(layers "F.Cu" "B.Cu")
		(net "GND")
	)
	(via
		(at 187.96 -15.24)
		(size 0.508)
		(drill 0.254)
		(layers "F.Cu" "B.Cu")
		(net "GND")
	)
	(via
		(at 262.103108 -336.198464)
		(size 0.508)
		(drill 0.254)
		(layers "F.Cu" "B.Cu")
		(net "GND")
	)
	(via
		(at 92.71 -303.784)
		(size 0.508)
		(drill 0.254)
		(layers "F.Cu" "B.Cu")
		(net "GND")
	)
	(via
		(at 86.233 -309.4355)
		(size 0.508)
		(drill 0.254)
		(layers "F.Cu" "B.Cu")
		(net "GND")
	)
	(via
		(at 208.28 -25.4)
		(size 0.508)
		(drill 0.254)
		(layers "F.Cu" "B.Cu")
		(net "GND")
	)
	(via
		(at 76.2 -162.56)
		(size 0.508)
		(drill 0.254)
		(layers "F.Cu" "B.Cu")
		(net "GND")
	)
	(via
		(at 137.16 -86.36)
		(size 0.508)
		(drill 0.254)
		(layers "F.Cu" "B.Cu")
		(net "GND")
	)
	(via
		(at 223.52 -309.88)
		(size 0.508)
		(drill 0.254)
		(layers "F.Cu" "B.Cu")
		(net "GND")
	)
	(via
		(at 187.96 -335.28)
		(size 0.508)
		(drill 0.254)
		(layers "F.Cu" "B.Cu")
		(net "GND")
	)
	(via
		(at 238.76 -264.16)
		(size 0.508)
		(drill 0.254)
		(layers "F.Cu" "B.Cu")
		(net "GND")
	)
	(via
		(at 198.12 -350.52)
		(size 0.508)
		(drill 0.254)
		(layers "F.Cu" "B.Cu")
		(net "GND")
	)
	(via
		(at 172.72 -208.28)
		(size 0.508)
		(drill 0.254)
		(layers "F.Cu" "B.Cu")
		(net "GND")
	)
	(via
		(at 251.464572 -1.397)
		(size 0.508)
		(drill 0.254)
		(layers "F.Cu" "B.Cu")
		(net "GND")
	)
	(via
		(at 55.88 -309.88)
		(size 0.508)
		(drill 0.254)
		(layers "F.Cu" "B.Cu")
		(net "GND")
	)
	(via
		(at 37.61613 -181.589934)
		(size 0.508)
		(drill 0.254)
		(layers "F.Cu" "B.Cu")
		(net "GND")
	)
	(via
		(at 49.403 -61.7982)
		(size 0.508)
		(drill 0.254)
		(layers "F.Cu" "B.Cu")
		(net "GND")
	)
	(via
		(at 81.28 -25.4)
		(size 0.508)
		(drill 0.254)
		(layers "F.Cu" "B.Cu")
		(net "GND")
	)
	(via
		(at 111.76 -426.72)
		(size 0.508)
		(drill 0.254)
		(layers "F.Cu" "B.Cu")
		(net "GND")
	)
	(via
		(at 243.84 -279.4)
		(size 0.508)
		(drill 0.254)
		(layers "F.Cu" "B.Cu")
		(net "GND")
	)
	(via
		(at 152.4 -137.16)
		(size 0.508)
		(drill 0.254)
		(layers "F.Cu" "B.Cu")
		(net "GND")
	)
	(via
		(at 30.6832 -111.252)
		(size 0.508)
		(drill 0.254)
		(layers "F.Cu" "B.Cu")
		(net "GND")
	)
	(via
		(at 96.52 -137.16)
		(size 0.508)
		(drill 0.254)
		(layers "F.Cu" "B.Cu")
		(net "GND")
	)
	(via
		(at 198.12 -325.12)
		(size 0.508)
		(drill 0.254)
		(layers "F.Cu" "B.Cu")
		(net "GND")
	)
	(via
		(at 6.7564 -459.8924)
		(size 0.7112)
		(drill 0.4064)
		(layers "F.Cu" "B.Cu")
		(net "GND")
	)
	(via
		(at 142.24 -147.32)
		(size 0.508)
		(drill 0.254)
		(layers "F.Cu" "B.Cu")
		(net "GND")
	)
	(via
		(at 245.11 -397.51)
		(size 0.7112)
		(drill 0.4064)
		(layers "F.Cu" "B.Cu")
		(net "GND")
	)
	(via
		(at 262.103108 -458.716126)
		(size 0.508)
		(drill 0.254)
		(layers "F.Cu" "B.Cu")
		(net "GND")
	)
	(via
		(at 210.824572 -1.397)
		(size 0.508)
		(drill 0.254)
		(layers "F.Cu" "B.Cu")
		(net "GND")
	)
	(via
		(at 177.8 -309.88)
		(size 0.508)
		(drill 0.254)
		(layers "F.Cu" "B.Cu")
		(net "GND")
	)
	(via
		(at 172.72 -60.96)
		(size 0.508)
		(drill 0.254)
		(layers "F.Cu" "B.Cu")
		(net "GND")
	)
	(via
		(at 18.034 -281.686)
		(size 0.508)
		(drill 0.254)
		(layers "F.Cu" "B.Cu")
		(net "GND")
	)
	(via
		(at 96.52 -35.56)
		(size 0.508)
		(drill 0.254)
		(layers "F.Cu" "B.Cu")
		(net "GND")
	)
	(via
		(at 60.96 -467.36)
		(size 0.508)
		(drill 0.254)
		(layers "F.Cu" "B.Cu")
		(net "GND")
	)
	(via
		(at 50.8 -325.12)
		(size 0.508)
		(drill 0.254)
		(layers "F.Cu" "B.Cu")
		(net "GND")
	)
	(via
		(at 248.92 -289.56)
		(size 0.508)
		(drill 0.254)
		(layers "F.Cu" "B.Cu")
		(net "GND")
	)
	(via
		(at 121.92 -340.36)
		(size 0.508)
		(drill 0.254)
		(layers "F.Cu" "B.Cu")
		(net "GND")
	)
	(via
		(at 147.32 -81.28)
		(size 0.508)
		(drill 0.254)
		(layers "F.Cu" "B.Cu")
		(net "GND")
	)
	(via
		(at 230.757222 -34.674302)
		(size 0.508)
		(drill 0.254)
		(layers "F.Cu" "B.Cu")
		(net "GND")
	)
	(via
		(at 121.92 -447.04)
		(size 0.508)
		(drill 0.254)
		(layers "F.Cu" "B.Cu")
		(net "GND")
	)
	(via
		(at 76.2 -477.52)
		(size 0.508)
		(drill 0.254)
		(layers "F.Cu" "B.Cu")
		(net "GND")
	)
	(via
		(at 187.96 -386.08)
		(size 0.508)
		(drill 0.254)
		(layers "F.Cu" "B.Cu")
		(net "GND")
	)
	(via
		(at 24.384 -15.460472)
		(size 0.508)
		(drill 0.254)
		(layers "F.Cu" "B.Cu")
		(net "GND")
	)
	(via
		(at 71.12 -208.28)
		(size 0.508)
		(drill 0.254)
		(layers "F.Cu" "B.Cu")
		(net "GND")
	)
	(via
		(at 137.16 -137.16)
		(size 0.508)
		(drill 0.254)
		(layers "F.Cu" "B.Cu")
		(net "GND")
	)
	(via
		(at 55.88 -162.56)
		(size 0.508)
		(drill 0.254)
		(layers "F.Cu" "B.Cu")
		(net "GND")
	)
	(via
		(at 223.52 -116.84)
		(size 0.508)
		(drill 0.254)
		(layers "F.Cu" "B.Cu")
		(net "GND")
	)
	(via
		(at 76.2 -325.12)
		(size 0.508)
		(drill 0.254)
		(layers "F.Cu" "B.Cu")
		(net "GND")
	)
	(via
		(at 4.191 -444.246)
		(size 0.508)
		(drill 0.254)
		(layers "F.Cu" "B.Cu")
		(net "GND")
	)
	(via
		(at 137.16 -426.72)
		(size 0.508)
		(drill 0.254)
		(layers "F.Cu" "B.Cu")
		(net "GND")
	)
	(via
		(at 234.4166 -266.2047)
		(size 0.508)
		(drill 0.254)
		(layers "F.Cu" "B.Cu")
		(net "GND")
	)
	(via
		(at 116.84 -447.04)
		(size 0.508)
		(drill 0.254)
		(layers "F.Cu" "B.Cu")
		(net "GND")
	)
	(via
		(at 222.616014 -270.99006)
		(size 0.508)
		(drill 0.254)
		(layers "F.Cu" "B.Cu")
		(net "GND")
	)
	(via
		(at 111.76 -20.32)
		(size 0.508)
		(drill 0.254)
		(layers "F.Cu" "B.Cu")
		(net "GND")
	)
	(via
		(at 243.84 -15.24)
		(size 0.508)
		(drill 0.254)
		(layers "F.Cu" "B.Cu")
		(net "GND")
	)
	(via
		(at 248.92 -142.24)
		(size 0.508)
		(drill 0.254)
		(layers "F.Cu" "B.Cu")
		(net "GND")
	)
	(via
		(at 257.189986 -504.603004)
		(size 0.508)
		(drill 0.254)
		(layers "F.Cu" "B.Cu")
		(net "GND")
	)
	(via
		(at 259.08 -238.76)
		(size 0.508)
		(drill 0.254)
		(layers "F.Cu" "B.Cu")
		(net "GND")
	)
	(via
		(at 259.08 -172.72)
		(size 0.508)
		(drill 0.254)
		(layers "F.Cu" "B.Cu")
		(net "GND")
	)
	(via
		(at 4.191 -411.48)
		(size 0.508)
		(drill 0.254)
		(layers "F.Cu" "B.Cu")
		(net "GND")
	)
	(via
		(at 254 -309.88)
		(size 0.508)
		(drill 0.254)
		(layers "F.Cu" "B.Cu")
		(net "GND")
	)
	(via
		(at 182.88 -294.64)
		(size 0.508)
		(drill 0.254)
		(layers "F.Cu" "B.Cu")
		(net "GND")
	)
	(via
		(at 219.314014 -382.399032)
		(size 0.508)
		(drill 0.254)
		(layers "F.Cu" "B.Cu")
		(net "GND")
	)
	(via
		(at 137.16 -350.52)
		(size 0.508)
		(drill 0.254)
		(layers "F.Cu" "B.Cu")
		(net "GND")
	)
	(via
		(at 172.72 -15.24)
		(size 0.508)
		(drill 0.254)
		(layers "F.Cu" "B.Cu")
		(net "GND")
	)
	(via
		(at 24.384 -223.810068)
		(size 0.508)
		(drill 0.254)
		(layers "F.Cu" "B.Cu")
		(net "GND")
	)
	(via
		(at 82.563462 -198.793608)
		(size 0.508)
		(drill 0.254)
		(layers "F.Cu" "B.Cu")
		(net "GND")
	)
	(via
		(at 218.313 -187.5282)
		(size 0.508)
		(drill 0.254)
		(layers "F.Cu" "B.Cu")
		(net "GND")
	)
	(via
		(at 10.541 -296.037)
		(size 0.508)
		(drill 0.254)
		(layers "F.Cu" "B.Cu")
		(net "GND")
	)
	(via
		(at 49.403 -60.173108)
		(size 0.508)
		(drill 0.254)
		(layers "F.Cu" "B.Cu")
		(net "GND")
	)
	(via
		(at 92.71 -430.403)
		(size 0.508)
		(drill 0.254)
		(layers "F.Cu" "B.Cu")
		(net "GND")
	)
	(via
		(at 187.96 -25.4)
		(size 0.508)
		(drill 0.254)
		(layers "F.Cu" "B.Cu")
		(net "GND")
	)
	(via
		(at 51.08575 -243.1288)
		(size 0.508)
		(drill 0.254)
		(layers "F.Cu" "B.Cu")
		(net "GND")
	)
	(via
		(at 43.188636 -7.99465)
		(size 0.508)
		(drill 0.254)
		(layers "F.Cu" "B.Cu")
		(net "GND")
	)
	(via
		(at 187.96 -111.76)
		(size 0.508)
		(drill 0.254)
		(layers "F.Cu" "B.Cu")
		(net "GND")
	)
	(via
		(at 147.32 -299.72)
		(size 0.508)
		(drill 0.254)
		(layers "F.Cu" "B.Cu")
		(net "GND")
	)
	(via
		(at 177.8 -167.64)
		(size 0.508)
		(drill 0.254)
		(layers "F.Cu" "B.Cu")
		(net "GND")
	)
	(via
		(at 29.6164 -11.8872)
		(size 0.508)
		(drill 0.254)
		(layers "F.Cu" "B.Cu")
		(net "GND")
	)
	(via
		(at 29.591 -382.397)
		(size 0.508)
		(drill 0.254)
		(layers "F.Cu" "B.Cu")
		(net "GND")
	)
	(via
		(at 218.44 -472.44)
		(size 0.508)
		(drill 0.254)
		(layers "F.Cu" "B.Cu")
		(net "GND")
	)
	(via
		(at 111.76 -40.64)
		(size 0.508)
		(drill 0.254)
		(layers "F.Cu" "B.Cu")
		(net "GND")
	)
	(via
		(at 24.384 -336.410046)
		(size 0.508)
		(drill 0.254)
		(layers "F.Cu" "B.Cu")
		(net "GND")
	)
	(via
		(at 167.64 -218.44)
		(size 0.508)
		(drill 0.254)
		(layers "F.Cu" "B.Cu")
		(net "GND")
	)
	(via
		(at 137.16 -60.96)
		(size 0.508)
		(drill 0.254)
		(layers "F.Cu" "B.Cu")
		(net "GND")
	)
	(via
		(at 37.61613 -369.190016)
		(size 0.508)
		(drill 0.254)
		(layers "F.Cu" "B.Cu")
		(net "GND")
	)
	(via
		(at 116.84 -487.68)
		(size 0.508)
		(drill 0.254)
		(layers "F.Cu" "B.Cu")
		(net "GND")
	)
	(via
		(at 77.4954 -103.5558)
		(size 0.508)
		(drill 0.254)
		(layers "F.Cu" "B.Cu")
		(net "GND")
	)
	(via
		(at 91.186 -210.82)
		(size 0.508)
		(drill 0.254)
		(layers "F.Cu" "B.Cu")
		(net "GND")
	)
	(via
		(at 5.08 -25.4)
		(size 0.508)
		(drill 0.254)
		(layers "F.Cu" "B.Cu")
		(net "GND")
	)
	(via
		(at 60.96 -20.32)
		(size 0.508)
		(drill 0.254)
		(layers "F.Cu" "B.Cu")
		(net "GND")
	)
	(via
		(at 222.616014 -73.789794)
		(size 0.508)
		(drill 0.254)
		(layers "F.Cu" "B.Cu")
		(net "GND")
	)
	(via
		(at 137.16 -365.76)
		(size 0.508)
		(drill 0.254)
		(layers "F.Cu" "B.Cu")
		(net "GND")
	)
	(via
		(at 34.26333 -483.87508)
		(size 0.508)
		(drill 0.254)
		(layers "F.Cu" "B.Cu")
		(net "GND")
	)
	(via
		(at 24.384 -219.009976)
		(size 0.508)
		(drill 0.254)
		(layers "F.Cu" "B.Cu")
		(net "GND")
	)
	(via
		(at 45.72 -492.76)
		(size 0.508)
		(drill 0.254)
		(layers "F.Cu" "B.Cu")
		(net "GND")
	)
	(via
		(at 127 -264.16)
		(size 0.508)
		(drill 0.254)
		(layers "F.Cu" "B.Cu")
		(net "GND")
	)
	(via
		(at 222.377 -197.231)
		(size 0.508)
		(drill 0.254)
		(layers "F.Cu" "B.Cu")
		(net "GND")
	)
	(via
		(at 111.76 -15.24)
		(size 0.508)
		(drill 0.254)
		(layers "F.Cu" "B.Cu")
		(net "GND")
	)
	(via
		(at 237.49 -394.97)
		(size 0.7112)
		(drill 0.4064)
		(layers "F.Cu" "B.Cu")
		(net "GND")
	)
	(via
		(at 127 -274.32)
		(size 0.508)
		(drill 0.254)
		(layers "F.Cu" "B.Cu")
		(net "GND")
	)
	(via
		(at 208.28 -35.56)
		(size 0.508)
		(drill 0.254)
		(layers "F.Cu" "B.Cu")
		(net "GND")
	)
	(via
		(at 4.191 -448.31)
		(size 0.508)
		(drill 0.254)
		(layers "F.Cu" "B.Cu")
		(net "GND")
	)
	(via
		(at 6.223 -442.73851)
		(size 0.508)
		(drill 0.254)
		(layers "F.Cu" "B.Cu")
		(net "GND")
	)
	(via
		(at 93.984572 -1.397)
		(size 0.508)
		(drill 0.254)
		(layers "F.Cu" "B.Cu")
		(net "GND")
	)
	(via
		(at 254 -243.84)
		(size 0.508)
		(drill 0.254)
		(layers "F.Cu" "B.Cu")
		(net "GND")
	)
	(via
		(at 55.88 -66.04)
		(size 0.508)
		(drill 0.254)
		(layers "F.Cu" "B.Cu")
		(net "GND")
	)
	(via
		(at 44.828968 -264.700766)
		(size 0.508)
		(drill 0.254)
		(layers "F.Cu" "B.Cu")
		(net "GND")
	)
	(via
		(at 66.04 -55.88)
		(size 0.508)
		(drill 0.254)
		(layers "F.Cu" "B.Cu")
		(net "GND")
	)
	(via
		(at 106.68 -243.84)
		(size 0.508)
		(drill 0.254)
		(layers "F.Cu" "B.Cu")
		(net "GND")
	)
	(via
		(at 132.08 -172.72)
		(size 0.508)
		(drill 0.254)
		(layers "F.Cu" "B.Cu")
		(net "GND")
	)
	(via
		(at 223.52 -233.68)
		(size 0.508)
		(drill 0.254)
		(layers "F.Cu" "B.Cu")
		(net "GND")
	)
	(via
		(at 233.68 -233.68)
		(size 0.508)
		(drill 0.254)
		(layers "F.Cu" "B.Cu")
		(net "GND")
	)
	(via
		(at 93.98 -429.006)
		(size 0.508)
		(drill 0.254)
		(layers "F.Cu" "B.Cu")
		(net "GND")
	)
	(via
		(at 248.92 -111.76)
		(size 0.508)
		(drill 0.254)
		(layers "F.Cu" "B.Cu")
		(net "GND")
	)
	(via
		(at 262.103108 -143.158464)
		(size 0.508)
		(drill 0.254)
		(layers "F.Cu" "B.Cu")
		(net "GND")
	)
	(via
		(at 238.76 -254)
		(size 0.508)
		(drill 0.254)
		(layers "F.Cu" "B.Cu")
		(net "GND")
	)
	(via
		(at 177.8 -345.44)
		(size 0.508)
		(drill 0.254)
		(layers "F.Cu" "B.Cu")
		(net "GND")
	)
	(via
		(at 101.6 -198.12)
		(size 0.508)
		(drill 0.254)
		(layers "F.Cu" "B.Cu")
		(net "GND")
	)
	(via
		(at 248.92 -45.72)
		(size 0.508)
		(drill 0.254)
		(layers "F.Cu" "B.Cu")
		(net "GND")
	)
	(via
		(at 162.56 -467.36)
		(size 0.508)
		(drill 0.254)
		(layers "F.Cu" "B.Cu")
		(net "GND")
	)
	(via
		(at 193.04 -40.64)
		(size 0.508)
		(drill 0.254)
		(layers "F.Cu" "B.Cu")
		(net "GND")
	)
	(via
		(at 147.32 -208.28)
		(size 0.508)
		(drill 0.254)
		(layers "F.Cu" "B.Cu")
		(net "GND")
	)
	(via
		(at 86.36 -243.84)
		(size 0.508)
		(drill 0.254)
		(layers "F.Cu" "B.Cu")
		(net "GND")
	)
	(via
		(at 15.748 -187.071)
		(size 0.508)
		(drill 0.254)
		(layers "F.Cu" "B.Cu")
		(net "GND")
	)
	(via
		(at 157.48 -106.68)
		(size 0.508)
		(drill 0.254)
		(layers "F.Cu" "B.Cu")
		(net "GND")
	)
	(via
		(at 27.813 -377.444)
		(size 0.508)
		(drill 0.254)
		(layers "F.Cu" "B.Cu")
		(net "GND")
	)
	(via
		(at 157.48 -101.6)
		(size 0.508)
		(drill 0.254)
		(layers "F.Cu" "B.Cu")
		(net "GND")
	)
	(via
		(at 10.5918 -478.4598)
		(size 0.508)
		(drill 0.254)
		(layers "F.Cu" "B.Cu")
		(net "GND")
	)
	(via
		(at 137.16 -142.24)
		(size 0.508)
		(drill 0.254)
		(layers "F.Cu" "B.Cu")
		(net "GND")
	)
	(via
		(at 187.96 -50.8)
		(size 0.508)
		(drill 0.254)
		(layers "F.Cu" "B.Cu")
		(net "GND")
	)
	(via
		(at 162.56 -457.2)
		(size 0.508)
		(drill 0.254)
		(layers "F.Cu" "B.Cu")
		(net "GND")
	)
	(via
		(at 25.5016 -103.124)
		(size 0.508)
		(drill 0.254)
		(layers "F.Cu" "B.Cu")
		(net "GND")
	)
	(via
		(at 79.629 -201.168)
		(size 0.508)
		(drill 0.254)
		(layers "F.Cu" "B.Cu")
		(net "GND")
	)
	(via
		(at 6.223 -436.338472)
		(size 0.508)
		(drill 0.254)
		(layers "F.Cu" "B.Cu")
		(net "GND")
	)
	(via
		(at 81.661 -204.978)
		(size 0.508)
		(drill 0.254)
		(layers "F.Cu" "B.Cu")
		(net "GND")
	)
	(via
		(at 238.76 -152.4)
		(size 0.508)
		(drill 0.254)
		(layers "F.Cu" "B.Cu")
		(net "GND")
	)
	(via
		(at 91.44 -259.08)
		(size 0.508)
		(drill 0.254)
		(layers "F.Cu" "B.Cu")
		(net "GND")
	)
	(via
		(at 9.398 -366.649)
		(size 0.508)
		(drill 0.254)
		(layers "F.Cu" "B.Cu")
		(net "GND")
	)
	(via
		(at 182.88 -137.16)
		(size 0.508)
		(drill 0.254)
		(layers "F.Cu" "B.Cu")
		(net "GND")
	)
	(via
		(at 223.52 -340.36)
		(size 0.508)
		(drill 0.254)
		(layers "F.Cu" "B.Cu")
		(net "GND")
	)
	(via
		(at 262.103108 -224.438464)
		(size 0.508)
		(drill 0.254)
		(layers "F.Cu" "B.Cu")
		(net "GND")
	)
	(via
		(at 60.96 -426.72)
		(size 0.508)
		(drill 0.254)
		(layers "F.Cu" "B.Cu")
		(net "GND")
	)
	(via
		(at 41.945052 -136.271)
		(size 0.508)
		(drill 0.254)
		(layers "F.Cu" "B.Cu")
		(net "GND")
	)
	(via
		(at 60.96 -81.28)
		(size 0.508)
		(drill 0.254)
		(layers "F.Cu" "B.Cu")
		(net "GND")
	)
	(via
		(at 99.064572 -1.397)
		(size 0.508)
		(drill 0.254)
		(layers "F.Cu" "B.Cu")
		(net "GND")
	)
	(via
		(at 190.504572 -1.397)
		(size 0.508)
		(drill 0.254)
		(layers "F.Cu" "B.Cu")
		(net "GND")
	)
	(via
		(at 37.61613 -476.990156)
		(size 0.508)
		(drill 0.254)
		(layers "F.Cu" "B.Cu")
		(net "GND")
	)
	(via
		(at 218.44 -30.48)
		(size 0.508)
		(drill 0.254)
		(layers "F.Cu" "B.Cu")
		(net "GND")
	)
	(via
		(at 66.04 -182.88)
		(size 0.508)
		(drill 0.254)
		(layers "F.Cu" "B.Cu")
		(net "GND")
	)
	(via
		(at 234.6452 -396.0622)
		(size 0.508)
		(drill 0.254)
		(layers "F.Cu" "B.Cu")
		(net "GND")
	)
	(via
		(at 152.4 -106.68)
		(size 0.508)
		(drill 0.254)
		(layers "F.Cu" "B.Cu")
		(net "GND")
	)
	(via
		(at 240.03 -385.064)
		(size 0.7112)
		(drill 0.4064)
		(layers "F.Cu" "B.Cu")
		(net "GND")
	)
	(via
		(at 106.868722 -308.677564)
		(size 0.508)
		(drill 0.254)
		(layers "F.Cu" "B.Cu")
		(net "GND")
	)
	(via
		(at 36.344098 -356.520242)
		(size 0.508)
		(drill 0.254)
		(layers "F.Cu" "B.Cu")
		(net "GND")
	)
	(via
		(at 35.433 -299.8216)
		(size 0.508)
		(drill 0.254)
		(layers "F.Cu" "B.Cu")
		(net "GND")
	)
	(via
		(at 106.68 -350.52)
		(size 0.508)
		(drill 0.254)
		(layers "F.Cu" "B.Cu")
		(net "GND")
	)
	(via
		(at 35.1028 -16.4846)
		(size 0.508)
		(drill 0.254)
		(layers "F.Cu" "B.Cu")
		(net "GND")
	)
	(via
		(at 125.109986 -504.603004)
		(size 0.508)
		(drill 0.254)
		(layers "F.Cu" "B.Cu")
		(net "GND")
	)
	(via
		(at 31.877 -67.437)
		(size 0.508)
		(drill 0.254)
		(layers "F.Cu" "B.Cu")
		(net "GND")
	)
	(via
		(at 121.92 -177.8)
		(size 0.508)
		(drill 0.254)
		(layers "F.Cu" "B.Cu")
		(net "GND")
	)
	(via
		(at 185.424572 -1.397)
		(size 0.508)
		(drill 0.254)
		(layers "F.Cu" "B.Cu")
		(net "GND")
	)
	(via
		(at 4.191 -326.366124)
		(size 0.508)
		(drill 0.254)
		(layers "F.Cu" "B.Cu")
		(net "GND")
	)
	(via
		(at 37.61613 -176.789842)
		(size 0.508)
		(drill 0.254)
		(layers "F.Cu" "B.Cu")
		(net "GND")
	)
	(via
		(at 91.44 -289.56)
		(size 0.508)
		(drill 0.254)
		(layers "F.Cu" "B.Cu")
		(net "GND")
	)
	(via
		(at 132.08 -116.84)
		(size 0.508)
		(drill 0.254)
		(layers "F.Cu" "B.Cu")
		(net "GND")
	)
	(via
		(at 209.38109 -195.93941)
		(size 0.508)
		(drill 0.254)
		(layers "F.Cu" "B.Cu")
		(net "GND")
	)
	(via
		(at 243.84 -447.04)
		(size 0.508)
		(drill 0.254)
		(layers "F.Cu" "B.Cu")
		(net "GND")
	)
	(via
		(at 12.192 -382.397)
		(size 0.508)
		(drill 0.254)
		(layers "F.Cu" "B.Cu")
		(net "GND")
	)
	(via
		(at 167.64 -309.88)
		(size 0.508)
		(drill 0.254)
		(layers "F.Cu" "B.Cu")
		(net "GND")
	)
	(via
		(at 81.661 -435.102)
		(size 0.508)
		(drill 0.254)
		(layers "F.Cu" "B.Cu")
		(net "GND")
	)
	(via
		(at 93.98 -431.8)
		(size 0.508)
		(drill 0.254)
		(layers "F.Cu" "B.Cu")
		(net "GND")
	)
	(via
		(at 24.384 -20.210018)
		(size 0.508)
		(drill 0.254)
		(layers "F.Cu" "B.Cu")
		(net "GND")
	)
	(via
		(at 213.36 -101.6)
		(size 0.508)
		(drill 0.254)
		(layers "F.Cu" "B.Cu")
		(net "GND")
	)
	(via
		(at 91.44 -254)
		(size 0.508)
		(drill 0.254)
		(layers "F.Cu" "B.Cu")
		(net "GND")
	)
	(via
		(at 15.24 -20.32)
		(size 0.508)
		(drill 0.254)
		(layers "F.Cu" "B.Cu")
		(net "GND")
	)
	(via
		(at 43.58513 -70.844918)
		(size 0.508)
		(drill 0.254)
		(layers "F.Cu" "B.Cu")
		(net "GND")
	)
	(via
		(at 208.28 -502.92)
		(size 0.508)
		(drill 0.254)
		(layers "F.Cu" "B.Cu")
		(net "GND")
	)
	(via
		(at 86.36 -248.92)
		(size 0.508)
		(drill 0.254)
		(layers "F.Cu" "B.Cu")
		(net "GND")
	)
	(via
		(at 28.1178 -501.4214)
		(size 0.508)
		(drill 0.254)
		(layers "F.Cu" "B.Cu")
		(net "GND")
	)
	(via
		(at 52.324 -440.69)
		(size 0.508)
		(drill 0.254)
		(layers "F.Cu" "B.Cu")
		(net "GND")
	)
	(via
		(at 132.08 -101.6)
		(size 0.508)
		(drill 0.254)
		(layers "F.Cu" "B.Cu")
		(net "GND")
	)
	(via
		(at 208.28 -284.48)
		(size 0.508)
		(drill 0.254)
		(layers "F.Cu" "B.Cu")
		(net "GND")
	)
	(via
		(at 248.92 -208.28)
		(size 0.508)
		(drill 0.254)
		(layers "F.Cu" "B.Cu")
		(net "GND")
	)
	(via
		(at 259.08 -254)
		(size 0.508)
		(drill 0.254)
		(layers "F.Cu" "B.Cu")
		(net "GND")
	)
	(via
		(at 167.64 -330.2)
		(size 0.508)
		(drill 0.254)
		(layers "F.Cu" "B.Cu")
		(net "GND")
	)
	(via
		(at 259.08 -111.76)
		(size 0.508)
		(drill 0.254)
		(layers "F.Cu" "B.Cu")
		(net "GND")
	)
	(via
		(at 254 -294.64)
		(size 0.508)
		(drill 0.254)
		(layers "F.Cu" "B.Cu")
		(net "GND")
	)
	(via
		(at 152.4 -452.12)
		(size 0.508)
		(drill 0.254)
		(layers "F.Cu" "B.Cu")
		(net "GND")
	)
	(via
		(at 96.52 -355.6)
		(size 0.508)
		(drill 0.254)
		(layers "F.Cu" "B.Cu")
		(net "GND")
	)
	(via
		(at 213.36 -208.28)
		(size 0.508)
		(drill 0.254)
		(layers "F.Cu" "B.Cu")
		(net "GND")
	)
	(via
		(at 152.4 -187.96)
		(size 0.508)
		(drill 0.254)
		(layers "F.Cu" "B.Cu")
		(net "GND")
	)
	(via
		(at 55.88 -71.12)
		(size 0.508)
		(drill 0.254)
		(layers "F.Cu" "B.Cu")
		(net "GND")
	)
	(via
		(at 71.12 -81.28)
		(size 0.508)
		(drill 0.254)
		(layers "F.Cu" "B.Cu")
		(net "GND")
	)
	(via
		(at 167.64 -45.72)
		(size 0.508)
		(drill 0.254)
		(layers "F.Cu" "B.Cu")
		(net "GND")
	)
	(via
		(at 172.72 -314.96)
		(size 0.508)
		(drill 0.254)
		(layers "F.Cu" "B.Cu")
		(net "GND")
	)
	(via
		(at 11.176 -482.6)
		(size 0.508)
		(drill 0.254)
		(layers "F.Cu" "B.Cu")
		(net "GND")
	)
	(via
		(at 202.99807 -497.975128)
		(size 0.508)
		(drill 0.254)
		(layers "F.Cu" "B.Cu")
		(net "GND")
	)
	(via
		(at 218.313 -291.4904)
		(size 0.508)
		(drill 0.254)
		(layers "F.Cu" "B.Cu")
		(net "GND")
	)
	(via
		(at 4.191 -346.290138)
		(size 0.508)
		(drill 0.254)
		(layers "F.Cu" "B.Cu")
		(net "GND")
	)
	(via
		(at 248.92 -66.04)
		(size 0.508)
		(drill 0.254)
		(layers "F.Cu" "B.Cu")
		(net "GND")
	)
	(via
		(at 157.48 -381)
		(size 0.508)
		(drill 0.254)
		(layers "F.Cu" "B.Cu")
		(net "GND")
	)
	(via
		(at 86.36 -10.16)
		(size 0.508)
		(drill 0.254)
		(layers "F.Cu" "B.Cu")
		(net "GND")
	)
	(via
		(at 259.08 -274.32)
		(size 0.508)
		(drill 0.254)
		(layers "F.Cu" "B.Cu")
		(net "GND")
	)
	(via
		(at 193.04 -330.2)
		(size 0.508)
		(drill 0.254)
		(layers "F.Cu" "B.Cu")
		(net "GND")
	)
	(via
		(at 142.24 -66.04)
		(size 0.508)
		(drill 0.254)
		(layers "F.Cu" "B.Cu")
		(net "GND")
	)
	(via
		(at 238.76 -91.44)
		(size 0.508)
		(drill 0.254)
		(layers "F.Cu" "B.Cu")
		(net "GND")
	)
	(via
		(at 142.24 -177.8)
		(size 0.508)
		(drill 0.254)
		(layers "F.Cu" "B.Cu")
		(net "GND")
	)
	(via
		(at 182.88 -218.44)
		(size 0.508)
		(drill 0.254)
		(layers "F.Cu" "B.Cu")
		(net "GND")
	)
	(via
		(at 222.616014 -367.59007)
		(size 0.508)
		(drill 0.254)
		(layers "F.Cu" "B.Cu")
		(net "GND")
	)
	(via
		(at 81.28 -497.84)
		(size 0.508)
		(drill 0.254)
		(layers "F.Cu" "B.Cu")
		(net "GND")
	)
	(via
		(at 213.36 -35.56)
		(size 0.508)
		(drill 0.254)
		(layers "F.Cu" "B.Cu")
		(net "GND")
	)
	(via
		(at 1.397 -248.995946)
		(size 0.508)
		(drill 0.254)
		(layers "F.Cu" "B.Cu")
		(net "GND")
	)
	(via
		(at 248.92 -137.16)
		(size 0.508)
		(drill 0.254)
		(layers "F.Cu" "B.Cu")
		(net "GND")
	)
	(via
		(at 43.942 -388.366)
		(size 0.508)
		(drill 0.254)
		(layers "F.Cu" "B.Cu")
		(net "GND")
	)
	(via
		(at 234.442 -299.7708)
		(size 0.508)
		(drill 0.254)
		(layers "F.Cu" "B.Cu")
		(net "GND")
	)
	(via
		(at 254 -457.2)
		(size 0.508)
		(drill 0.254)
		(layers "F.Cu" "B.Cu")
		(net "GND")
	)
	(via
		(at 167.64 -66.04)
		(size 0.508)
		(drill 0.254)
		(layers "F.Cu" "B.Cu")
		(net "GND")
	)
	(via
		(at 157.48 -5.08)
		(size 0.508)
		(drill 0.254)
		(layers "F.Cu" "B.Cu")
		(net "GND")
	)
	(via
		(at 98.3615 -223.774)
		(size 0.508)
		(drill 0.254)
		(layers "F.Cu" "B.Cu")
		(net "GND")
	)
	(via
		(at 243.84 -431.8)
		(size 0.508)
		(drill 0.254)
		(layers "F.Cu" "B.Cu")
		(net "GND")
	)
	(via
		(at 17.145 -208.915)
		(size 0.508)
		(drill 0.254)
		(layers "F.Cu" "B.Cu")
		(net "GND")
	)
	(via
		(at 24.384 -452.21017)
		(size 0.508)
		(drill 0.254)
		(layers "F.Cu" "B.Cu")
		(net "GND")
	)
	(via
		(at 207.264 -457.454)
		(size 0.508)
		(drill 0.254)
		(layers "F.Cu" "B.Cu")
		(net "GND")
	)
	(via
		(at 71.12 -254)
		(size 0.508)
		(drill 0.254)
		(layers "F.Cu" "B.Cu")
		(net "GND")
	)
	(via
		(at 92.583 -306.578)
		(size 0.508)
		(drill 0.254)
		(layers "F.Cu" "B.Cu")
		(net "GND")
	)
	(via
		(at 37.7444 -207.9498)
		(size 0.508)
		(drill 0.254)
		(layers "F.Cu" "B.Cu")
		(net "GND")
	)
	(via
		(at 60.96 -193.04)
		(size 0.508)
		(drill 0.254)
		(layers "F.Cu" "B.Cu")
		(net "GND")
	)
	(via
		(at 84.201 -209.042)
		(size 0.508)
		(drill 0.254)
		(layers "F.Cu" "B.Cu")
		(net "GND")
	)
	(via
		(at 238.76 -238.76)
		(size 0.508)
		(drill 0.254)
		(layers "F.Cu" "B.Cu")
		(net "GND")
	)
	(via
		(at 96.52 -421.64)
		(size 0.508)
		(drill 0.254)
		(layers "F.Cu" "B.Cu")
		(net "GND")
	)
	(via
		(at 132.08 -15.24)
		(size 0.508)
		(drill 0.254)
		(layers "F.Cu" "B.Cu")
		(net "GND")
	)
	(via
		(at 187.96 -228.6)
		(size 0.508)
		(drill 0.254)
		(layers "F.Cu" "B.Cu")
		(net "GND")
	)
	(via
		(at 219.583 -197.231)
		(size 0.508)
		(drill 0.254)
		(layers "F.Cu" "B.Cu")
		(net "GND")
	)
	(via
		(at 71.12 -320.04)
		(size 0.508)
		(drill 0.254)
		(layers "F.Cu" "B.Cu")
		(net "GND")
	)
	(via
		(at 1.397 -61.209428)
		(size 0.508)
		(drill 0.254)
		(layers "F.Cu" "B.Cu")
		(net "GND")
	)
	(via
		(at 1.397 -71.369428)
		(size 0.508)
		(drill 0.254)
		(layers "F.Cu" "B.Cu")
		(net "GND")
	)
	(via
		(at 111.76 -381)
		(size 0.508)
		(drill 0.254)
		(layers "F.Cu" "B.Cu")
		(net "GND")
	)
	(via
		(at 208.28 -243.84)
		(size 0.508)
		(drill 0.254)
		(layers "F.Cu" "B.Cu")
		(net "GND")
	)
	(via
		(at 91.44 -274.32)
		(size 0.508)
		(drill 0.254)
		(layers "F.Cu" "B.Cu")
		(net "GND")
	)
	(via
		(at 142.24 -25.4)
		(size 0.508)
		(drill 0.254)
		(layers "F.Cu" "B.Cu")
		(net "GND")
	)
	(via
		(at 96.774 -429.006)
		(size 0.508)
		(drill 0.254)
		(layers "F.Cu" "B.Cu")
		(net "GND")
	)
	(via
		(at 93.599 -422.656)
		(size 0.508)
		(drill 0.254)
		(layers "F.Cu" "B.Cu")
		(net "GND")
	)
	(via
		(at 187.96 -325.12)
		(size 0.508)
		(drill 0.254)
		(layers "F.Cu" "B.Cu")
		(net "GND")
	)
	(via
		(at 208.28 -101.6)
		(size 0.508)
		(drill 0.254)
		(layers "F.Cu" "B.Cu")
		(net "GND")
	)
	(via
		(at 20.32 -50.8)
		(size 0.508)
		(drill 0.254)
		(layers "F.Cu" "B.Cu")
		(net "GND")
	)
	(via
		(at 68.584572 -1.397)
		(size 0.508)
		(drill 0.254)
		(layers "F.Cu" "B.Cu")
		(net "GND")
	)
	(via
		(at 75.186794 -301.10938)
		(size 0.508)
		(drill 0.254)
		(layers "F.Cu" "B.Cu")
		(net "GND")
	)
	(via
		(at 18.034 -117.729)
		(size 0.508)
		(drill 0.254)
		(layers "F.Cu" "B.Cu")
		(net "GND")
	)
	(via
		(at 93.98 -213.614)
		(size 0.508)
		(drill 0.254)
		(layers "F.Cu" "B.Cu")
		(net "GND")
	)
	(via
		(at 220.345 -474.98)
		(size 0.508)
		(drill 0.254)
		(layers "F.Cu" "B.Cu")
		(net "GND")
	)
	(via
		(at 101.6 -421.64)
		(size 0.508)
		(drill 0.254)
		(layers "F.Cu" "B.Cu")
		(net "GND")
	)
	(via
		(at 94.248986 -229.450138)
		(size 0.508)
		(drill 0.254)
		(layers "F.Cu" "B.Cu")
		(net "GND")
	)
	(via
		(at 157.48 -55.88)
		(size 0.508)
		(drill 0.254)
		(layers "F.Cu" "B.Cu")
		(net "GND")
	)
	(via
		(at 203.2 -96.52)
		(size 0.508)
		(drill 0.254)
		(layers "F.Cu" "B.Cu")
		(net "GND")
	)
	(via
		(at 203.2 -198.12)
		(size 0.508)
		(drill 0.254)
		(layers "F.Cu" "B.Cu")
		(net "GND")
	)
	(via
		(at 94.012512 -91.779598)
		(size 0.508)
		(drill 0.254)
		(layers "F.Cu" "B.Cu")
		(net "GND")
	)
	(via
		(at 17.018 -68.326)
		(size 0.508)
		(drill 0.254)
		(layers "F.Cu" "B.Cu")
		(net "GND")
	)
	(via
		(at 218.44 -350.52)
		(size 0.508)
		(drill 0.254)
		(layers "F.Cu" "B.Cu")
		(net "GND")
	)
	(via
		(at 12.192 -376.428)
		(size 0.508)
		(drill 0.254)
		(layers "F.Cu" "B.Cu")
		(net "GND")
	)
	(via
		(at 233.68 -335.28)
		(size 0.508)
		(drill 0.254)
		(layers "F.Cu" "B.Cu")
		(net "GND")
	)
	(via
		(at 196.229986 -504.603004)
		(size 0.508)
		(drill 0.254)
		(layers "F.Cu" "B.Cu")
		(net "GND")
	)
	(via
		(at 1.397 -501.31599)
		(size 0.508)
		(drill 0.254)
		(layers "F.Cu" "B.Cu")
		(net "GND")
	)
	(via
		(at 34.28873 -76.649072)
		(size 0.508)
		(drill 0.254)
		(layers "F.Cu" "B.Cu")
		(net "GND")
	)
	(via
		(at 34.288222 -181.130956)
		(size 0.508)
		(drill 0.254)
		(layers "F.Cu" "B.Cu")
		(net "GND")
	)
	(via
		(at 32.5628 -482.6762)
		(size 0.508)
		(drill 0.254)
		(layers "F.Cu" "B.Cu")
		(net "GND")
	)
	(via
		(at 162.56 -203.2)
		(size 0.508)
		(drill 0.254)
		(layers "F.Cu" "B.Cu")
		(net "GND")
	)
	(via
		(at 37.61613 -76.18984)
		(size 0.508)
		(drill 0.254)
		(layers "F.Cu" "B.Cu")
		(net "GND")
	)
	(via
		(at 76.2 -148.717)
		(size 0.508)
		(drill 0.254)
		(layers "F.Cu" "B.Cu")
		(net "GND")
	)
	(via
		(at 91.44 -497.84)
		(size 0.508)
		(drill 0.254)
		(layers "F.Cu" "B.Cu")
		(net "GND")
	)
	(via
		(at 182.88 -167.64)
		(size 0.508)
		(drill 0.254)
		(layers "F.Cu" "B.Cu")
		(net "GND")
	)
	(via
		(at 172.72 -284.48)
		(size 0.508)
		(drill 0.254)
		(layers "F.Cu" "B.Cu")
		(net "GND")
	)
	(via
		(at 4.191 -354.366068)
		(size 0.508)
		(drill 0.254)
		(layers "F.Cu" "B.Cu")
		(net "GND")
	)
	(via
		(at 218.44 -248.92)
		(size 0.508)
		(drill 0.254)
		(layers "F.Cu" "B.Cu")
		(net "GND")
	)
	(via
		(at 219.302838 -181.17312)
		(size 0.508)
		(drill 0.254)
		(layers "F.Cu" "B.Cu")
		(net "GND")
	)
	(via
		(at 248.92 -457.2)
		(size 0.508)
		(drill 0.254)
		(layers "F.Cu" "B.Cu")
		(net "GND")
	)
	(via
		(at 14.44625 -496.3795)
		(size 0.508)
		(drill 0.254)
		(layers "F.Cu" "B.Cu")
		(net "GND")
	)
	(via
		(at 31.614364 -93.98635)
		(size 0.508)
		(drill 0.254)
		(layers "F.Cu" "B.Cu")
		(net "GND")
	)
	(via
		(at 101.6 -360.68)
		(size 0.508)
		(drill 0.254)
		(layers "F.Cu" "B.Cu")
		(net "GND")
	)
	(via
		(at 228.6 -30.48)
		(size 0.508)
		(drill 0.254)
		(layers "F.Cu" "B.Cu")
		(net "GND")
	)
	(via
		(at 93.599 -110.744)
		(size 0.508)
		(drill 0.254)
		(layers "F.Cu" "B.Cu")
		(net "GND")
	)
	(via
		(at 218.44 -15.24)
		(size 0.508)
		(drill 0.254)
		(layers "F.Cu" "B.Cu")
		(net "GND")
	)
	(via
		(at 198.12 -152.4)
		(size 0.508)
		(drill 0.254)
		(layers "F.Cu" "B.Cu")
		(net "GND")
	)
	(via
		(at 6.223 -430.738534)
		(size 0.508)
		(drill 0.254)
		(layers "F.Cu" "B.Cu")
		(net "GND")
	)
	(via
		(at 37.3634 -197.0024)
		(size 0.508)
		(drill 0.254)
		(layers "F.Cu" "B.Cu")
		(net "GND")
	)
	(via
		(at 32.7152 -470.916)
		(size 0.508)
		(drill 0.254)
		(layers "F.Cu" "B.Cu")
		(net "GND")
	)
	(via
		(at 24.384 -241.409982)
		(size 0.508)
		(drill 0.254)
		(layers "F.Cu" "B.Cu")
		(net "GND")
	)
	(via
		(at 6.223 -444.44285)
		(size 0.508)
		(drill 0.254)
		(layers "F.Cu" "B.Cu")
		(net "GND")
	)
	(via
		(at 208.28 -309.88)
		(size 0.508)
		(drill 0.254)
		(layers "F.Cu" "B.Cu")
		(net "GND")
	)
	(via
		(at 259.08 -121.92)
		(size 0.508)
		(drill 0.254)
		(layers "F.Cu" "B.Cu")
		(net "GND")
	)
	(via
		(at 203.2 -487.68)
		(size 0.508)
		(drill 0.254)
		(layers "F.Cu" "B.Cu")
		(net "GND")
	)
	(via
		(at 73.664572 -1.397)
		(size 0.508)
		(drill 0.254)
		(layers "F.Cu" "B.Cu")
		(net "GND")
	)
	(via
		(at 251.5362 -358.775)
		(size 0.508)
		(drill 0.254)
		(layers "F.Cu" "B.Cu")
		(net "GND")
	)
	(via
		(at 121.92 -426.72)
		(size 0.508)
		(drill 0.254)
		(layers "F.Cu" "B.Cu")
		(net "GND")
	)
	(via
		(at 248.92 -330.2)
		(size 0.508)
		(drill 0.254)
		(layers "F.Cu" "B.Cu")
		(net "GND")
	)
	(via
		(at 177.8 -25.4)
		(size 0.508)
		(drill 0.254)
		(layers "F.Cu" "B.Cu")
		(net "GND")
	)
	(via
		(at 253.865126 -488.56011)
		(size 0.508)
		(drill 0.254)
		(layers "F.Cu" "B.Cu")
		(net "GND")
	)
	(via
		(at 116.84 -299.72)
		(size 0.508)
		(drill 0.254)
		(layers "F.Cu" "B.Cu")
		(net "GND")
	)
	(via
		(at 248.92 -472.44)
		(size 0.508)
		(drill 0.254)
		(layers "F.Cu" "B.Cu")
		(net "GND")
	)
	(via
		(at 84.963 -419.1)
		(size 0.508)
		(drill 0.254)
		(layers "F.Cu" "B.Cu")
		(net "GND")
	)
	(via
		(at 157.48 -45.72)
		(size 0.508)
		(drill 0.254)
		(layers "F.Cu" "B.Cu")
		(net "GND")
	)
	(via
		(at 34.28873 -78.130908)
		(size 0.508)
		(drill 0.254)
		(layers "F.Cu" "B.Cu")
		(net "GND")
	)
	(via
		(at 147.32 -340.36)
		(size 0.508)
		(drill 0.254)
		(layers "F.Cu" "B.Cu")
		(net "GND")
	)
	(via
		(at 5.588 -459.5114)
		(size 0.7112)
		(drill 0.4064)
		(layers "F.Cu" "B.Cu")
		(net "GND")
	)
	(via
		(at 92.583 -210.82)
		(size 0.508)
		(drill 0.254)
		(layers "F.Cu" "B.Cu")
		(net "GND")
	)
	(via
		(at 135.269986 -504.603004)
		(size 0.508)
		(drill 0.254)
		(layers "F.Cu" "B.Cu")
		(net "GND")
	)
	(via
		(at 238.76 -127)
		(size 0.508)
		(drill 0.254)
		(layers "F.Cu" "B.Cu")
		(net "GND")
	)
	(via
		(at 1.397 -45.969428)
		(size 0.508)
		(drill 0.254)
		(layers "F.Cu" "B.Cu")
		(net "GND")
	)
	(via
		(at 60.96 -259.08)
		(size 0.508)
		(drill 0.254)
		(layers "F.Cu" "B.Cu")
		(net "GND")
	)
	(via
		(at 262.103108 -214.278464)
		(size 0.508)
		(drill 0.254)
		(layers "F.Cu" "B.Cu")
		(net "GND")
	)
	(via
		(at 219.314014 -157.127956)
		(size 0.508)
		(drill 0.254)
		(layers "F.Cu" "B.Cu")
		(net "GND")
	)
	(via
		(at 106.68 -10.16)
		(size 0.508)
		(drill 0.254)
		(layers "F.Cu" "B.Cu")
		(net "GND")
	)
	(via
		(at 37.61613 -156.789882)
		(size 0.508)
		(drill 0.254)
		(layers "F.Cu" "B.Cu")
		(net "GND")
	)
	(via
		(at 218.44 -320.04)
		(size 0.508)
		(drill 0.254)
		(layers "F.Cu" "B.Cu")
		(net "GND")
	)
	(via
		(at 24.384 -237.40999)
		(size 0.508)
		(drill 0.254)
		(layers "F.Cu" "B.Cu")
		(net "GND")
	)
	(via
		(at 203.2 -187.96)
		(size 0.508)
		(drill 0.254)
		(layers "F.Cu" "B.Cu")
		(net "GND")
	)
	(via
		(at 50.8 -294.64)
		(size 0.508)
		(drill 0.254)
		(layers "F.Cu" "B.Cu")
		(net "GND")
	)
	(via
		(at 37.61613 -279.78989)
		(size 0.508)
		(drill 0.254)
		(layers "F.Cu" "B.Cu")
		(net "GND")
	)
	(via
		(at 1.397 -66.289428)
		(size 0.508)
		(drill 0.254)
		(layers "F.Cu" "B.Cu")
		(net "GND")
	)
	(via
		(at 222.616014 -71.390002)
		(size 0.508)
		(drill 0.254)
		(layers "F.Cu" "B.Cu")
		(net "GND")
	)
	(via
		(at 193.04 -106.68)
		(size 0.508)
		(drill 0.254)
		(layers "F.Cu" "B.Cu")
		(net "GND")
	)
	(via
		(at 18.415 -42.204894)
		(size 0.508)
		(drill 0.254)
		(layers "F.Cu" "B.Cu")
		(net "GND")
	)
	(via
		(at 247.65 -392.43)
		(size 0.7112)
		(drill 0.4064)
		(layers "F.Cu" "B.Cu")
		(net "GND")
	)
	(via
		(at 66.04 -152.4)
		(size 0.508)
		(drill 0.254)
		(layers "F.Cu" "B.Cu")
		(net "GND")
	)
	(via
		(at 167.64 -452.12)
		(size 0.508)
		(drill 0.254)
		(layers "F.Cu" "B.Cu")
		(net "GND")
	)
	(via
		(at 147.32 -492.76)
		(size 0.508)
		(drill 0.254)
		(layers "F.Cu" "B.Cu")
		(net "GND")
	)
	(via
		(at 177.8 -487.68)
		(size 0.508)
		(drill 0.254)
		(layers "F.Cu" "B.Cu")
		(net "GND")
	)
	(via
		(at 254 -330.2)
		(size 0.508)
		(drill 0.254)
		(layers "F.Cu" "B.Cu")
		(net "GND")
	)
	(via
		(at 172.72 -447.04)
		(size 0.508)
		(drill 0.254)
		(layers "F.Cu" "B.Cu")
		(net "GND")
	)
	(via
		(at 85.299042 -238.84382)
		(size 0.508)
		(drill 0.254)
		(layers "F.Cu" "B.Cu")
		(net "GND")
	)
	(via
		(at 1.397 -30.729428)
		(size 0.508)
		(drill 0.254)
		(layers "F.Cu" "B.Cu")
		(net "GND")
	)
	(via
		(at 60.96 -304.8)
		(size 0.508)
		(drill 0.254)
		(layers "F.Cu" "B.Cu")
		(net "GND")
	)
	(via
		(at 259.08 -193.04)
		(size 0.508)
		(drill 0.254)
		(layers "F.Cu" "B.Cu")
		(net "GND")
	)
	(via
		(at 238.76 -81.28)
		(size 0.508)
		(drill 0.254)
		(layers "F.Cu" "B.Cu")
		(net "GND")
	)
	(via
		(at 244.729 -425.45)
		(size 0.508)
		(drill 0.254)
		(layers "F.Cu" "B.Cu")
		(net "GND")
	)
	(via
		(at 228.585014 -278.115014)
		(size 0.508)
		(drill 0.254)
		(layers "F.Cu" "B.Cu")
		(net "GND")
	)
	(via
		(at 262.103108 -132.998464)
		(size 0.508)
		(drill 0.254)
		(layers "F.Cu" "B.Cu")
		(net "GND")
	)
	(via
		(at 147.32 -350.52)
		(size 0.508)
		(drill 0.254)
		(layers "F.Cu" "B.Cu")
		(net "GND")
	)
	(via
		(at 157.48 -431.8)
		(size 0.508)
		(drill 0.254)
		(layers "F.Cu" "B.Cu")
		(net "GND")
	)
	(via
		(at 243.84 -101.6)
		(size 0.508)
		(drill 0.254)
		(layers "F.Cu" "B.Cu")
		(net "GND")
	)
	(via
		(at 127 -396.24)
		(size 0.508)
		(drill 0.254)
		(layers "F.Cu" "B.Cu")
		(net "GND")
	)
	(via
		(at 37.2872 -403.0726)
		(size 0.508)
		(drill 0.254)
		(layers "F.Cu" "B.Cu")
		(net "GND")
	)
	(via
		(at 73.139554 -23.684484)
		(size 0.7112)
		(drill 0.3556)
		(layers "F.Cu" "B.Cu")
		(net "GND")
	)
	(via
		(at 142.24 -487.68)
		(size 0.508)
		(drill 0.254)
		(layers "F.Cu" "B.Cu")
		(net "GND")
	)
	(via
		(at 213.36 -223.52)
		(size 0.508)
		(drill 0.254)
		(layers "F.Cu" "B.Cu")
		(net "GND")
	)
	(via
		(at 238.76 -187.96)
		(size 0.508)
		(drill 0.254)
		(layers "F.Cu" "B.Cu")
		(net "GND")
	)
	(via
		(at 238.76 -35.56)
		(size 0.508)
		(drill 0.254)
		(layers "F.Cu" "B.Cu")
		(net "GND")
	)
	(via
		(at 4.191 -397.891)
		(size 0.508)
		(drill 0.254)
		(layers "F.Cu" "B.Cu")
		(net "GND")
	)
	(via
		(at 167.64 -477.52)
		(size 0.508)
		(drill 0.254)
		(layers "F.Cu" "B.Cu")
		(net "GND")
	)
	(via
		(at 35.56 -340.36)
		(size 0.508)
		(drill 0.254)
		(layers "F.Cu" "B.Cu")
		(net "GND")
	)
	(via
		(at 230.798116 -161.699702)
		(size 0.508)
		(drill 0.254)
		(layers "F.Cu" "B.Cu")
		(net "GND")
	)
	(via
		(at 111.76 -259.08)
		(size 0.508)
		(drill 0.254)
		(layers "F.Cu" "B.Cu")
		(net "GND")
	)
	(via
		(at 220.599 -372.11)
		(size 0.508)
		(drill 0.254)
		(layers "F.Cu" "B.Cu")
		(net "GND")
	)
	(via
		(at 116.84 -172.72)
		(size 0.508)
		(drill 0.254)
		(layers "F.Cu" "B.Cu")
		(net "GND")
	)
	(via
		(at 127 -81.28)
		(size 0.508)
		(drill 0.254)
		(layers "F.Cu" "B.Cu")
		(net "GND")
	)
	(via
		(at 254 -208.28)
		(size 0.508)
		(drill 0.254)
		(layers "F.Cu" "B.Cu")
		(net "GND")
	)
	(via
		(at 187.96 -55.88)
		(size 0.508)
		(drill 0.254)
		(layers "F.Cu" "B.Cu")
		(net "GND")
	)
	(via
		(at 228.981 -182.372)
		(size 0.508)
		(drill 0.254)
		(layers "F.Cu" "B.Cu")
		(net "GND")
	)
	(via
		(at 233.68 -309.88)
		(size 0.508)
		(drill 0.254)
		(layers "F.Cu" "B.Cu")
		(net "GND")
	)
	(via
		(at 30.988 -373.38)
		(size 0.508)
		(drill 0.254)
		(layers "F.Cu" "B.Cu")
		(net "GND")
	)
	(via
		(at 142.24 -386.08)
		(size 0.508)
		(drill 0.254)
		(layers "F.Cu" "B.Cu")
		(net "GND")
	)
	(via
		(at 96.52 -350.52)
		(size 0.508)
		(drill 0.254)
		(layers "F.Cu" "B.Cu")
		(net "GND")
	)
	(via
		(at 102.108 -305.435)
		(size 0.508)
		(drill 0.254)
		(layers "F.Cu" "B.Cu")
		(net "GND")
	)
	(via
		(at 219.274898 -170.10126)
		(size 0.508)
		(drill 0.254)
		(layers "F.Cu" "B.Cu")
		(net "GND")
	)
	(via
		(at 167.64 -162.56)
		(size 0.508)
		(drill 0.254)
		(layers "F.Cu" "B.Cu")
		(net "GND")
	)
	(via
		(at 243.84 -208.28)
		(size 0.508)
		(drill 0.254)
		(layers "F.Cu" "B.Cu")
		(net "GND")
	)
	(via
		(at 55.88 -157.48)
		(size 0.508)
		(drill 0.254)
		(layers "F.Cu" "B.Cu")
		(net "GND")
	)
	(via
		(at 203.2 -243.84)
		(size 0.508)
		(drill 0.254)
		(layers "F.Cu" "B.Cu")
		(net "GND")
	)
	(via
		(at 4.191 -396.367)
		(size 0.508)
		(drill 0.254)
		(layers "F.Cu" "B.Cu")
		(net "GND")
	)
	(via
		(at 37.61613 -485.789986)
		(size 0.508)
		(drill 0.254)
		(layers "F.Cu" "B.Cu")
		(net "GND")
	)
	(via
		(at 60.96 -457.2)
		(size 0.508)
		(drill 0.254)
		(layers "F.Cu" "B.Cu")
		(net "GND")
	)
	(via
		(at 76.2 -396.24)
		(size 0.508)
		(drill 0.254)
		(layers "F.Cu" "B.Cu")
		(net "GND")
	)
	(via
		(at 193.04 -198.12)
		(size 0.508)
		(drill 0.254)
		(layers "F.Cu" "B.Cu")
		(net "GND")
	)
	(via
		(at 24.638 -412.115)
		(size 0.508)
		(drill 0.254)
		(layers "F.Cu" "B.Cu")
		(net "GND")
	)
	(via
		(at 145.429986 -504.603004)
		(size 0.508)
		(drill 0.254)
		(layers "F.Cu" "B.Cu")
		(net "GND")
	)
	(via
		(at 152.4 -228.6)
		(size 0.508)
		(drill 0.254)
		(layers "F.Cu" "B.Cu")
		(net "GND")
	)
	(via
		(at 233.68 -213.36)
		(size 0.508)
		(drill 0.254)
		(layers "F.Cu" "B.Cu")
		(net "GND")
	)
	(via
		(at 157.48 -497.84)
		(size 0.508)
		(drill 0.254)
		(layers "F.Cu" "B.Cu")
		(net "GND")
	)
	(via
		(at 193.04 -386.08)
		(size 0.508)
		(drill 0.254)
		(layers "F.Cu" "B.Cu")
		(net "GND")
	)
	(via
		(at 5.08 -55.88)
		(size 0.508)
		(drill 0.254)
		(layers "F.Cu" "B.Cu")
		(net "GND")
	)
	(via
		(at 213.36 -350.52)
		(size 0.508)
		(drill 0.254)
		(layers "F.Cu" "B.Cu")
		(net "GND")
	)
	(via
		(at 26.5176 -103.124)
		(size 0.508)
		(drill 0.254)
		(layers "F.Cu" "B.Cu")
		(net "GND")
	)
	(via
		(at 55.88 -167.64)
		(size 0.508)
		(drill 0.254)
		(layers "F.Cu" "B.Cu")
		(net "GND")
	)
	(via
		(at 167.64 -137.16)
		(size 0.508)
		(drill 0.254)
		(layers "F.Cu" "B.Cu")
		(net "GND")
	)
	(via
		(at 111.76 -294.64)
		(size 0.508)
		(drill 0.254)
		(layers "F.Cu" "B.Cu")
		(net "GND")
	)
	(via
		(at 187.96 -121.92)
		(size 0.508)
		(drill 0.254)
		(layers "F.Cu" "B.Cu")
		(net "GND")
	)
	(via
		(at 198.12 -5.08)
		(size 0.508)
		(drill 0.254)
		(layers "F.Cu" "B.Cu")
		(net "GND")
	)
	(via
		(at 101.6 -477.52)
		(size 0.508)
		(drill 0.254)
		(layers "F.Cu" "B.Cu")
		(net "GND")
	)
	(via
		(at 101.6 -330.2)
		(size 0.508)
		(drill 0.254)
		(layers "F.Cu" "B.Cu")
		(net "GND")
	)
	(via
		(at 137.16 -482.6)
		(size 0.508)
		(drill 0.254)
		(layers "F.Cu" "B.Cu")
		(net "GND")
	)
	(via
		(at 132.08 -431.8)
		(size 0.508)
		(drill 0.254)
		(layers "F.Cu" "B.Cu")
		(net "GND")
	)
	(via
		(at 187.96 -441.96)
		(size 0.508)
		(drill 0.254)
		(layers "F.Cu" "B.Cu")
		(net "GND")
	)
	(via
		(at 17.145 -443.516512)
		(size 0.508)
		(drill 0.254)
		(layers "F.Cu" "B.Cu")
		(net "GND")
	)
	(via
		(at 187.96 -223.52)
		(size 0.508)
		(drill 0.254)
		(layers "F.Cu" "B.Cu")
		(net "GND")
	)
	(via
		(at 162.56 -264.16)
		(size 0.508)
		(drill 0.254)
		(layers "F.Cu" "B.Cu")
		(net "GND")
	)
	(via
		(at 222.616014 -167.990012)
		(size 0.508)
		(drill 0.254)
		(layers "F.Cu" "B.Cu")
		(net "GND")
	)
	(via
		(at 37.36975 -40.767)
		(size 0.508)
		(drill 0.254)
		(layers "F.Cu" "B.Cu")
		(net "GND")
	)
	(via
		(at 94.488 -110.744)
		(size 0.508)
		(drill 0.254)
		(layers "F.Cu" "B.Cu")
		(net "GND")
	)
	(via
		(at 27.686 -348.872048)
		(size 0.508)
		(drill 0.254)
		(layers "F.Cu" "B.Cu")
		(net "GND")
	)
	(via
		(at 5.08 -116.84)
		(size 0.508)
		(drill 0.254)
		(layers "F.Cu" "B.Cu")
		(net "GND")
	)
	(via
		(at 167.64 -314.96)
		(size 0.508)
		(drill 0.254)
		(layers "F.Cu" "B.Cu")
		(net "GND")
	)
	(via
		(at 248.92 -309.88)
		(size 0.508)
		(drill 0.254)
		(layers "F.Cu" "B.Cu")
		(net "GND")
	)
	(via
		(at 193.04 -223.52)
		(size 0.508)
		(drill 0.254)
		(layers "F.Cu" "B.Cu")
		(net "GND")
	)
	(via
		(at 27.178 -501.4214)
		(size 0.508)
		(drill 0.254)
		(layers "F.Cu" "B.Cu")
		(net "GND")
	)
	(via
		(at 88.904572 -1.397)
		(size 0.508)
		(drill 0.254)
		(layers "F.Cu" "B.Cu")
		(net "GND")
	)
	(via
		(at 38.749986 -504.603004)
		(size 0.508)
		(drill 0.254)
		(layers "F.Cu" "B.Cu")
		(net "GND")
	)
	(via
		(at 165.104572 -1.397)
		(size 0.508)
		(drill 0.254)
		(layers "F.Cu" "B.Cu")
		(net "GND")
	)
	(via
		(at 92.71 -209.423)
		(size 0.508)
		(drill 0.254)
		(layers "F.Cu" "B.Cu")
		(net "GND")
	)
	(via
		(at 177.8 -132.08)
		(size 0.508)
		(drill 0.254)
		(layers "F.Cu" "B.Cu")
		(net "GND")
	)
	(via
		(at 77.343 -309.245)
		(size 0.508)
		(drill 0.254)
		(layers "F.Cu" "B.Cu")
		(net "GND")
	)
	(via
		(at 137.16 -502.92)
		(size 0.508)
		(drill 0.254)
		(layers "F.Cu" "B.Cu")
		(net "GND")
	)
	(via
		(at 218.44 -264.16)
		(size 0.508)
		(drill 0.254)
		(layers "F.Cu" "B.Cu")
		(net "GND")
	)
	(via
		(at 137.16 -447.04)
		(size 0.508)
		(drill 0.254)
		(layers "F.Cu" "B.Cu")
		(net "GND")
	)
	(via
		(at 238.76 -497.84)
		(size 0.508)
		(drill 0.254)
		(layers "F.Cu" "B.Cu")
		(net "GND")
	)
	(via
		(at 6.223 -393.089892)
		(size 0.508)
		(drill 0.254)
		(layers "F.Cu" "B.Cu")
		(net "GND")
	)
	(via
		(at 132.08 -421.64)
		(size 0.508)
		(drill 0.254)
		(layers "F.Cu" "B.Cu")
		(net "GND")
	)
	(via
		(at 4.191 -339.8901)
		(size 0.508)
		(drill 0.254)
		(layers "F.Cu" "B.Cu")
		(net "GND")
	)
	(via
		(at 66.04 -355.6)
		(size 0.508)
		(drill 0.254)
		(layers "F.Cu" "B.Cu")
		(net "GND")
	)
	(via
		(at 71.12 -492.76)
		(size 0.508)
		(drill 0.254)
		(layers "F.Cu" "B.Cu")
		(net "GND")
	)
	(via
		(at 182.88 -497.84)
		(size 0.508)
		(drill 0.254)
		(layers "F.Cu" "B.Cu")
		(net "GND")
	)
	(via
		(at 106.68 -25.4)
		(size 0.508)
		(drill 0.254)
		(layers "F.Cu" "B.Cu")
		(net "GND")
	)
	(via
		(at 81.28 -71.12)
		(size 0.508)
		(drill 0.254)
		(layers "F.Cu" "B.Cu")
		(net "GND")
	)
	(via
		(at 66.04 -467.36)
		(size 0.508)
		(drill 0.254)
		(layers "F.Cu" "B.Cu")
		(net "GND")
	)
	(via
		(at 100.7745 -300.0375)
		(size 0.508)
		(drill 0.254)
		(layers "F.Cu" "B.Cu")
		(net "GND")
	)
	(via
		(at 81.28 -492.76)
		(size 0.508)
		(drill 0.254)
		(layers "F.Cu" "B.Cu")
		(net "GND")
	)
	(via
		(at 37.61613 -78.589886)
		(size 0.508)
		(drill 0.254)
		(layers "F.Cu" "B.Cu")
		(net "GND")
	)
	(via
		(at 111.76 -25.4)
		(size 0.508)
		(drill 0.254)
		(layers "F.Cu" "B.Cu")
		(net "GND")
	)
	(via
		(at 50.8 -487.68)
		(size 0.508)
		(drill 0.254)
		(layers "F.Cu" "B.Cu")
		(net "GND")
	)
	(via
		(at 193.04 -360.68)
		(size 0.508)
		(drill 0.254)
		(layers "F.Cu" "B.Cu")
		(net "GND")
	)
	(via
		(at 66.04 -111.76)
		(size 0.508)
		(drill 0.254)
		(layers "F.Cu" "B.Cu")
		(net "GND")
	)
	(via
		(at 27.69616 -221.826836)
		(size 0.508)
		(drill 0.254)
		(layers "F.Cu" "B.Cu")
		(net "GND")
	)
	(via
		(at 6.223 -220.222318)
		(size 0.508)
		(drill 0.254)
		(layers "F.Cu" "B.Cu")
		(net "GND")
	)
	(via
		(at 162.56 -309.88)
		(size 0.508)
		(drill 0.254)
		(layers "F.Cu" "B.Cu")
		(net "GND")
	)
	(via
		(at 45.72 -132.08)
		(size 0.508)
		(drill 0.254)
		(layers "F.Cu" "B.Cu")
		(net "GND")
	)
	(via
		(at 167.64 -421.64)
		(size 0.508)
		(drill 0.254)
		(layers "F.Cu" "B.Cu")
		(net "GND")
	)
	(via
		(at 10.16 -492.76)
		(size 0.508)
		(drill 0.254)
		(layers "F.Cu" "B.Cu")
		(net "GND")
	)
	(via
		(at 187.96 -436.88)
		(size 0.508)
		(drill 0.254)
		(layers "F.Cu" "B.Cu")
		(net "GND")
	)
	(via
		(at 167.64 -20.32)
		(size 0.508)
		(drill 0.254)
		(layers "F.Cu" "B.Cu")
		(net "GND")
	)
	(via
		(at 259.08 -248.92)
		(size 0.508)
		(drill 0.254)
		(layers "F.Cu" "B.Cu")
		(net "GND")
	)
	(via
		(at 96.52 -233.68)
		(size 0.508)
		(drill 0.254)
		(layers "F.Cu" "B.Cu")
		(net "GND")
	)
	(via
		(at 33.3502 -85.3186)
		(size 0.508)
		(drill 0.254)
		(layers "F.Cu" "B.Cu")
		(net "GND")
	)
	(via
		(at 259.08 -71.12)
		(size 0.508)
		(drill 0.254)
		(layers "F.Cu" "B.Cu")
		(net "GND")
	)
	(via
		(at 132.08 -162.56)
		(size 0.508)
		(drill 0.254)
		(layers "F.Cu" "B.Cu")
		(net "GND")
	)
	(via
		(at 96.52 -386.08)
		(size 0.508)
		(drill 0.254)
		(layers "F.Cu" "B.Cu")
		(net "GND")
	)
	(via
		(at 247.65 -389.89)
		(size 0.7112)
		(drill 0.4064)
		(layers "F.Cu" "B.Cu")
		(net "GND")
	)
	(via
		(at 182.88 -426.72)
		(size 0.508)
		(drill 0.254)
		(layers "F.Cu" "B.Cu")
		(net "GND")
	)
	(via
		(at 34.31413 -279.398984)
		(size 0.508)
		(drill 0.254)
		(layers "F.Cu" "B.Cu")
		(net "GND")
	)
	(via
		(at 37.61613 -60.189872)
		(size 0.508)
		(drill 0.254)
		(layers "F.Cu" "B.Cu")
		(net "GND")
	)
	(via
		(at 233.68 -116.84)
		(size 0.508)
		(drill 0.254)
		(layers "F.Cu" "B.Cu")
		(net "GND")
	)
	(via
		(at 147.32 -269.24)
		(size 0.508)
		(drill 0.254)
		(layers "F.Cu" "B.Cu")
		(net "GND")
	)
	(via
		(at 147.32 -264.16)
		(size 0.508)
		(drill 0.254)
		(layers "F.Cu" "B.Cu")
		(net "GND")
	)
	(via
		(at 96.52 -10.16)
		(size 0.508)
		(drill 0.254)
		(layers "F.Cu" "B.Cu")
		(net "GND")
	)
	(via
		(at 132.08 -25.4)
		(size 0.508)
		(drill 0.254)
		(layers "F.Cu" "B.Cu")
		(net "GND")
	)
	(via
		(at 162.56 -127)
		(size 0.508)
		(drill 0.254)
		(layers "F.Cu" "B.Cu")
		(net "GND")
	)
	(via
		(at 157.48 -116.84)
		(size 0.508)
		(drill 0.254)
		(layers "F.Cu" "B.Cu")
		(net "GND")
	)
	(via
		(at 111.76 -111.76)
		(size 0.508)
		(drill 0.254)
		(layers "F.Cu" "B.Cu")
		(net "GND")
	)
	(via
		(at 13.349986 -504.603004)
		(size 0.508)
		(drill 0.254)
		(layers "F.Cu" "B.Cu")
		(net "GND")
	)
	(via
		(at 92.583 -433.197)
		(size 0.508)
		(drill 0.254)
		(layers "F.Cu" "B.Cu")
		(net "GND")
	)
	(via
		(at 193.04 -15.24)
		(size 0.508)
		(drill 0.254)
		(layers "F.Cu" "B.Cu")
		(net "GND")
	)
	(via
		(at 162.56 -60.96)
		(size 0.508)
		(drill 0.254)
		(layers "F.Cu" "B.Cu")
		(net "GND")
	)
	(via
		(at 86.36 -172.72)
		(size 0.508)
		(drill 0.254)
		(layers "F.Cu" "B.Cu")
		(net "GND")
	)
	(via
		(at 198.12 -157.48)
		(size 0.508)
		(drill 0.254)
		(layers "F.Cu" "B.Cu")
		(net "GND")
	)
	(via
		(at 157.48 -30.48)
		(size 0.508)
		(drill 0.254)
		(layers "F.Cu" "B.Cu")
		(net "GND")
	)
	(via
		(at 167.64 -127)
		(size 0.508)
		(drill 0.254)
		(layers "F.Cu" "B.Cu")
		(net "GND")
	)
	(via
		(at 209.648552 -430.657)
		(size 0.508)
		(drill 0.254)
		(layers "F.Cu" "B.Cu")
		(net "GND")
	)
	(via
		(at 111.76 -370.84)
		(size 0.508)
		(drill 0.254)
		(layers "F.Cu" "B.Cu")
		(net "GND")
	)
	(via
		(at 75.7428 -182.88)
		(size 0.508)
		(drill 0.254)
		(layers "F.Cu" "B.Cu")
		(net "GND")
	)
	(via
		(at 116.84 -20.32)
		(size 0.508)
		(drill 0.254)
		(layers "F.Cu" "B.Cu")
		(net "GND")
	)
	(via
		(at 208.28 -213.36)
		(size 0.508)
		(drill 0.254)
		(layers "F.Cu" "B.Cu")
		(net "GND")
	)
	(via
		(at 228.6 -259.08)
		(size 0.508)
		(drill 0.254)
		(layers "F.Cu" "B.Cu")
		(net "GND")
	)
	(via
		(at 219.289884 -284.131004)
		(size 0.508)
		(drill 0.254)
		(layers "F.Cu" "B.Cu")
		(net "GND")
	)
	(via
		(at 187.96 -187.96)
		(size 0.508)
		(drill 0.254)
		(layers "F.Cu" "B.Cu")
		(net "GND")
	)
	(via
		(at 223.52 -111.76)
		(size 0.508)
		(drill 0.254)
		(layers "F.Cu" "B.Cu")
		(net "GND")
	)
	(via
		(at 147.32 -213.36)
		(size 0.508)
		(drill 0.254)
		(layers "F.Cu" "B.Cu")
		(net "GND")
	)
	(via
		(at 222.616014 -179.189888)
		(size 0.508)
		(drill 0.254)
		(layers "F.Cu" "B.Cu")
		(net "GND")
	)
	(via
		(at 254 -335.28)
		(size 0.508)
		(drill 0.254)
		(layers "F.Cu" "B.Cu")
		(net "GND")
	)
	(via
		(at 259.08 -30.48)
		(size 0.508)
		(drill 0.254)
		(layers "F.Cu" "B.Cu")
		(net "GND")
	)
	(via
		(at 92.583 -101.6)
		(size 0.508)
		(drill 0.254)
		(layers "F.Cu" "B.Cu")
		(net "GND")
	)
	(via
		(at 188.077856 -380.844552)
		(size 0.7112)
		(drill 0.3556)
		(layers "F.Cu" "B.Cu")
		(net "GND")
	)
	(via
		(at 27.686 -123.600972)
		(size 0.508)
		(drill 0.254)
		(layers "F.Cu" "B.Cu")
		(net "GND")
	)
	(via
		(at 49.657 -136.8425)
		(size 0.508)
		(drill 0.254)
		(layers "F.Cu" "B.Cu")
		(net "GND")
	)
	(via
		(at 4.191 -384.175)
		(size 0.508)
		(drill 0.254)
		(layers "F.Cu" "B.Cu")
		(net "GND")
	)
	(via
		(at 198.12 -457.2)
		(size 0.508)
		(drill 0.254)
		(layers "F.Cu" "B.Cu")
		(net "GND")
	)
	(via
		(at 111.76 -335.28)
		(size 0.508)
		(drill 0.254)
		(layers "F.Cu" "B.Cu")
		(net "GND")
	)
	(via
		(at 37.61613 -284.589982)
		(size 0.508)
		(drill 0.254)
		(layers "F.Cu" "B.Cu")
		(net "GND")
	)
	(via
		(at 137.16 -452.12)
		(size 0.508)
		(drill 0.254)
		(layers "F.Cu" "B.Cu")
		(net "GND")
	)
	(via
		(at 243.84 -320.04)
		(size 0.508)
		(drill 0.254)
		(layers "F.Cu" "B.Cu")
		(net "GND")
	)
	(via
		(at 213.36 -365.76)
		(size 0.508)
		(drill 0.254)
		(layers "F.Cu" "B.Cu")
		(net "GND")
	)
	(via
		(at 241.304572 -1.397)
		(size 0.508)
		(drill 0.254)
		(layers "F.Cu" "B.Cu")
		(net "GND")
	)
	(via
		(at 76.2 -81.28)
		(size 0.508)
		(drill 0.254)
		(layers "F.Cu" "B.Cu")
		(net "GND")
	)
	(via
		(at 10.16 -502.92)
		(size 0.508)
		(drill 0.254)
		(layers "F.Cu" "B.Cu")
		(net "GND")
	)
	(via
		(at 6.223 -291.074602)
		(size 0.508)
		(drill 0.254)
		(layers "F.Cu" "B.Cu")
		(net "GND")
	)
	(via
		(at 60.96 -396.24)
		(size 0.508)
		(drill 0.254)
		(layers "F.Cu" "B.Cu")
		(net "GND")
	)
	(via
		(at 234.442 -294.6908)
		(size 0.508)
		(drill 0.254)
		(layers "F.Cu" "B.Cu")
		(net "GND")
	)
	(via
		(at 10.0076 -462.2546)
		(size 0.508)
		(drill 0.254)
		(layers "F.Cu" "B.Cu")
		(net "GND")
	)
	(via
		(at 4.191 -215.566244)
		(size 0.508)
		(drill 0.254)
		(layers "F.Cu" "B.Cu")
		(net "GND")
	)
	(via
		(at 254 -502.92)
		(size 0.508)
		(drill 0.254)
		(layers "F.Cu" "B.Cu")
		(net "GND")
	)
	(via
		(at 238.76 -492.76)
		(size 0.508)
		(drill 0.254)
		(layers "F.Cu" "B.Cu")
		(net "GND")
	)
	(via
		(at 198.12 -35.56)
		(size 0.508)
		(drill 0.254)
		(layers "F.Cu" "B.Cu")
		(net "GND")
	)
	(via
		(at 111.76 -401.32)
		(size 0.508)
		(drill 0.254)
		(layers "F.Cu" "B.Cu")
		(net "GND")
	)
	(via
		(at 137.16 -264.16)
		(size 0.508)
		(drill 0.254)
		(layers "F.Cu" "B.Cu")
		(net "GND")
	)
	(via
		(at 37.61613 -274.990052)
		(size 0.508)
		(drill 0.254)
		(layers "F.Cu" "B.Cu")
		(net "GND")
	)
	(via
		(at 116.84 -259.08)
		(size 0.508)
		(drill 0.254)
		(layers "F.Cu" "B.Cu")
		(net "GND")
	)
	(via
		(at 177.8 -279.4)
		(size 0.508)
		(drill 0.254)
		(layers "F.Cu" "B.Cu")
		(net "GND")
	)
	(via
		(at 219.314014 -174.780956)
		(size 0.508)
		(drill 0.254)
		(layers "F.Cu" "B.Cu")
		(net "GND")
	)
	(via
		(at 5.08 -40.64)
		(size 0.508)
		(drill 0.254)
		(layers "F.Cu" "B.Cu")
		(net "GND")
	)
	(via
		(at 132.08 -213.36)
		(size 0.508)
		(drill 0.254)
		(layers "F.Cu" "B.Cu")
		(net "GND")
	)
	(via
		(at 218.44 -35.56)
		(size 0.508)
		(drill 0.254)
		(layers "F.Cu" "B.Cu")
		(net "GND")
	)
	(via
		(at 152.4 -5.08)
		(size 0.508)
		(drill 0.254)
		(layers "F.Cu" "B.Cu")
		(net "GND")
	)
	(via
		(at 259.08 -50.8)
		(size 0.508)
		(drill 0.254)
		(layers "F.Cu" "B.Cu")
		(net "GND")
	)
	(via
		(at 13.081 -185.547)
		(size 0.508)
		(drill 0.254)
		(layers "F.Cu" "B.Cu")
		(net "GND")
	)
	(via
		(at 219.314014 -176.398936)
		(size 0.508)
		(drill 0.254)
		(layers "F.Cu" "B.Cu")
		(net "GND")
	)
	(via
		(at 35.56 -121.92)
		(size 0.508)
		(drill 0.254)
		(layers "F.Cu" "B.Cu")
		(net "GND")
	)
	(via
		(at 76.2 -361.061)
		(size 0.508)
		(drill 0.254)
		(layers "F.Cu" "B.Cu")
		(net "GND")
	)
	(via
		(at 167.64 -284.48)
		(size 0.508)
		(drill 0.254)
		(layers "F.Cu" "B.Cu")
		(net "GND")
	)
	(via
		(at 162.56 -66.04)
		(size 0.508)
		(drill 0.254)
		(layers "F.Cu" "B.Cu")
		(net "GND")
	)
	(via
		(at 228.585014 -368.415062)
		(size 0.508)
		(drill 0.254)
		(layers "F.Cu" "B.Cu")
		(net "GND")
	)
	(via
		(at 182.88 -198.12)
		(size 0.508)
		(drill 0.254)
		(layers "F.Cu" "B.Cu")
		(net "GND")
	)
	(via
		(at 66.04 -497.84)
		(size 0.508)
		(drill 0.254)
		(layers "F.Cu" "B.Cu")
		(net "GND")
	)
	(via
		(at 25.4762 -503.1486)
		(size 0.508)
		(drill 0.254)
		(layers "F.Cu" "B.Cu")
		(net "GND")
	)
	(via
		(at 182.88 -304.8)
		(size 0.508)
		(drill 0.254)
		(layers "F.Cu" "B.Cu")
		(net "GND")
	)
	(via
		(at 34.30651 -467.7791)
		(size 0.508)
		(drill 0.254)
		(layers "F.Cu" "B.Cu")
		(net "GND")
	)
	(via
		(at 55.88 -121.92)
		(size 0.508)
		(drill 0.254)
		(layers "F.Cu" "B.Cu")
		(net "GND")
	)
	(via
		(at 28.321 -70.104)
		(size 0.508)
		(drill 0.254)
		(layers "F.Cu" "B.Cu")
		(net "GND")
	)
	(via
		(at 111.76 -50.8)
		(size 0.508)
		(drill 0.254)
		(layers "F.Cu" "B.Cu")
		(net "GND")
	)
	(via
		(at 24.384 -391.4394)
		(size 0.508)
		(drill 0.254)
		(layers "F.Cu" "B.Cu")
		(net "GND")
	)
	(via
		(at 177.8 -325.12)
		(size 0.508)
		(drill 0.254)
		(layers "F.Cu" "B.Cu")
		(net "GND")
	)
	(via
		(at 172.72 -381)
		(size 0.508)
		(drill 0.254)
		(layers "F.Cu" "B.Cu")
		(net "GND")
	)
	(via
		(at 85.725 -433.3875)
		(size 0.508)
		(drill 0.254)
		(layers "F.Cu" "B.Cu")
		(net "GND")
	)
	(via
		(at 4.191 -229.890066)
		(size 0.508)
		(drill 0.254)
		(layers "F.Cu" "B.Cu")
		(net "GND")
	)
	(via
		(at 254 -25.4)
		(size 0.508)
		(drill 0.254)
		(layers "F.Cu" "B.Cu")
		(net "GND")
	)
	(via
		(at 167.64 -365.76)
		(size 0.508)
		(drill 0.254)
		(layers "F.Cu" "B.Cu")
		(net "GND")
	)
	(via
		(at 228.6 -132.08)
		(size 0.508)
		(drill 0.254)
		(layers "F.Cu" "B.Cu")
		(net "GND")
	)
	(via
		(at 76.2 -406.4)
		(size 0.508)
		(drill 0.254)
		(layers "F.Cu" "B.Cu")
		(net "GND")
	)
	(via
		(at 116.84 -203.2)
		(size 0.508)
		(drill 0.254)
		(layers "F.Cu" "B.Cu")
		(net "GND")
	)
	(via
		(at 50.8 -304.8)
		(size 0.508)
		(drill 0.254)
		(layers "F.Cu" "B.Cu")
		(net "GND")
	)
	(via
		(at 215.138 -501.269)
		(size 0.508)
		(drill 0.254)
		(layers "F.Cu" "B.Cu")
		(net "GND")
	)
	(via
		(at 132.08 -360.68)
		(size 0.508)
		(drill 0.254)
		(layers "F.Cu" "B.Cu")
		(net "GND")
	)
	(via
		(at 254 -60.96)
		(size 0.508)
		(drill 0.254)
		(layers "F.Cu" "B.Cu")
		(net "GND")
	)
	(via
		(at 172.72 -20.32)
		(size 0.508)
		(drill 0.254)
		(layers "F.Cu" "B.Cu")
		(net "GND")
	)
	(via
		(at 208.28 -127)
		(size 0.508)
		(drill 0.254)
		(layers "F.Cu" "B.Cu")
		(net "GND")
	)
	(via
		(at 24.519128 -248.331228)
		(size 0.508)
		(drill 0.254)
		(layers "F.Cu" "B.Cu")
		(net "GND")
	)
	(via
		(at 71.12 -25.4)
		(size 0.508)
		(drill 0.254)
		(layers "F.Cu" "B.Cu")
		(net "GND")
	)
	(via
		(at 213.36 -172.72)
		(size 0.508)
		(drill 0.254)
		(layers "F.Cu" "B.Cu")
		(net "GND")
	)
	(via
		(at 187.96 -20.32)
		(size 0.508)
		(drill 0.254)
		(layers "F.Cu" "B.Cu")
		(net "GND")
	)
	(via
		(at 77.089 -352.806)
		(size 0.508)
		(drill 0.254)
		(layers "F.Cu" "B.Cu")
		(net "GND")
	)
	(via
		(at 182.854854 -238.556292)
		(size 0.7112)
		(drill 0.3556)
		(layers "F.Cu" "B.Cu")
		(net "GND")
	)
	(via
		(at 248.92 -76.2)
		(size 0.508)
		(drill 0.254)
		(layers "F.Cu" "B.Cu")
		(net "GND")
	)
	(via
		(at 262.103108 -168.558464)
		(size 0.508)
		(drill 0.254)
		(layers "F.Cu" "B.Cu")
		(net "GND")
	)
	(via
		(at 243.84 -55.88)
		(size 0.508)
		(drill 0.254)
		(layers "F.Cu" "B.Cu")
		(net "GND")
	)
	(via
		(at 4.191 -197.54215)
		(size 0.508)
		(drill 0.254)
		(layers "F.Cu" "B.Cu")
		(net "GND")
	)
	(via
		(at 75.565 -360.426)
		(size 0.508)
		(drill 0.254)
		(layers "F.Cu" "B.Cu")
		(net "GND")
	)
	(via
		(at 248.92 -497.84)
		(size 0.508)
		(drill 0.254)
		(layers "F.Cu" "B.Cu")
		(net "GND")
	)
	(via
		(at 243.84 -137.16)
		(size 0.508)
		(drill 0.254)
		(layers "F.Cu" "B.Cu")
		(net "GND")
	)
	(via
		(at 30.099 -500.7356)
		(size 0.508)
		(drill 0.254)
		(layers "F.Cu" "B.Cu")
		(net "GND")
	)
	(via
		(at 162.56 -25.4)
		(size 0.508)
		(drill 0.254)
		(layers "F.Cu" "B.Cu")
		(net "GND")
	)
	(via
		(at 4.191 -388.366)
		(size 0.508)
		(drill 0.254)
		(layers "F.Cu" "B.Cu")
		(net "GND")
	)
	(via
		(at 91.186 -212.217)
		(size 0.508)
		(drill 0.254)
		(layers "F.Cu" "B.Cu")
		(net "GND")
	)
	(via
		(at 142.24 -193.04)
		(size 0.508)
		(drill 0.254)
		(layers "F.Cu" "B.Cu")
		(net "GND")
	)
	(via
		(at 76.2 -502.92)
		(size 0.508)
		(drill 0.254)
		(layers "F.Cu" "B.Cu")
		(net "GND")
	)
	(via
		(at 248.92 -193.04)
		(size 0.508)
		(drill 0.254)
		(layers "F.Cu" "B.Cu")
		(net "GND")
	)
	(via
		(at 76.2 -116.84)
		(size 0.508)
		(drill 0.254)
		(layers "F.Cu" "B.Cu")
		(net "GND")
	)
	(via
		(at 96.774 -212.217)
		(size 0.508)
		(drill 0.254)
		(layers "F.Cu" "B.Cu")
		(net "GND")
	)
	(via
		(at 213.36 -360.68)
		(size 0.508)
		(drill 0.254)
		(layers "F.Cu" "B.Cu")
		(net "GND")
	)
	(via
		(at 93.98 -302.387)
		(size 0.508)
		(drill 0.254)
		(layers "F.Cu" "B.Cu")
		(net "GND")
	)
	(via
		(at 147.32 -40.64)
		(size 0.508)
		(drill 0.254)
		(layers "F.Cu" "B.Cu")
		(net "GND")
	)
	(via
		(at 223.52 -218.44)
		(size 0.508)
		(drill 0.254)
		(layers "F.Cu" "B.Cu")
		(net "GND")
	)
	(via
		(at 37.61613 -480.990148)
		(size 0.508)
		(drill 0.254)
		(layers "F.Cu" "B.Cu")
		(net "GND")
	)
	(via
		(at 86.36 -157.48)
		(size 0.508)
		(drill 0.254)
		(layers "F.Cu" "B.Cu")
		(net "GND")
	)
	(via
		(at 106.68 -35.56)
		(size 0.508)
		(drill 0.254)
		(layers "F.Cu" "B.Cu")
		(net "GND")
	)
	(via
		(at 32.766 -267.081)
		(size 0.508)
		(drill 0.254)
		(layers "F.Cu" "B.Cu")
		(net "GND")
	)
	(via
		(at 121.92 -60.96)
		(size 0.508)
		(drill 0.254)
		(layers "F.Cu" "B.Cu")
		(net "GND")
	)
	(via
		(at 111.76 -452.12)
		(size 0.508)
		(drill 0.254)
		(layers "F.Cu" "B.Cu")
		(net "GND")
	)
	(via
		(at 203.2 -233.68)
		(size 0.508)
		(drill 0.254)
		(layers "F.Cu" "B.Cu")
		(net "GND")
	)
	(via
		(at 243.84 -157.48)
		(size 0.508)
		(drill 0.254)
		(layers "F.Cu" "B.Cu")
		(net "GND")
	)
	(via
		(at 37.61613 -488.190032)
		(size 0.508)
		(drill 0.254)
		(layers "F.Cu" "B.Cu")
		(net "GND")
	)
	(via
		(at 93.98 -430.403)
		(size 0.508)
		(drill 0.254)
		(layers "F.Cu" "B.Cu")
		(net "GND")
	)
	(via
		(at 55.88 -35.56)
		(size 0.508)
		(drill 0.254)
		(layers "F.Cu" "B.Cu")
		(net "GND")
	)
	(via
		(at 198.12 -320.04)
		(size 0.508)
		(drill 0.254)
		(layers "F.Cu" "B.Cu")
		(net "GND")
	)
	(via
		(at 167.64 -5.08)
		(size 0.508)
		(drill 0.254)
		(layers "F.Cu" "B.Cu")
		(net "GND")
	)
	(via
		(at 182.88 -203.2)
		(size 0.508)
		(drill 0.254)
		(layers "F.Cu" "B.Cu")
		(net "GND")
	)
	(via
		(at 4.191 -155.490164)
		(size 0.508)
		(drill 0.254)
		(layers "F.Cu" "B.Cu")
		(net "GND")
	)
	(via
		(at 222.616014 -480.990148)
		(size 0.508)
		(drill 0.254)
		(layers "F.Cu" "B.Cu")
		(net "GND")
	)
	(via
		(at 106.68 -248.92)
		(size 0.508)
		(drill 0.254)
		(layers "F.Cu" "B.Cu")
		(net "GND")
	)
	(via
		(at 18.429986 -504.603004)
		(size 0.508)
		(drill 0.254)
		(layers "F.Cu" "B.Cu")
		(net "GND")
	)
	(via
		(at 1.397 -132.329428)
		(size 0.508)
		(drill 0.254)
		(layers "F.Cu" "B.Cu")
		(net "GND")
	)
	(via
		(at 11.807698 -91.5416)
		(size 0.508)
		(drill 0.254)
		(layers "F.Cu" "B.Cu")
		(net "GND")
	)
	(via
		(at 233.68 -10.16)
		(size 0.508)
		(drill 0.254)
		(layers "F.Cu" "B.Cu")
		(net "GND")
	)
	(via
		(at 208.28 -147.32)
		(size 0.508)
		(drill 0.254)
		(layers "F.Cu" "B.Cu")
		(net "GND")
	)
	(via
		(at 96.52 -248.92)
		(size 0.508)
		(drill 0.254)
		(layers "F.Cu" "B.Cu")
		(net "GND")
	)
	(via
		(at 4.191 -158.69031)
		(size 0.508)
		(drill 0.254)
		(layers "F.Cu" "B.Cu")
		(net "GND")
	)
	(via
		(at 6.223 -439.538364)
		(size 0.508)
		(drill 0.254)
		(layers "F.Cu" "B.Cu")
		(net "GND")
	)
	(via
		(at 6.223 -424.338496)
		(size 0.508)
		(drill 0.254)
		(layers "F.Cu" "B.Cu")
		(net "GND")
	)
	(via
		(at 228.6 -15.24)
		(size 0.508)
		(drill 0.254)
		(layers "F.Cu" "B.Cu")
		(net "GND")
	)
	(via
		(at 81.28 -396.24)
		(size 0.508)
		(drill 0.254)
		(layers "F.Cu" "B.Cu")
		(net "GND")
	)
	(via
		(at 127 -340.36)
		(size 0.508)
		(drill 0.254)
		(layers "F.Cu" "B.Cu")
		(net "GND")
	)
	(via
		(at 262.103108 -82.198464)
		(size 0.508)
		(drill 0.254)
		(layers "F.Cu" "B.Cu")
		(net "GND")
	)
	(via
		(at 228.585014 -379.845062)
		(size 0.508)
		(drill 0.254)
		(layers "F.Cu" "B.Cu")
		(net "GND")
	)
	(via
		(at 24.384 -346.809822)
		(size 0.508)
		(drill 0.254)
		(layers "F.Cu" "B.Cu")
		(net "GND")
	)
	(via
		(at 60.96 -76.2)
		(size 0.508)
		(drill 0.254)
		(layers "F.Cu" "B.Cu")
		(net "GND")
	)
	(via
		(at 37.338 -93.98)
		(size 0.508)
		(drill 0.254)
		(layers "F.Cu" "B.Cu")
		(net "GND")
	)
	(via
		(at 106.68 -314.96)
		(size 0.508)
		(drill 0.254)
		(layers "F.Cu" "B.Cu")
		(net "GND")
	)
	(via
		(at 111.76 -81.28)
		(size 0.508)
		(drill 0.254)
		(layers "F.Cu" "B.Cu")
		(net "GND")
	)
	(via
		(at 202.7936 -167.5892)
		(size 0.508)
		(drill 0.254)
		(layers "F.Cu" "B.Cu")
		(net "GND")
	)
	(via
		(at 259.08 -497.84)
		(size 0.508)
		(drill 0.254)
		(layers "F.Cu" "B.Cu")
		(net "GND")
	)
	(via
		(at 152.4 -309.88)
		(size 0.508)
		(drill 0.254)
		(layers "F.Cu" "B.Cu")
		(net "GND")
	)
	(via
		(at 182.88 -223.52)
		(size 0.508)
		(drill 0.254)
		(layers "F.Cu" "B.Cu")
		(net "GND")
	)
	(via
		(at 222.616014 -387.59003)
		(size 0.508)
		(drill 0.254)
		(layers "F.Cu" "B.Cu")
		(net "GND")
	)
	(via
		(at 254 -238.76)
		(size 0.508)
		(drill 0.254)
		(layers "F.Cu" "B.Cu")
		(net "GND")
	)
	(via
		(at 162.56 -147.32)
		(size 0.508)
		(drill 0.254)
		(layers "F.Cu" "B.Cu")
		(net "GND")
	)
	(via
		(at 229.828852 -264.700766)
		(size 0.508)
		(drill 0.254)
		(layers "F.Cu" "B.Cu")
		(net "GND")
	)
	(via
		(at 101.6 -116.84)
		(size 0.508)
		(drill 0.254)
		(layers "F.Cu" "B.Cu")
		(net "GND")
	)
	(via
		(at 142.24 -106.68)
		(size 0.508)
		(drill 0.254)
		(layers "F.Cu" "B.Cu")
		(net "GND")
	)
	(via
		(at 157.48 -187.96)
		(size 0.508)
		(drill 0.254)
		(layers "F.Cu" "B.Cu")
		(net "GND")
	)
	(via
		(at 55.88 -325.12)
		(size 0.508)
		(drill 0.254)
		(layers "F.Cu" "B.Cu")
		(net "GND")
	)
	(via
		(at 162.56 -142.24)
		(size 0.508)
		(drill 0.254)
		(layers "F.Cu" "B.Cu")
		(net "GND")
	)
	(via
		(at 203.2 -269.24)
		(size 0.508)
		(drill 0.254)
		(layers "F.Cu" "B.Cu")
		(net "GND")
	)
	(via
		(at 262.103108 -173.638464)
		(size 0.508)
		(drill 0.254)
		(layers "F.Cu" "B.Cu")
		(net "GND")
	)
	(via
		(at 106.68 -259.08)
		(size 0.508)
		(drill 0.254)
		(layers "F.Cu" "B.Cu")
		(net "GND")
	)
	(via
		(at 245.11 -400.05)
		(size 0.7112)
		(drill 0.4064)
		(layers "F.Cu" "B.Cu")
		(net "GND")
	)
	(via
		(at 142.24 -213.36)
		(size 0.508)
		(drill 0.254)
		(layers "F.Cu" "B.Cu")
		(net "GND")
	)
	(via
		(at 34.3662 -402.6154)
		(size 0.508)
		(drill 0.254)
		(layers "F.Cu" "B.Cu")
		(net "GND")
	)
	(via
		(at 43.829986 -504.603004)
		(size 0.508)
		(drill 0.254)
		(layers "F.Cu" "B.Cu")
		(net "GND")
	)
	(via
		(at 77.3176 -215.0618)
		(size 0.508)
		(drill 0.254)
		(layers "F.Cu" "B.Cu")
		(net "GND")
	)
	(via
		(at 167.64 -213.36)
		(size 0.508)
		(drill 0.254)
		(layers "F.Cu" "B.Cu")
		(net "GND")
	)
	(via
		(at 101.6 -238.76)
		(size 0.508)
		(drill 0.254)
		(layers "F.Cu" "B.Cu")
		(net "GND")
	)
	(via
		(at 172.72 -40.64)
		(size 0.508)
		(drill 0.254)
		(layers "F.Cu" "B.Cu")
		(net "GND")
	)
	(via
		(at 132.08 -330.2)
		(size 0.508)
		(drill 0.254)
		(layers "F.Cu" "B.Cu")
		(net "GND")
	)
	(via
		(at 76.2 -320.04)
		(size 0.508)
		(drill 0.254)
		(layers "F.Cu" "B.Cu")
		(net "GND")
	)
	(via
		(at 121.92 -269.24)
		(size 0.508)
		(drill 0.254)
		(layers "F.Cu" "B.Cu")
		(net "GND")
	)
	(via
		(at 230.251 -440.4614)
		(size 0.508)
		(drill 0.254)
		(layers "F.Cu" "B.Cu")
		(net "GND")
	)
	(via
		(at 91.44 -243.84)
		(size 0.508)
		(drill 0.254)
		(layers "F.Cu" "B.Cu")
		(net "GND")
	)
	(via
		(at 60.96 -71.12)
		(size 0.508)
		(drill 0.254)
		(layers "F.Cu" "B.Cu")
		(net "GND")
	)
	(via
		(at 111.76 -116.84)
		(size 0.508)
		(drill 0.254)
		(layers "F.Cu" "B.Cu")
		(net "GND")
	)
	(via
		(at 96.774 -307.975)
		(size 0.508)
		(drill 0.254)
		(layers "F.Cu" "B.Cu")
		(net "GND")
	)
	(via
		(at 152.4 -436.88)
		(size 0.508)
		(drill 0.254)
		(layers "F.Cu" "B.Cu")
		(net "GND")
	)
	(via
		(at 157.48 -91.44)
		(size 0.508)
		(drill 0.254)
		(layers "F.Cu" "B.Cu")
		(net "GND")
	)
	(via
		(at 127 -228.6)
		(size 0.508)
		(drill 0.254)
		(layers "F.Cu" "B.Cu")
		(net "GND")
	)
	(via
		(at 32.639 -62.992)
		(size 0.508)
		(drill 0.254)
		(layers "F.Cu" "B.Cu")
		(net "GND")
	)
	(via
		(at 4.191 -394.716)
		(size 0.508)
		(drill 0.254)
		(layers "F.Cu" "B.Cu")
		(net "GND")
	)
	(via
		(at 220.7895 -36.7665)
		(size 0.508)
		(drill 0.254)
		(layers "F.Cu" "B.Cu")
		(net "GND")
	)
	(via
		(at 172.72 -127)
		(size 0.508)
		(drill 0.254)
		(layers "F.Cu" "B.Cu")
		(net "GND")
	)
	(via
		(at 167.64 -25.4)
		(size 0.508)
		(drill 0.254)
		(layers "F.Cu" "B.Cu")
		(net "GND")
	)
	(via
		(at 22.3266 -298.0182)
		(size 0.508)
		(drill 0.254)
		(layers "F.Cu" "B.Cu")
		(net "GND")
	)
	(via
		(at 121.92 -40.64)
		(size 0.508)
		(drill 0.254)
		(layers "F.Cu" "B.Cu")
		(net "GND")
	)
	(via
		(at 1.397 -20.569428)
		(size 0.508)
		(drill 0.254)
		(layers "F.Cu" "B.Cu")
		(net "GND")
	)
	(via
		(at 27.686 -125.218952)
		(size 0.508)
		(drill 0.254)
		(layers "F.Cu" "B.Cu")
		(net "GND")
	)
	(via
		(at 177.8 -472.44)
		(size 0.508)
		(drill 0.254)
		(layers "F.Cu" "B.Cu")
		(net "GND")
	)
	(via
		(at 4.191 -173.166278)
		(size 0.508)
		(drill 0.254)
		(layers "F.Cu" "B.Cu")
		(net "GND")
	)
	(via
		(at 91.44 -457.2)
		(size 0.508)
		(drill 0.254)
		(layers "F.Cu" "B.Cu")
		(net "GND")
	)
	(via
		(at 254 -447.04)
		(size 0.508)
		(drill 0.254)
		(layers "F.Cu" "B.Cu")
		(net "GND")
	)
	(via
		(at 5.08 -137.16)
		(size 0.508)
		(drill 0.254)
		(layers "F.Cu" "B.Cu")
		(net "GND")
	)
	(via
		(at 233.68 -223.52)
		(size 0.508)
		(drill 0.254)
		(layers "F.Cu" "B.Cu")
		(net "GND")
	)
	(via
		(at 167.64 -198.12)
		(size 0.508)
		(drill 0.254)
		(layers "F.Cu" "B.Cu")
		(net "GND")
	)
	(via
		(at 222.616014 -171.990004)
		(size 0.508)
		(drill 0.254)
		(layers "F.Cu" "B.Cu")
		(net "GND")
	)
	(via
		(at 208.28 -223.52)
		(size 0.508)
		(drill 0.254)
		(layers "F.Cu" "B.Cu")
		(net "GND")
	)
	(via
		(at 187.96 -274.32)
		(size 0.508)
		(drill 0.254)
		(layers "F.Cu" "B.Cu")
		(net "GND")
	)
	(via
		(at 208.28 -20.32)
		(size 0.508)
		(drill 0.254)
		(layers "F.Cu" "B.Cu")
		(net "GND")
	)
	(via
		(at 75.819 -167.6908)
		(size 0.508)
		(drill 0.254)
		(layers "F.Cu" "B.Cu")
		(net "GND")
	)
	(via
		(at 187.96 -147.32)
		(size 0.508)
		(drill 0.254)
		(layers "F.Cu" "B.Cu")
		(net "GND")
	)
	(via
		(at 43.58513 -59.414918)
		(size 0.508)
		(drill 0.254)
		(layers "F.Cu" "B.Cu")
		(net "GND")
	)
	(via
		(at 28.589986 -504.603004)
		(size 0.508)
		(drill 0.254)
		(layers "F.Cu" "B.Cu")
		(net "GND")
	)
	(via
		(at 259.08 -127)
		(size 0.508)
		(drill 0.254)
		(layers "F.Cu" "B.Cu")
		(net "GND")
	)
	(via
		(at 243.84 -142.24)
		(size 0.508)
		(drill 0.254)
		(layers "F.Cu" "B.Cu")
		(net "GND")
	)
	(via
		(at 152.4 -492.76)
		(size 0.508)
		(drill 0.254)
		(layers "F.Cu" "B.Cu")
		(net "GND")
	)
	(via
		(at 66.04 -177.8)
		(size 0.508)
		(drill 0.254)
		(layers "F.Cu" "B.Cu")
		(net "GND")
	)
	(via
		(at 121.92 -314.96)
		(size 0.508)
		(drill 0.254)
		(layers "F.Cu" "B.Cu")
		(net "GND")
	)
	(via
		(at 46.228 -241.046)
		(size 0.508)
		(drill 0.254)
		(layers "F.Cu" "B.Cu")
		(net "GND")
	)
	(via
		(at 4.191 -169.966132)
		(size 0.508)
		(drill 0.254)
		(layers "F.Cu" "B.Cu")
		(net "GND")
	)
	(via
		(at 10.3632 -464.1342)
		(size 0.508)
		(drill 0.254)
		(layers "F.Cu" "B.Cu")
		(net "GND")
	)
	(via
		(at 262.103108 -72.038464)
		(size 0.508)
		(drill 0.254)
		(layers "F.Cu" "B.Cu")
		(net "GND")
	)
	(via
		(at 209.38109 -298.93641)
		(size 0.508)
		(drill 0.254)
		(layers "F.Cu" "B.Cu")
		(net "GND")
	)
	(via
		(at 55.88 -177.8)
		(size 0.508)
		(drill 0.254)
		(layers "F.Cu" "B.Cu")
		(net "GND")
	)
	(via
		(at 36.6268 -392.557)
		(size 0.508)
		(drill 0.254)
		(layers "F.Cu" "B.Cu")
		(net "GND")
	)
	(via
		(at 238.76 -121.92)
		(size 0.508)
		(drill 0.254)
		(layers "F.Cu" "B.Cu")
		(net "GND")
	)
	(via
		(at 262.103108 -148.238464)
		(size 0.508)
		(drill 0.254)
		(layers "F.Cu" "B.Cu")
		(net "GND")
	)
	(via
		(at 78.486 -201.93)
		(size 0.508)
		(drill 0.254)
		(layers "F.Cu" "B.Cu")
		(net "GND")
	)
	(via
		(at 45.798232 -264.700766)
		(size 0.508)
		(drill 0.254)
		(layers "F.Cu" "B.Cu")
		(net "GND")
	)
	(via
		(at 45.72 -116.84)
		(size 0.508)
		(drill 0.254)
		(layers "F.Cu" "B.Cu")
		(net "GND")
	)
	(via
		(at 132.08 -10.16)
		(size 0.508)
		(drill 0.254)
		(layers "F.Cu" "B.Cu")
		(net "GND")
	)
	(via
		(at 48.909986 -504.603004)
		(size 0.508)
		(drill 0.254)
		(layers "F.Cu" "B.Cu")
		(net "GND")
	)
	(via
		(at 221.629986 -504.603004)
		(size 0.508)
		(drill 0.254)
		(layers "F.Cu" "B.Cu")
		(net "GND")
	)
	(via
		(at 262.103108 -468.876126)
		(size 0.508)
		(drill 0.254)
		(layers "F.Cu" "B.Cu")
		(net "GND")
	)
	(via
		(at 147.32 -172.72)
		(size 0.508)
		(drill 0.254)
		(layers "F.Cu" "B.Cu")
		(net "GND")
	)
	(via
		(at 132.08 -66.04)
		(size 0.508)
		(drill 0.254)
		(layers "F.Cu" "B.Cu")
		(net "GND")
	)
	(via
		(at 27.2796 -252.476)
		(size 0.508)
		(drill 0.254)
		(layers "F.Cu" "B.Cu")
		(net "GND")
	)
	(via
		(at 4.191 -347.966284)
		(size 0.508)
		(drill 0.254)
		(layers "F.Cu" "B.Cu")
		(net "GND")
	)
	(via
		(at 55.88 -482.6)
		(size 0.508)
		(drill 0.254)
		(layers "F.Cu" "B.Cu")
		(net "GND")
	)
	(via
		(at 86.36 -492.76)
		(size 0.508)
		(drill 0.254)
		(layers "F.Cu" "B.Cu")
		(net "GND")
	)
	(via
		(at 219.302838 -179.606956)
		(size 0.508)
		(drill 0.254)
		(layers "F.Cu" "B.Cu")
		(net "GND")
	)
	(via
		(at 24.384 -338.009992)
		(size 0.508)
		(drill 0.254)
		(layers "F.Cu" "B.Cu")
		(net "GND")
	)
	(via
		(at 91.44 -502.92)
		(size 0.508)
		(drill 0.254)
		(layers "F.Cu" "B.Cu")
		(net "GND")
	)
	(via
		(at 24.638 -196.1134)
		(size 0.508)
		(drill 0.254)
		(layers "F.Cu" "B.Cu")
		(net "GND")
	)
	(via
		(at 187.96 -167.64)
		(size 0.508)
		(drill 0.254)
		(layers "F.Cu" "B.Cu")
		(net "GND")
	)
	(via
		(at 6.223 -406.794208)
		(size 0.508)
		(drill 0.254)
		(layers "F.Cu" "B.Cu")
		(net "GND")
	)
	(via
		(at 32.7152 -488.0102)
		(size 0.508)
		(drill 0.254)
		(layers "F.Cu" "B.Cu")
		(net "GND")
	)
	(via
		(at 92.71 -208.026)
		(size 0.508)
		(drill 0.254)
		(layers "F.Cu" "B.Cu")
		(net "GND")
	)
	(via
		(at 238.76 -5.08)
		(size 0.508)
		(drill 0.254)
		(layers "F.Cu" "B.Cu")
		(net "GND")
	)
	(via
		(at 86.36 -477.52)
		(size 0.508)
		(drill 0.254)
		(layers "F.Cu" "B.Cu")
		(net "GND")
	)
	(via
		(at 35.433 -152.5016)
		(size 0.508)
		(drill 0.254)
		(layers "F.Cu" "B.Cu")
		(net "GND")
	)
	(via
		(at 71.12 -386.08)
		(size 0.508)
		(drill 0.254)
		(layers "F.Cu" "B.Cu")
		(net "GND")
	)
	(via
		(at 252.6284 -359.1814)
		(size 0.508)
		(drill 0.254)
		(layers "F.Cu" "B.Cu")
		(net "GND")
	)
	(via
		(at 193.04 -66.04)
		(size 0.508)
		(drill 0.254)
		(layers "F.Cu" "B.Cu")
		(net "GND")
	)
	(via
		(at 226.709986 -504.603004)
		(size 0.508)
		(drill 0.254)
		(layers "F.Cu" "B.Cu")
		(net "GND")
	)
	(via
		(at 116.84 -198.12)
		(size 0.508)
		(drill 0.254)
		(layers "F.Cu" "B.Cu")
		(net "GND")
	)
	(via
		(at 71.12 -350.52)
		(size 0.508)
		(drill 0.254)
		(layers "F.Cu" "B.Cu")
		(net "GND")
	)
	(via
		(at 116.84 -45.72)
		(size 0.508)
		(drill 0.254)
		(layers "F.Cu" "B.Cu")
		(net "GND")
	)
	(via
		(at 37.61613 -362.789978)
		(size 0.508)
		(drill 0.254)
		(layers "F.Cu" "B.Cu")
		(net "GND")
	)
	(via
		(at 60.96 -91.44)
		(size 0.508)
		(drill 0.254)
		(layers "F.Cu" "B.Cu")
		(net "GND")
	)
	(via
		(at 242.57 -392.43)
		(size 0.7112)
		(drill 0.4064)
		(layers "F.Cu" "B.Cu")
		(net "GND")
	)
	(via
		(at 177.8 -162.56)
		(size 0.508)
		(drill 0.254)
		(layers "F.Cu" "B.Cu")
		(net "GND")
	)
	(via
		(at 31.496 -137.508742)
		(size 0.508)
		(drill 0.254)
		(layers "F.Cu" "B.Cu")
		(net "GND")
	)
	(via
		(at 27.664918 -141.1478)
		(size 0.508)
		(drill 0.254)
		(layers "F.Cu" "B.Cu")
		(net "GND")
	)
	(via
		(at 24.384 -343.027)
		(size 0.508)
		(drill 0.254)
		(layers "F.Cu" "B.Cu")
		(net "GND")
	)
	(via
		(at 162.56 -279.4)
		(size 0.508)
		(drill 0.254)
		(layers "F.Cu" "B.Cu")
		(net "GND")
	)
	(via
		(at 27.733498 -231.501696)
		(size 0.508)
		(drill 0.254)
		(layers "F.Cu" "B.Cu")
		(net "GND")
	)
	(via
		(at 248.92 -121.92)
		(size 0.508)
		(drill 0.254)
		(layers "F.Cu" "B.Cu")
		(net "GND")
	)
	(via
		(at 132.08 -45.72)
		(size 0.508)
		(drill 0.254)
		(layers "F.Cu" "B.Cu")
		(net "GND")
	)
	(via
		(at 238.76 -15.24)
		(size 0.508)
		(drill 0.254)
		(layers "F.Cu" "B.Cu")
		(net "GND")
	)
	(via
		(at 101.6 -447.04)
		(size 0.508)
		(drill 0.254)
		(layers "F.Cu" "B.Cu")
		(net "GND")
	)
	(via
		(at 243.84 -86.36)
		(size 0.508)
		(drill 0.254)
		(layers "F.Cu" "B.Cu")
		(net "GND")
	)
	(via
		(at 45.798232 -367.699036)
		(size 0.508)
		(drill 0.254)
		(layers "F.Cu" "B.Cu")
		(net "GND")
	)
	(via
		(at 137.16 -20.32)
		(size 0.508)
		(drill 0.254)
		(layers "F.Cu" "B.Cu")
		(net "GND")
	)
	(via
		(at 238.76 -116.84)
		(size 0.508)
		(drill 0.254)
		(layers "F.Cu" "B.Cu")
		(net "GND")
	)
	(via
		(at 106.68 -233.68)
		(size 0.508)
		(drill 0.254)
		(layers "F.Cu" "B.Cu")
		(net "GND")
	)
	(via
		(at 198.12 -142.24)
		(size 0.508)
		(drill 0.254)
		(layers "F.Cu" "B.Cu")
		(net "GND")
	)
	(via
		(at 111.76 -314.96)
		(size 0.508)
		(drill 0.254)
		(layers "F.Cu" "B.Cu")
		(net "GND")
	)
	(via
		(at 152.4 -96.52)
		(size 0.508)
		(drill 0.254)
		(layers "F.Cu" "B.Cu")
		(net "GND")
	)
	(via
		(at 38.1508 -16.51)
		(size 0.508)
		(drill 0.254)
		(layers "F.Cu" "B.Cu")
		(net "GND")
	)
	(via
		(at 152.4 -76.2)
		(size 0.508)
		(drill 0.254)
		(layers "F.Cu" "B.Cu")
		(net "GND")
	)
	(via
		(at 10.16 -45.72)
		(size 0.508)
		(drill 0.254)
		(layers "F.Cu" "B.Cu")
		(net "GND")
	)
	(via
		(at 4.191 -439.587132)
		(size 0.508)
		(drill 0.254)
		(layers "F.Cu" "B.Cu")
		(net "GND")
	)
	(via
		(at 132.08 -86.36)
		(size 0.508)
		(drill 0.254)
		(layers "F.Cu" "B.Cu")
		(net "GND")
	)
	(via
		(at 243.84 -345.44)
		(size 0.508)
		(drill 0.254)
		(layers "F.Cu" "B.Cu")
		(net "GND")
	)
	(via
		(at 237.49 -385.064)
		(size 0.7112)
		(drill 0.4064)
		(layers "F.Cu" "B.Cu")
		(net "GND")
	)
	(via
		(at 127 -5.08)
		(size 0.508)
		(drill 0.254)
		(layers "F.Cu" "B.Cu")
		(net "GND")
	)
	(via
		(at 81.28 -391.16)
		(size 0.508)
		(drill 0.254)
		(layers "F.Cu" "B.Cu")
		(net "GND")
	)
	(via
		(at 193.04 -121.92)
		(size 0.508)
		(drill 0.254)
		(layers "F.Cu" "B.Cu")
		(net "GND")
	)
	(via
		(at 142.24 -375.92)
		(size 0.508)
		(drill 0.254)
		(layers "F.Cu" "B.Cu")
		(net "GND")
	)
	(via
		(at 248.92 -467.36)
		(size 0.508)
		(drill 0.254)
		(layers "F.Cu" "B.Cu")
		(net "GND")
	)
	(via
		(at 69.271388 -402.539454)
		(size 0.7112)
		(drill 0.3556)
		(layers "F.Cu" "B.Cu")
		(net "GND")
	)
	(via
		(at 116.84 -182.88)
		(size 0.508)
		(drill 0.254)
		(layers "F.Cu" "B.Cu")
		(net "GND")
	)
	(via
		(at 238.76 -147.32)
		(size 0.508)
		(drill 0.254)
		(layers "F.Cu" "B.Cu")
		(net "GND")
	)
	(via
		(at 233.426 -162.48761)
		(size 0.508)
		(drill 0.254)
		(layers "F.Cu" "B.Cu")
		(net "GND")
	)
	(via
		(at 243.84 -284.48)
		(size 0.508)
		(drill 0.254)
		(layers "F.Cu" "B.Cu")
		(net "GND")
	)
	(via
		(at 228.981 -285.369)
		(size 0.508)
		(drill 0.254)
		(layers "F.Cu" "B.Cu")
		(net "GND")
	)
	(via
		(at 106.68 -391.16)
		(size 0.508)
		(drill 0.254)
		(layers "F.Cu" "B.Cu")
		(net "GND")
	)
	(via
		(at 86.36 -182.88)
		(size 0.508)
		(drill 0.254)
		(layers "F.Cu" "B.Cu")
		(net "GND")
	)
	(via
		(at 238.76 -330.2)
		(size 0.508)
		(drill 0.254)
		(layers "F.Cu" "B.Cu")
		(net "GND")
	)
	(via
		(at 5.08 -86.36)
		(size 0.508)
		(drill 0.254)
		(layers "F.Cu" "B.Cu")
		(net "GND")
	)
	(via
		(at 121.92 -10.16)
		(size 0.508)
		(drill 0.254)
		(layers "F.Cu" "B.Cu")
		(net "GND")
	)
	(via
		(at 147.32 -45.72)
		(size 0.508)
		(drill 0.254)
		(layers "F.Cu" "B.Cu")
		(net "GND")
	)
	(via
		(at 101.6 -228.6)
		(size 0.508)
		(drill 0.254)
		(layers "F.Cu" "B.Cu")
		(net "GND")
	)
	(via
		(at 137.16 -76.2)
		(size 0.508)
		(drill 0.254)
		(layers "F.Cu" "B.Cu")
		(net "GND")
	)
	(via
		(at 187.96 -218.44)
		(size 0.508)
		(drill 0.254)
		(layers "F.Cu" "B.Cu")
		(net "GND")
	)
	(via
		(at 219.456 -300.2026)
		(size 0.508)
		(drill 0.254)
		(layers "F.Cu" "B.Cu")
		(net "GND")
	)
	(via
		(at 254 -223.52)
		(size 0.508)
		(drill 0.254)
		(layers "F.Cu" "B.Cu")
		(net "GND")
	)
	(via
		(at 55.88 -50.8)
		(size 0.508)
		(drill 0.254)
		(layers "F.Cu" "B.Cu")
		(net "GND")
	)
	(via
		(at 5.334 -361.823)
		(size 0.508)
		(drill 0.254)
		(layers "F.Cu" "B.Cu")
		(net "GND")
	)
	(via
		(at 229.828852 -58.70067)
		(size 0.508)
		(drill 0.254)
		(layers "F.Cu" "B.Cu")
		(net "GND")
	)
	(via
		(at 172.72 -71.12)
		(size 0.508)
		(drill 0.254)
		(layers "F.Cu" "B.Cu")
		(net "GND")
	)
	(via
		(at 259.08 -350.52)
		(size 0.508)
		(drill 0.254)
		(layers "F.Cu" "B.Cu")
		(net "GND")
	)
	(via
		(at 42.418 -237.720886)
		(size 0.508)
		(drill 0.254)
		(layers "F.Cu" "B.Cu")
		(net "GND")
	)
	(via
		(at 34.306256 -55.778908)
		(size 0.508)
		(drill 0.254)
		(layers "F.Cu" "B.Cu")
		(net "GND")
	)
	(via
		(at 55.88 -457.2)
		(size 0.508)
		(drill 0.254)
		(layers "F.Cu" "B.Cu")
		(net "GND")
	)
	(via
		(at 238.76 -157.48)
		(size 0.508)
		(drill 0.254)
		(layers "F.Cu" "B.Cu")
		(net "GND")
	)
	(via
		(at 81.28 -452.12)
		(size 0.508)
		(drill 0.254)
		(layers "F.Cu" "B.Cu")
		(net "GND")
	)
	(via
		(at 60.96 -325.12)
		(size 0.508)
		(drill 0.254)
		(layers "F.Cu" "B.Cu")
		(net "GND")
	)
	(via
		(at 219.314014 -261.852156)
		(size 0.508)
		(drill 0.254)
		(layers "F.Cu" "B.Cu")
		(net "GND")
	)
	(via
		(at 180.344572 -1.397)
		(size 0.508)
		(drill 0.254)
		(layers "F.Cu" "B.Cu")
		(net "GND")
	)
	(via
		(at 243.84 -147.32)
		(size 0.508)
		(drill 0.254)
		(layers "F.Cu" "B.Cu")
		(net "GND")
	)
	(via
		(at 93.98 -305.181)
		(size 0.508)
		(drill 0.254)
		(layers "F.Cu" "B.Cu")
		(net "GND")
	)
	(via
		(at 243.84 -254)
		(size 0.508)
		(drill 0.254)
		(layers "F.Cu" "B.Cu")
		(net "GND")
	)
	(via
		(at 233.68 -132.08)
		(size 0.508)
		(drill 0.254)
		(layers "F.Cu" "B.Cu")
		(net "GND")
	)
	(via
		(at 106.68 -172.72)
		(size 0.508)
		(drill 0.254)
		(layers "F.Cu" "B.Cu")
		(net "GND")
	)
	(via
		(at 167.64 -502.92)
		(size 0.508)
		(drill 0.254)
		(layers "F.Cu" "B.Cu")
		(net "GND")
	)
	(via
		(at 147.32 -238.76)
		(size 0.508)
		(drill 0.254)
		(layers "F.Cu" "B.Cu")
		(net "GND")
	)
	(via
		(at 116.84 -294.64)
		(size 0.508)
		(drill 0.254)
		(layers "F.Cu" "B.Cu")
		(net "GND")
	)
	(via
		(at 234.0356 -62.2808)
		(size 0.508)
		(drill 0.254)
		(layers "F.Cu" "B.Cu")
		(net "GND")
	)
	(via
		(at 121.92 -91.44)
		(size 0.508)
		(drill 0.254)
		(layers "F.Cu" "B.Cu")
		(net "GND")
	)
	(via
		(at 4.191 -182.766208)
		(size 0.508)
		(drill 0.254)
		(layers "F.Cu" "B.Cu")
		(net "GND")
	)
	(via
		(at 4.191 -297.490134)
		(size 0.508)
		(drill 0.254)
		(layers "F.Cu" "B.Cu")
		(net "GND")
	)
	(via
		(at 76.2 -482.6)
		(size 0.508)
		(drill 0.254)
		(layers "F.Cu" "B.Cu")
		(net "GND")
	)
	(via
		(at 218.313 -393.6238)
		(size 0.508)
		(drill 0.254)
		(layers "F.Cu" "B.Cu")
		(net "GND")
	)
	(via
		(at 262.103108 -21.238464)
		(size 0.508)
		(drill 0.254)
		(layers "F.Cu" "B.Cu")
		(net "GND")
	)
	(via
		(at 132.08 -370.84)
		(size 0.508)
		(drill 0.254)
		(layers "F.Cu" "B.Cu")
		(net "GND")
	)
	(via
		(at 223.52 -335.28)
		(size 0.508)
		(drill 0.254)
		(layers "F.Cu" "B.Cu")
		(net "GND")
	)
	(via
		(at 13.081 -119.126)
		(size 0.508)
		(drill 0.254)
		(layers "F.Cu" "B.Cu")
		(net "GND")
	)
	(via
		(at 132.08 -365.76)
		(size 0.508)
		(drill 0.254)
		(layers "F.Cu" "B.Cu")
		(net "GND")
	)
	(via
		(at 7.8232 -459.867)
		(size 0.7112)
		(drill 0.4064)
		(layers "F.Cu" "B.Cu")
		(net "GND")
	)
	(via
		(at 137.16 -116.84)
		(size 0.508)
		(drill 0.254)
		(layers "F.Cu" "B.Cu")
		(net "GND")
	)
	(via
		(at 33.147 -494.3348)
		(size 0.508)
		(drill 0.254)
		(layers "F.Cu" "B.Cu")
		(net "GND")
	)
	(via
		(at 233.426 -471.487754)
		(size 0.508)
		(drill 0.254)
		(layers "F.Cu" "B.Cu")
		(net "GND")
	)
	(via
		(at 193.04 -10.16)
		(size 0.508)
		(drill 0.254)
		(layers "F.Cu" "B.Cu")
		(net "GND")
	)
	(via
		(at 203.2 -502.92)
		(size 0.508)
		(drill 0.254)
		(layers "F.Cu" "B.Cu")
		(net "GND")
	)
	(via
		(at 214.249 -501.269)
		(size 0.508)
		(drill 0.254)
		(layers "F.Cu" "B.Cu")
		(net "GND")
	)
	(via
		(at 76.2 -20.32)
		(size 0.508)
		(drill 0.254)
		(layers "F.Cu" "B.Cu")
		(net "GND")
	)
	(via
		(at 187.96 -457.2)
		(size 0.508)
		(drill 0.254)
		(layers "F.Cu" "B.Cu")
		(net "GND")
	)
	(via
		(at 142.24 -299.72)
		(size 0.508)
		(drill 0.254)
		(layers "F.Cu" "B.Cu")
		(net "GND")
	)
	(via
		(at 212.696552 -430.657)
		(size 0.508)
		(drill 0.254)
		(layers "F.Cu" "B.Cu")
		(net "GND")
	)
	(via
		(at 24.384 -447.410078)
		(size 0.508)
		(drill 0.254)
		(layers "F.Cu" "B.Cu")
		(net "GND")
	)
	(via
		(at 76.2 -71.12)
		(size 0.508)
		(drill 0.254)
		(layers "F.Cu" "B.Cu")
		(net "GND")
	)
	(via
		(at 157.48 -142.24)
		(size 0.508)
		(drill 0.254)
		(layers "F.Cu" "B.Cu")
		(net "GND")
	)
	(via
		(at 4.191 -454.787)
		(size 0.508)
		(drill 0.254)
		(layers "F.Cu" "B.Cu")
		(net "GND")
	)
	(via
		(at 18.5166 -153.7716)
		(size 0.508)
		(drill 0.254)
		(layers "F.Cu" "B.Cu")
		(net "GND")
	)
	(via
		(at 24.0538 -501.4214)
		(size 0.508)
		(drill 0.254)
		(layers "F.Cu" "B.Cu")
		(net "GND")
	)
	(via
		(at 218.44 -309.88)
		(size 0.508)
		(drill 0.254)
		(layers "F.Cu" "B.Cu")
		(net "GND")
	)
	(via
		(at 88.961214 -112.871758)
		(size 0.508)
		(drill 0.254)
		(layers "F.Cu" "B.Cu")
		(net "GND")
	)
	(via
		(at 248.92 -127)
		(size 0.508)
		(drill 0.254)
		(layers "F.Cu" "B.Cu")
		(net "GND")
	)
	(via
		(at 71.12 -162.56)
		(size 0.508)
		(drill 0.254)
		(layers "F.Cu" "B.Cu")
		(net "GND")
	)
	(via
		(at 86.36 -45.72)
		(size 0.508)
		(drill 0.254)
		(layers "F.Cu" "B.Cu")
		(net "GND")
	)
	(via
		(at 6.223 -341.660734)
		(size 0.508)
		(drill 0.254)
		(layers "F.Cu" "B.Cu")
		(net "GND")
	)
	(via
		(at 211.680552 -441.833)
		(size 0.508)
		(drill 0.254)
		(layers "F.Cu" "B.Cu")
		(net "GND")
	)
	(via
		(at 198.174356 -496.127278)
		(size 0.508)
		(drill 0.254)
		(layers "F.Cu" "B.Cu")
		(net "GND")
	)
	(via
		(at 243.84 -127)
		(size 0.508)
		(drill 0.254)
		(layers "F.Cu" "B.Cu")
		(net "GND")
	)
	(via
		(at 132.08 -345.44)
		(size 0.508)
		(drill 0.254)
		(layers "F.Cu" "B.Cu")
		(net "GND")
	)
	(via
		(at 81.28 -467.36)
		(size 0.508)
		(drill 0.254)
		(layers "F.Cu" "B.Cu")
		(net "GND")
	)
	(via
		(at 1.397 -259.155946)
		(size 0.508)
		(drill 0.254)
		(layers "F.Cu" "B.Cu")
		(net "GND")
	)
	(via
		(at 66.04 -25.4)
		(size 0.508)
		(drill 0.254)
		(layers "F.Cu" "B.Cu")
		(net "GND")
	)
	(via
		(at 45.72 -340.36)
		(size 0.508)
		(drill 0.254)
		(layers "F.Cu" "B.Cu")
		(net "GND")
	)
	(via
		(at 167.64 -482.6)
		(size 0.508)
		(drill 0.254)
		(layers "F.Cu" "B.Cu")
		(net "GND")
	)
	(via
		(at 228.585014 -59.414918)
		(size 0.508)
		(drill 0.254)
		(layers "F.Cu" "B.Cu")
		(net "GND")
	)
	(via
		(at 242.57 -394.97)
		(size 0.7112)
		(drill 0.4064)
		(layers "F.Cu" "B.Cu")
		(net "GND")
	)
	(via
		(at 248.92 -177.8)
		(size 0.508)
		(drill 0.254)
		(layers "F.Cu" "B.Cu")
		(net "GND")
	)
	(via
		(at 106.934 -435.2925)
		(size 0.508)
		(drill 0.254)
		(layers "F.Cu" "B.Cu")
		(net "GND")
	)
	(via
		(at 259.08 -467.36)
		(size 0.508)
		(drill 0.254)
		(layers "F.Cu" "B.Cu")
		(net "GND")
	)
	(via
		(at 6.223 -195.473066)
		(size 0.508)
		(drill 0.254)
		(layers "F.Cu" "B.Cu")
		(net "GND")
	)
	(via
		(at 167.64 -91.44)
		(size 0.508)
		(drill 0.254)
		(layers "F.Cu" "B.Cu")
		(net "GND")
	)
	(via
		(at 238.76 -106.68)
		(size 0.508)
		(drill 0.254)
		(layers "F.Cu" "B.Cu")
		(net "GND")
	)
	(via
		(at 55.88 -86.36)
		(size 0.508)
		(drill 0.254)
		(layers "F.Cu" "B.Cu")
		(net "GND")
	)
	(via
		(at 81.28 -177.8)
		(size 0.508)
		(drill 0.254)
		(layers "F.Cu" "B.Cu")
		(net "GND")
	)
	(via
		(at 82.042 -208.153)
		(size 0.508)
		(drill 0.254)
		(layers "F.Cu" "B.Cu")
		(net "GND")
	)
	(via
		(at 70.993 -455.93)
		(size 0.508)
		(drill 0.254)
		(layers "F.Cu" "B.Cu")
		(net "GND")
	)
	(via
		(at 222.616014 -465.790026)
		(size 0.508)
		(drill 0.254)
		(layers "F.Cu" "B.Cu")
		(net "GND")
	)
	(via
		(at 225.042222 -34.262822)
		(size 0.508)
		(drill 0.254)
		(layers "F.Cu" "B.Cu")
		(net "GND")
	)
	(via
		(at 29.464 -206.883)
		(size 0.508)
		(drill 0.254)
		(layers "F.Cu" "B.Cu")
		(net "GND")
	)
	(via
		(at 222.616014 -80.989932)
		(size 0.508)
		(drill 0.254)
		(layers "F.Cu" "B.Cu")
		(net "GND")
	)
	(via
		(at 203.2 -345.44)
		(size 0.508)
		(drill 0.254)
		(layers "F.Cu" "B.Cu")
		(net "GND")
	)
	(via
		(at 37.61613 -282.189936)
		(size 0.508)
		(drill 0.254)
		(layers "F.Cu" "B.Cu")
		(net "GND")
	)
	(via
		(at 106.68 -264.16)
		(size 0.508)
		(drill 0.254)
		(layers "F.Cu" "B.Cu")
		(net "GND")
	)
	(via
		(at 208.28 -345.44)
		(size 0.508)
		(drill 0.254)
		(layers "F.Cu" "B.Cu")
		(net "GND")
	)
	(via
		(at 10.16 -15.24)
		(size 0.508)
		(drill 0.254)
		(layers "F.Cu" "B.Cu")
		(net "GND")
	)
	(via
		(at 45.503338 -35.029902)
		(size 0.508)
		(drill 0.254)
		(layers "F.Cu" "B.Cu")
		(net "GND")
	)
	(via
		(at 219.289884 -78.130908)
		(size 0.508)
		(drill 0.254)
		(layers "F.Cu" "B.Cu")
		(net "GND")
	)
	(via
		(at 172.72 -10.16)
		(size 0.508)
		(drill 0.254)
		(layers "F.Cu" "B.Cu")
		(net "GND")
	)
	(via
		(at 248.92 -203.2)
		(size 0.508)
		(drill 0.254)
		(layers "F.Cu" "B.Cu")
		(net "GND")
	)
	(via
		(at 37.61613 -165.589966)
		(size 0.508)
		(drill 0.254)
		(layers "F.Cu" "B.Cu")
		(net "GND")
	)
	(via
		(at 254 -101.6)
		(size 0.508)
		(drill 0.254)
		(layers "F.Cu" "B.Cu")
		(net "GND")
	)
	(via
		(at 111.76 -101.6)
		(size 0.508)
		(drill 0.254)
		(layers "F.Cu" "B.Cu")
		(net "GND")
	)
	(via
		(at 4.191 -295.966134)
		(size 0.508)
		(drill 0.254)
		(layers "F.Cu" "B.Cu")
		(net "GND")
	)
	(via
		(at 262.103108 -326.038464)
		(size 0.508)
		(drill 0.254)
		(layers "F.Cu" "B.Cu")
		(net "GND")
	)
	(via
		(at 228.6 -213.36)
		(size 0.508)
		(drill 0.254)
		(layers "F.Cu" "B.Cu")
		(net "GND")
	)
	(via
		(at 101.6 -365.76)
		(size 0.508)
		(drill 0.254)
		(layers "F.Cu" "B.Cu")
		(net "GND")
	)
	(via
		(at 43.58513 -278.115014)
		(size 0.508)
		(drill 0.254)
		(layers "F.Cu" "B.Cu")
		(net "GND")
	)
	(via
		(at 43.58513 -158.604966)
		(size 0.508)
		(drill 0.254)
		(layers "F.Cu" "B.Cu")
		(net "GND")
	)
	(via
		(at 55.88 -45.72)
		(size 0.508)
		(drill 0.254)
		(layers "F.Cu" "B.Cu")
		(net "GND")
	)
	(via
		(at 4.191 -294.290242)
		(size 0.508)
		(drill 0.254)
		(layers "F.Cu" "B.Cu")
		(net "GND")
	)
	(via
		(at 34.31413 -73.398888)
		(size 0.508)
		(drill 0.254)
		(layers "F.Cu" "B.Cu")
		(net "GND")
	)
	(via
		(at 167.64 -472.44)
		(size 0.508)
		(drill 0.254)
		(layers "F.Cu" "B.Cu")
		(net "GND")
	)
	(via
		(at 116.84 -96.52)
		(size 0.508)
		(drill 0.254)
		(layers "F.Cu" "B.Cu")
		(net "GND")
	)
	(via
		(at 218.44 -208.28)
		(size 0.508)
		(drill 0.254)
		(layers "F.Cu" "B.Cu")
		(net "GND")
	)
	(via
		(at 31.877 -182.626)
		(size 0.508)
		(drill 0.254)
		(layers "F.Cu" "B.Cu")
		(net "GND")
	)
	(via
		(at 71.12 -309.88)
		(size 0.508)
		(drill 0.254)
		(layers "F.Cu" "B.Cu")
		(net "GND")
	)
	(via
		(at 219.314014 -364.852204)
		(size 0.508)
		(drill 0.254)
		(layers "F.Cu" "B.Cu")
		(net "GND")
	)
	(via
		(at 18.415 -38.394894)
		(size 0.508)
		(drill 0.254)
		(layers "F.Cu" "B.Cu")
		(net "GND")
	)
	(via
		(at 50.8 -421.64)
		(size 0.508)
		(drill 0.254)
		(layers "F.Cu" "B.Cu")
		(net "GND")
	)
	(via
		(at 147.32 -66.04)
		(size 0.508)
		(drill 0.254)
		(layers "F.Cu" "B.Cu")
		(net "GND")
	)
	(via
		(at 76.2 -264.16)
		(size 0.508)
		(drill 0.254)
		(layers "F.Cu" "B.Cu")
		(net "GND")
	)
	(via
		(at 137.16 -269.24)
		(size 0.508)
		(drill 0.254)
		(layers "F.Cu" "B.Cu")
		(net "GND")
	)
	(via
		(at 1.397 -91.689428)
		(size 0.508)
		(drill 0.254)
		(layers "F.Cu" "B.Cu")
		(net "GND")
	)
	(via
		(at 228.981 -388.366)
		(size 0.508)
		(drill 0.254)
		(layers "F.Cu" "B.Cu")
		(net "GND")
	)
	(via
		(at 228.6 -274.32)
		(size 0.508)
		(drill 0.254)
		(layers "F.Cu" "B.Cu")
		(net "GND")
	)
	(via
		(at 233.68 -386.08)
		(size 0.508)
		(drill 0.254)
		(layers "F.Cu" "B.Cu")
		(net "GND")
	)
	(via
		(at 132.08 -462.28)
		(size 0.508)
		(drill 0.254)
		(layers "F.Cu" "B.Cu")
		(net "GND")
	)
	(via
		(at 147.32 -60.96)
		(size 0.508)
		(drill 0.254)
		(layers "F.Cu" "B.Cu")
		(net "GND")
	)
	(via
		(at 55.88 -492.76)
		(size 0.508)
		(drill 0.254)
		(layers "F.Cu" "B.Cu")
		(net "GND")
	)
	(via
		(at 25.2984 -254.3556)
		(size 0.508)
		(drill 0.254)
		(layers "F.Cu" "B.Cu")
		(net "GND")
	)
	(via
		(at 55.88 -132.08)
		(size 0.508)
		(drill 0.254)
		(layers "F.Cu" "B.Cu")
		(net "GND")
	)
	(via
		(at 147.32 -228.6)
		(size 0.508)
		(drill 0.254)
		(layers "F.Cu" "B.Cu")
		(net "GND")
	)
	(via
		(at 213.36 -233.68)
		(size 0.508)
		(drill 0.254)
		(layers "F.Cu" "B.Cu")
		(net "GND")
	)
	(via
		(at 101.6 -45.72)
		(size 0.508)
		(drill 0.254)
		(layers "F.Cu" "B.Cu")
		(net "GND")
	)
	(via
		(at 60.96 -421.64)
		(size 0.508)
		(drill 0.254)
		(layers "F.Cu" "B.Cu")
		(net "GND")
	)
	(via
		(at 230.503222 -446.67424)
		(size 0.508)
		(drill 0.254)
		(layers "F.Cu" "B.Cu")
		(net "GND")
	)
	(via
		(at 40.64 -330.2)
		(size 0.508)
		(drill 0.254)
		(layers "F.Cu" "B.Cu")
		(net "GND")
	)
	(via
		(at 203.2 -396.24)
		(size 0.508)
		(drill 0.254)
		(layers "F.Cu" "B.Cu")
		(net "GND")
	)
	(via
		(at 243.84 -182.88)
		(size 0.508)
		(drill 0.254)
		(layers "F.Cu" "B.Cu")
		(net "GND")
	)
	(via
		(at 132.08 -452.12)
		(size 0.508)
		(drill 0.254)
		(layers "F.Cu" "B.Cu")
		(net "GND")
	)
	(via
		(at 142.24 -187.96)
		(size 0.508)
		(drill 0.254)
		(layers "F.Cu" "B.Cu")
		(net "GND")
	)
	(via
		(at 24.384 -445.810132)
		(size 0.508)
		(drill 0.254)
		(layers "F.Cu" "B.Cu")
		(net "GND")
	)
	(via
		(at 218.4654 -85.471)
		(size 0.508)
		(drill 0.254)
		(layers "F.Cu" "B.Cu")
		(net "GND")
	)
	(via
		(at 4.191 -210.690206)
		(size 0.508)
		(drill 0.254)
		(layers "F.Cu" "B.Cu")
		(net "GND")
	)
	(via
		(at 152.4 -431.8)
		(size 0.508)
		(drill 0.254)
		(layers "F.Cu" "B.Cu")
		(net "GND")
	)
	(via
		(at 219.837 -403.606)
		(size 0.508)
		(drill 0.254)
		(layers "F.Cu" "B.Cu")
		(net "GND")
	)
	(via
		(at 101.6 -254)
		(size 0.508)
		(drill 0.254)
		(layers "F.Cu" "B.Cu")
		(net "GND")
	)
	(via
		(at 65.024 -443.357)
		(size 0.508)
		(drill 0.254)
		(layers "F.Cu" "B.Cu")
		(net "GND")
	)
	(via
		(at 162.56 -30.48)
		(size 0.508)
		(drill 0.254)
		(layers "F.Cu" "B.Cu")
		(net "GND")
	)
	(via
		(at 6.223 -307.07457)
		(size 0.508)
		(drill 0.254)
		(layers "F.Cu" "B.Cu")
		(net "GND")
	)
	(via
		(at 203.2 -320.04)
		(size 0.508)
		(drill 0.254)
		(layers "F.Cu" "B.Cu")
		(net "GND")
	)
	(via
		(at 182.88 -477.52)
		(size 0.508)
		(drill 0.254)
		(layers "F.Cu" "B.Cu")
		(net "GND")
	)
	(via
		(at 91.186 -430.403)
		(size 0.508)
		(drill 0.254)
		(layers "F.Cu" "B.Cu")
		(net "GND")
	)
	(via
		(at 172.72 -45.72)
		(size 0.508)
		(drill 0.254)
		(layers "F.Cu" "B.Cu")
		(net "GND")
	)
	(via
		(at 18.034 -323.723)
		(size 0.508)
		(drill 0.254)
		(layers "F.Cu" "B.Cu")
		(net "GND")
	)
	(via
		(at 45.503338 -343.674192)
		(size 0.508)
		(drill 0.254)
		(layers "F.Cu" "B.Cu")
		(net "GND")
	)
	(via
		(at 81.28 -477.52)
		(size 0.508)
		(drill 0.254)
		(layers "F.Cu" "B.Cu")
		(net "GND")
	)
	(via
		(at 4.191 -312.039)
		(size 0.508)
		(drill 0.254)
		(layers "F.Cu" "B.Cu")
		(net "GND")
	)
	(via
		(at 83.185 -424.942)
		(size 0.508)
		(drill 0.254)
		(layers "F.Cu" "B.Cu")
		(net "GND")
	)
	(via
		(at 127 -147.32)
		(size 0.508)
		(drill 0.254)
		(layers "F.Cu" "B.Cu")
		(net "GND")
	)
	(via
		(at 106.68 -142.24)
		(size 0.508)
		(drill 0.254)
		(layers "F.Cu" "B.Cu")
		(net "GND")
	)
	(via
		(at 219.289884 -282.649168)
		(size 0.508)
		(drill 0.254)
		(layers "F.Cu" "B.Cu")
		(net "GND")
	)
	(via
		(at 182.88 -132.08)
		(size 0.508)
		(drill 0.254)
		(layers "F.Cu" "B.Cu")
		(net "GND")
	)
	(via
		(at 106.68 -132.08)
		(size 0.508)
		(drill 0.254)
		(layers "F.Cu" "B.Cu")
		(net "GND")
	)
	(via
		(at 127 -10.16)
		(size 0.508)
		(drill 0.254)
		(layers "F.Cu" "B.Cu")
		(net "GND")
	)
	(via
		(at 60.96 -152.4)
		(size 0.508)
		(drill 0.254)
		(layers "F.Cu" "B.Cu")
		(net "GND")
	)
	(via
		(at 262.103108 -56.798464)
		(size 0.508)
		(drill 0.254)
		(layers "F.Cu" "B.Cu")
		(net "GND")
	)
	(via
		(at 96.52 -269.24)
		(size 0.508)
		(drill 0.254)
		(layers "F.Cu" "B.Cu")
		(net "GND")
	)
	(via
		(at 86.36 -35.56)
		(size 0.508)
		(drill 0.254)
		(layers "F.Cu" "B.Cu")
		(net "GND")
	)
	(via
		(at 29.0068 -501.4214)
		(size 0.508)
		(drill 0.254)
		(layers "F.Cu" "B.Cu")
		(net "GND")
	)
	(via
		(at 177.8 -55.88)
		(size 0.508)
		(drill 0.254)
		(layers "F.Cu" "B.Cu")
		(net "GND")
	)
	(via
		(at 137.16 -35.56)
		(size 0.508)
		(drill 0.254)
		(layers "F.Cu" "B.Cu")
		(net "GND")
	)
	(via
		(at 193.04 -320.04)
		(size 0.508)
		(drill 0.254)
		(layers "F.Cu" "B.Cu")
		(net "GND")
	)
	(via
		(at 81.28 -200.533)
		(size 0.508)
		(drill 0.254)
		(layers "F.Cu" "B.Cu")
		(net "GND")
	)
	(via
		(at 162.56 -426.72)
		(size 0.508)
		(drill 0.254)
		(layers "F.Cu" "B.Cu")
		(net "GND")
	)
	(via
		(at 248.92 -248.92)
		(size 0.508)
		(drill 0.254)
		(layers "F.Cu" "B.Cu")
		(net "GND")
	)
	(via
		(at 208.28 -30.48)
		(size 0.508)
		(drill 0.254)
		(layers "F.Cu" "B.Cu")
		(net "GND")
	)
	(via
		(at 162.56 -193.04)
		(size 0.508)
		(drill 0.254)
		(layers "F.Cu" "B.Cu")
		(net "GND")
	)
	(via
		(at 193.04 -208.28)
		(size 0.508)
		(drill 0.254)
		(layers "F.Cu" "B.Cu")
		(net "GND")
	)
	(via
		(at 162.56 -172.72)
		(size 0.508)
		(drill 0.254)
		(layers "F.Cu" "B.Cu")
		(net "GND")
	)
	(via
		(at 243.84 -462.28)
		(size 0.508)
		(drill 0.254)
		(layers "F.Cu" "B.Cu")
		(net "GND")
	)
	(via
		(at 127 -116.84)
		(size 0.508)
		(drill 0.254)
		(layers "F.Cu" "B.Cu")
		(net "GND")
	)
	(via
		(at 111.76 -248.92)
		(size 0.508)
		(drill 0.254)
		(layers "F.Cu" "B.Cu")
		(net "GND")
	)
	(via
		(at 262.103108 -66.958464)
		(size 0.508)
		(drill 0.254)
		(layers "F.Cu" "B.Cu")
		(net "GND")
	)
	(via
		(at 221.615 -61.341)
		(size 0.508)
		(drill 0.254)
		(layers "F.Cu" "B.Cu")
		(net "GND")
	)
	(via
		(at 262.103108 -97.438464)
		(size 0.508)
		(drill 0.254)
		(layers "F.Cu" "B.Cu")
		(net "GND")
	)
	(via
		(at 222.616014 -165.589966)
		(size 0.508)
		(drill 0.254)
		(layers "F.Cu" "B.Cu")
		(net "GND")
	)
	(via
		(at 187.96 -477.52)
		(size 0.508)
		(drill 0.254)
		(layers "F.Cu" "B.Cu")
		(net "GND")
	)
	(via
		(at 259.08 -223.52)
		(size 0.508)
		(drill 0.254)
		(layers "F.Cu" "B.Cu")
		(net "GND")
	)
	(via
		(at 243.84 -355.6)
		(size 0.508)
		(drill 0.254)
		(layers "F.Cu" "B.Cu")
		(net "GND")
	)
	(via
		(at 101.6 -487.68)
		(size 0.508)
		(drill 0.254)
		(layers "F.Cu" "B.Cu")
		(net "GND")
	)
	(via
		(at 233.68 -111.76)
		(size 0.508)
		(drill 0.254)
		(layers "F.Cu" "B.Cu")
		(net "GND")
	)
	(via
		(at 4.191 -429.133)
		(size 0.508)
		(drill 0.254)
		(layers "F.Cu" "B.Cu")
		(net "GND")
	)
	(via
		(at 22.11705 -195.1355)
		(size 0.508)
		(drill 0.254)
		(layers "F.Cu" "B.Cu")
		(net "GND")
	)
	(via
		(at 127 -426.72)
		(size 0.508)
		(drill 0.254)
		(layers "F.Cu" "B.Cu")
		(net "GND")
	)
	(via
		(at 34.671 -460.121)
		(size 0.508)
		(drill 0.254)
		(layers "F.Cu" "B.Cu")
		(net "GND")
	)
	(via
		(at 187.96 -40.64)
		(size 0.508)
		(drill 0.254)
		(layers "F.Cu" "B.Cu")
		(net "GND")
	)
	(via
		(at 91.186 -104.394)
		(size 0.508)
		(drill 0.254)
		(layers "F.Cu" "B.Cu")
		(net "GND")
	)
	(via
		(at 18.288 -394.081)
		(size 0.508)
		(drill 0.254)
		(layers "F.Cu" "B.Cu")
		(net "GND")
	)
	(via
		(at 119.384572 -1.397)
		(size 0.508)
		(drill 0.254)
		(layers "F.Cu" "B.Cu")
		(net "GND")
	)
	(via
		(at 228.585014 -265.415014)
		(size 0.508)
		(drill 0.254)
		(layers "F.Cu" "B.Cu")
		(net "GND")
	)
	(via
		(at 30.48 -309.88)
		(size 0.508)
		(drill 0.254)
		(layers "F.Cu" "B.Cu")
		(net "GND")
	)
	(via
		(at 254 -71.12)
		(size 0.508)
		(drill 0.254)
		(layers "F.Cu" "B.Cu")
		(net "GND")
	)
	(via
		(at 106.68 -228.6)
		(size 0.508)
		(drill 0.254)
		(layers "F.Cu" "B.Cu")
		(net "GND")
	)
	(via
		(at 116.84 -66.04)
		(size 0.508)
		(drill 0.254)
		(layers "F.Cu" "B.Cu")
		(net "GND")
	)
	(via
		(at 96.52 -487.68)
		(size 0.508)
		(drill 0.254)
		(layers "F.Cu" "B.Cu")
		(net "GND")
	)
	(via
		(at 116.84 -325.12)
		(size 0.508)
		(drill 0.254)
		(layers "F.Cu" "B.Cu")
		(net "GND")
	)
	(via
		(at 157.48 -25.4)
		(size 0.508)
		(drill 0.254)
		(layers "F.Cu" "B.Cu")
		(net "GND")
	)
	(via
		(at 86.36 -15.24)
		(size 0.508)
		(drill 0.254)
		(layers "F.Cu" "B.Cu")
		(net "GND")
	)
	(via
		(at 91.186 -102.997)
		(size 0.508)
		(drill 0.254)
		(layers "F.Cu" "B.Cu")
		(net "GND")
	)
	(via
		(at 17.145 -302.641)
		(size 0.508)
		(drill 0.254)
		(layers "F.Cu" "B.Cu")
		(net "GND")
	)
	(via
		(at 262.103108 -249.838464)
		(size 0.508)
		(drill 0.254)
		(layers "F.Cu" "B.Cu")
		(net "GND")
	)
	(via
		(at 96.52 -340.36)
		(size 0.508)
		(drill 0.254)
		(layers "F.Cu" "B.Cu")
		(net "GND")
	)
	(via
		(at 111.76 -482.6)
		(size 0.508)
		(drill 0.254)
		(layers "F.Cu" "B.Cu")
		(net "GND")
	)
	(via
		(at 182.88 -345.44)
		(size 0.508)
		(drill 0.254)
		(layers "F.Cu" "B.Cu")
		(net "GND")
	)
	(via
		(at 208.28 -264.16)
		(size 0.508)
		(drill 0.254)
		(layers "F.Cu" "B.Cu")
		(net "GND")
	)
	(via
		(at 6.223 -174.723806)
		(size 0.508)
		(drill 0.254)
		(layers "F.Cu" "B.Cu")
		(net "GND")
	)
	(via
		(at 238.76 -477.52)
		(size 0.508)
		(drill 0.254)
		(layers "F.Cu" "B.Cu")
		(net "GND")
	)
	(via
		(at 217.4748 -85.6742)
		(size 0.508)
		(drill 0.254)
		(layers "F.Cu" "B.Cu")
		(net "GND")
	)
	(via
		(at 193.04 -345.44)
		(size 0.508)
		(drill 0.254)
		(layers "F.Cu" "B.Cu")
		(net "GND")
	)
	(via
		(at 193.04 -20.32)
		(size 0.508)
		(drill 0.254)
		(layers "F.Cu" "B.Cu")
		(net "GND")
	)
	(via
		(at 167.64 -335.28)
		(size 0.508)
		(drill 0.254)
		(layers "F.Cu" "B.Cu")
		(net "GND")
	)
	(via
		(at 34.275014 -68.478908)
		(size 0.508)
		(drill 0.254)
		(layers "F.Cu" "B.Cu")
		(net "GND")
	)
	(via
		(at 137.16 -431.8)
		(size 0.508)
		(drill 0.254)
		(layers "F.Cu" "B.Cu")
		(net "GND")
	)
	(via
		(at 6.223 -344.86088)
		(size 0.508)
		(drill 0.254)
		(layers "F.Cu" "B.Cu")
		(net "GND")
	)
	(via
		(at 203.2 -127)
		(size 0.508)
		(drill 0.254)
		(layers "F.Cu" "B.Cu")
		(net "GND")
	)
	(via
		(at 213.36 -111.76)
		(size 0.508)
		(drill 0.254)
		(layers "F.Cu" "B.Cu")
		(net "GND")
	)
	(via
		(at 92.71 -100.203)
		(size 0.508)
		(drill 0.254)
		(layers "F.Cu" "B.Cu")
		(net "GND")
	)
	(via
		(at 187.96 -106.68)
		(size 0.508)
		(drill 0.254)
		(layers "F.Cu" "B.Cu")
		(net "GND")
	)
	(via
		(at 4.191 -308.76621)
		(size 0.508)
		(drill 0.254)
		(layers "F.Cu" "B.Cu")
		(net "GND")
	)
	(via
		(at 208.28 -462.28)
		(size 0.508)
		(drill 0.254)
		(layers "F.Cu" "B.Cu")
		(net "GND")
	)
	(via
		(at 15.24 -489.712)
		(size 0.508)
		(drill 0.254)
		(layers "F.Cu" "B.Cu")
		(net "GND")
	)
	(via
		(at 10.16 -10.16)
		(size 0.508)
		(drill 0.254)
		(layers "F.Cu" "B.Cu")
		(net "GND")
	)
	(via
		(at 37.61613 -483.390194)
		(size 0.508)
		(drill 0.254)
		(layers "F.Cu" "B.Cu")
		(net "GND")
	)
	(via
		(at 147.32 -193.04)
		(size 0.508)
		(drill 0.254)
		(layers "F.Cu" "B.Cu")
		(net "GND")
	)
	(via
		(at 33.1724 -393.4714)
		(size 0.508)
		(drill 0.254)
		(layers "F.Cu" "B.Cu")
		(net "GND")
	)
	(via
		(at 66.04 -309.88)
		(size 0.508)
		(drill 0.254)
		(layers "F.Cu" "B.Cu")
		(net "GND")
	)
	(via
		(at 147.32 -106.68)
		(size 0.508)
		(drill 0.254)
		(layers "F.Cu" "B.Cu")
		(net "GND")
	)
	(via
		(at 228.6 -254)
		(size 0.508)
		(drill 0.254)
		(layers "F.Cu" "B.Cu")
		(net "GND")
	)
	(via
		(at 86.36 -269.24)
		(size 0.508)
		(drill 0.254)
		(layers "F.Cu" "B.Cu")
		(net "GND")
	)
	(via
		(at 4.191 -151.942038)
		(size 0.508)
		(drill 0.254)
		(layers "F.Cu" "B.Cu")
		(net "GND")
	)
	(via
		(at 259.08 -132.08)
		(size 0.508)
		(drill 0.254)
		(layers "F.Cu" "B.Cu")
		(net "GND")
	)
	(via
		(at 233.68 -457.2)
		(size 0.508)
		(drill 0.254)
		(layers "F.Cu" "B.Cu")
		(net "GND")
	)
	(via
		(at 223.52 -127)
		(size 0.508)
		(drill 0.254)
		(layers "F.Cu" "B.Cu")
		(net "GND")
	)
	(via
		(at 37.61613 -465.790026)
		(size 0.508)
		(drill 0.254)
		(layers "F.Cu" "B.Cu")
		(net "GND")
	)
	(via
		(at 137.16 -111.76)
		(size 0.508)
		(drill 0.254)
		(layers "F.Cu" "B.Cu")
		(net "GND")
	)
	(via
		(at 177.8 -121.92)
		(size 0.508)
		(drill 0.254)
		(layers "F.Cu" "B.Cu")
		(net "GND")
	)
	(via
		(at 243.84 -203.2)
		(size 0.508)
		(drill 0.254)
		(layers "F.Cu" "B.Cu")
		(net "GND")
	)
	(via
		(at 37.61613 -163.18992)
		(size 0.508)
		(drill 0.254)
		(layers "F.Cu" "B.Cu")
		(net "GND")
	)
	(via
		(at 6.223 -308.809898)
		(size 0.508)
		(drill 0.254)
		(layers "F.Cu" "B.Cu")
		(net "GND")
	)
	(via
		(at 30.266386 -102.8954)
		(size 0.508)
		(drill 0.254)
		(layers "F.Cu" "B.Cu")
		(net "GND")
	)
	(via
		(at 4.445 -460.2226)
		(size 0.7112)
		(drill 0.4064)
		(layers "F.Cu" "B.Cu")
		(net "GND")
	)
	(via
		(at 4.191 -164.973)
		(size 0.508)
		(drill 0.254)
		(layers "F.Cu" "B.Cu")
		(net "GND")
	)
	(via
		(at 50.8 -106.68)
		(size 0.508)
		(drill 0.254)
		(layers "F.Cu" "B.Cu")
		(net "GND")
	)
	(via
		(at 222.616014 -68.989956)
		(size 0.508)
		(drill 0.254)
		(layers "F.Cu" "B.Cu")
		(net "GND")
	)
	(via
		(at 198.12 -137.16)
		(size 0.508)
		(drill 0.254)
		(layers "F.Cu" "B.Cu")
		(net "GND")
	)
	(via
		(at 55.88 -187.96)
		(size 0.508)
		(drill 0.254)
		(layers "F.Cu" "B.Cu")
		(net "GND")
	)
	(via
		(at 193.04 -45.72)
		(size 0.508)
		(drill 0.254)
		(layers "F.Cu" "B.Cu")
		(net "GND")
	)
	(via
		(at 177.8 -152.4)
		(size 0.508)
		(drill 0.254)
		(layers "F.Cu" "B.Cu")
		(net "GND")
	)
	(via
		(at 101.6 -162.56)
		(size 0.508)
		(drill 0.254)
		(layers "F.Cu" "B.Cu")
		(net "GND")
	)
	(via
		(at 93.98 -212.217)
		(size 0.508)
		(drill 0.254)
		(layers "F.Cu" "B.Cu")
		(net "GND")
	)
	(via
		(at 4.191 -199.566276)
		(size 0.508)
		(drill 0.254)
		(layers "F.Cu" "B.Cu")
		(net "GND")
	)
	(via
		(at 7.747 -371.729)
		(size 0.508)
		(drill 0.254)
		(layers "F.Cu" "B.Cu")
		(net "GND")
	)
	(via
		(at 45.7454 -58.69813)
		(size 0.508)
		(drill 0.254)
		(layers "F.Cu" "B.Cu")
		(net "GND")
	)
	(via
		(at 40.64 -325.12)
		(size 0.508)
		(drill 0.254)
		(layers "F.Cu" "B.Cu")
		(net "GND")
	)
	(via
		(at 132.08 -167.64)
		(size 0.508)
		(drill 0.254)
		(layers "F.Cu" "B.Cu")
		(net "GND")
	)
	(via
		(at 144.784572 -1.397)
		(size 0.508)
		(drill 0.254)
		(layers "F.Cu" "B.Cu")
		(net "GND")
	)
	(via
		(at 247.142 -357.886)
		(size 0.508)
		(drill 0.254)
		(layers "F.Cu" "B.Cu")
		(net "GND")
	)
	(via
		(at 233.68 -375.92)
		(size 0.508)
		(drill 0.254)
		(layers "F.Cu" "B.Cu")
		(net "GND")
	)
	(via
		(at 149.864572 -1.397)
		(size 0.508)
		(drill 0.254)
		(layers "F.Cu" "B.Cu")
		(net "GND")
	)
	(via
		(at 205.744572 -1.397)
		(size 0.508)
		(drill 0.254)
		(layers "F.Cu" "B.Cu")
		(net "GND")
	)
	(via
		(at 262.103108 -127.918464)
		(size 0.508)
		(drill 0.254)
		(layers "F.Cu" "B.Cu")
		(net "GND")
	)
	(via
		(at 28.6004 -111.506)
		(size 0.508)
		(drill 0.254)
		(layers "F.Cu" "B.Cu")
		(net "GND")
	)
	(via
		(at 101.6 -50.8)
		(size 0.508)
		(drill 0.254)
		(layers "F.Cu" "B.Cu")
		(net "GND")
	)
	(via
		(at 152.4 -66.04)
		(size 0.508)
		(drill 0.254)
		(layers "F.Cu" "B.Cu")
		(net "GND")
	)
	(via
		(at 116.84 -5.08)
		(size 0.508)
		(drill 0.254)
		(layers "F.Cu" "B.Cu")
		(net "GND")
	)
	(via
		(at 208.28 -111.76)
		(size 0.508)
		(drill 0.254)
		(layers "F.Cu" "B.Cu")
		(net "GND")
	)
	(via
		(at 5.08 -96.52)
		(size 0.508)
		(drill 0.254)
		(layers "F.Cu" "B.Cu")
		(net "GND")
	)
	(via
		(at 167.64 -81.28)
		(size 0.508)
		(drill 0.254)
		(layers "F.Cu" "B.Cu")
		(net "GND")
	)
	(via
		(at 86.233 -215.0745)
		(size 0.508)
		(drill 0.254)
		(layers "F.Cu" "B.Cu")
		(net "GND")
	)
	(via
		(at 157.48 -152.4)
		(size 0.508)
		(drill 0.254)
		(layers "F.Cu" "B.Cu")
		(net "GND")
	)
	(via
		(at 60.96 -264.16)
		(size 0.508)
		(drill 0.254)
		(layers "F.Cu" "B.Cu")
		(net "GND")
	)
	(via
		(at 182.88 -162.56)
		(size 0.508)
		(drill 0.254)
		(layers "F.Cu" "B.Cu")
		(net "GND")
	)
	(via
		(at 208.28 -121.92)
		(size 0.508)
		(drill 0.254)
		(layers "F.Cu" "B.Cu")
		(net "GND")
	)
	(via
		(at 233.68 -198.12)
		(size 0.508)
		(drill 0.254)
		(layers "F.Cu" "B.Cu")
		(net "GND")
	)
	(via
		(at 132.08 -35.56)
		(size 0.508)
		(drill 0.254)
		(layers "F.Cu" "B.Cu")
		(net "GND")
	)
	(via
		(at 240.03 -387.35)
		(size 0.7112)
		(drill 0.4064)
		(layers "F.Cu" "B.Cu")
		(net "GND")
	)
	(via
		(at 232.791 -439.293)
		(size 0.508)
		(drill 0.254)
		(layers "F.Cu" "B.Cu")
		(net "GND")
	)
	(via
		(at 182.88 -101.6)
		(size 0.508)
		(drill 0.254)
		(layers "F.Cu" "B.Cu")
		(net "GND")
	)
	(via
		(at 1.397 -56.129428)
		(size 0.508)
		(drill 0.254)
		(layers "F.Cu" "B.Cu")
		(net "GND")
	)
	(via
		(at 142.24 -497.84)
		(size 0.508)
		(drill 0.254)
		(layers "F.Cu" "B.Cu")
		(net "GND")
	)
	(via
		(at 177.8 -228.6)
		(size 0.508)
		(drill 0.254)
		(layers "F.Cu" "B.Cu")
		(net "GND")
	)
	(via
		(at 18.415 -454.205086)
		(size 0.508)
		(drill 0.254)
		(layers "F.Cu" "B.Cu")
		(net "GND")
	)
	(via
		(at 220.472 -197.231)
		(size 0.508)
		(drill 0.254)
		(layers "F.Cu" "B.Cu")
		(net "GND")
	)
	(via
		(at 203.2 -182.88)
		(size 0.508)
		(drill 0.254)
		(layers "F.Cu" "B.Cu")
		(net "GND")
	)
	(via
		(at 31.10103 -188.9252)
		(size 0.508)
		(drill 0.254)
		(layers "F.Cu" "B.Cu")
		(net "GND")
	)
	(via
		(at 4.191 -163.71062)
		(size 0.508)
		(drill 0.254)
		(layers "F.Cu" "B.Cu")
		(net "GND")
	)
	(via
		(at 132.08 -477.52)
		(size 0.508)
		(drill 0.254)
		(layers "F.Cu" "B.Cu")
		(net "GND")
	)
	(via
		(at 40.005 -140.0048)
		(size 0.508)
		(drill 0.254)
		(layers "F.Cu" "B.Cu")
		(net "GND")
	)
	(via
		(at 132.08 -233.68)
		(size 0.508)
		(drill 0.254)
		(layers "F.Cu" "B.Cu")
		(net "GND")
	)
	(via
		(at 233.426 -371.48516)
		(size 0.508)
		(drill 0.254)
		(layers "F.Cu" "B.Cu")
		(net "GND")
	)
	(via
		(at 182.88 -314.96)
		(size 0.508)
		(drill 0.254)
		(layers "F.Cu" "B.Cu")
		(net "GND")
	)
	(via
		(at 91.44 -340.36)
		(size 0.508)
		(drill 0.254)
		(layers "F.Cu" "B.Cu")
		(net "GND")
	)
	(via
		(at 142.24 -243.84)
		(size 0.508)
		(drill 0.254)
		(layers "F.Cu" "B.Cu")
		(net "GND")
	)
	(via
		(at 5.588 -460.7814)
		(size 0.7112)
		(drill 0.4064)
		(layers "F.Cu" "B.Cu")
		(net "GND")
	)
	(via
		(at 152.4 -121.92)
		(size 0.508)
		(drill 0.254)
		(layers "F.Cu" "B.Cu")
		(net "GND")
	)
	(via
		(at 137.16 -304.8)
		(size 0.508)
		(drill 0.254)
		(layers "F.Cu" "B.Cu")
		(net "GND")
	)
	(via
		(at 127 -40.64)
		(size 0.508)
		(drill 0.254)
		(layers "F.Cu" "B.Cu")
		(net "GND")
	)
	(via
		(at 147.32 -294.64)
		(size 0.508)
		(drill 0.254)
		(layers "F.Cu" "B.Cu")
		(net "GND")
	)
	(via
		(at 31.115 -281.178)
		(size 0.508)
		(drill 0.254)
		(layers "F.Cu" "B.Cu")
		(net "GND")
	)
	(via
		(at 85.725 -306.7685)
		(size 0.508)
		(drill 0.254)
		(layers "F.Cu" "B.Cu")
		(net "GND")
	)
	(via
		(at 24.9682 -112.6236)
		(size 0.508)
		(drill 0.254)
		(layers "F.Cu" "B.Cu")
		(net "GND")
	)
	(via
		(at 116.84 -497.84)
		(size 0.508)
		(drill 0.254)
		(layers "F.Cu" "B.Cu")
		(net "GND")
	)
	(via
		(at 4.191 -414.782)
		(size 0.508)
		(drill 0.254)
		(layers "F.Cu" "B.Cu")
		(net "GND")
	)
	(via
		(at 111.76 -30.48)
		(size 0.508)
		(drill 0.254)
		(layers "F.Cu" "B.Cu")
		(net "GND")
	)
	(via
		(at 162.56 -375.92)
		(size 0.508)
		(drill 0.254)
		(layers "F.Cu" "B.Cu")
		(net "GND")
	)
	(via
		(at 152.4 -345.44)
		(size 0.508)
		(drill 0.254)
		(layers "F.Cu" "B.Cu")
		(net "GND")
	)
	(via
		(at 243.84 -116.84)
		(size 0.508)
		(drill 0.254)
		(layers "F.Cu" "B.Cu")
		(net "GND")
	)
	(via
		(at 198.12 -203.2)
		(size 0.508)
		(drill 0.254)
		(layers "F.Cu" "B.Cu")
		(net "GND")
	)
	(via
		(at 127 -25.4)
		(size 0.508)
		(drill 0.254)
		(layers "F.Cu" "B.Cu")
		(net "GND")
	)
	(via
		(at 43.561 -409.829)
		(size 0.508)
		(drill 0.254)
		(layers "F.Cu" "B.Cu")
		(net "GND")
	)
	(via
		(at 60.96 -309.88)
		(size 0.508)
		(drill 0.254)
		(layers "F.Cu" "B.Cu")
		(net "GND")
	)
	(via
		(at 5.588 -377.698)
		(size 0.508)
		(drill 0.254)
		(layers "F.Cu" "B.Cu")
		(net "GND")
	)
	(via
		(at 37.61613 -73.789794)
		(size 0.508)
		(drill 0.254)
		(layers "F.Cu" "B.Cu")
		(net "GND")
	)
	(via
		(at 172.72 -198.12)
		(size 0.508)
		(drill 0.254)
		(layers "F.Cu" "B.Cu")
		(net "GND")
	)
	(via
		(at 167.64 -111.76)
		(size 0.508)
		(drill 0.254)
		(layers "F.Cu" "B.Cu")
		(net "GND")
	)
	(via
		(at 32.893 -275.463)
		(size 0.508)
		(drill 0.254)
		(layers "F.Cu" "B.Cu")
		(net "GND")
	)
	(via
		(at 87.302086 -443.023498)
		(size 0.508)
		(drill 0.254)
		(layers "F.Cu" "B.Cu")
		(net "GND")
	)
	(via
		(at 111.76 -218.44)
		(size 0.508)
		(drill 0.254)
		(layers "F.Cu" "B.Cu")
		(net "GND")
	)
	(via
		(at 221.488 -197.231)
		(size 0.508)
		(drill 0.254)
		(layers "F.Cu" "B.Cu")
		(net "GND")
	)
	(via
		(at 167.64 -203.2)
		(size 0.508)
		(drill 0.254)
		(layers "F.Cu" "B.Cu")
		(net "GND")
	)
	(via
		(at 50.8 -76.2)
		(size 0.508)
		(drill 0.254)
		(layers "F.Cu" "B.Cu")
		(net "GND")
	)
	(via
		(at 172.72 -172.72)
		(size 0.508)
		(drill 0.254)
		(layers "F.Cu" "B.Cu")
		(net "GND")
	)
	(via
		(at 48.4124 -268.484096)
		(size 0.508)
		(drill 0.254)
		(layers "F.Cu" "B.Cu")
		(net "GND")
	)
	(via
		(at 6.223 -209.211418)
		(size 0.508)
		(drill 0.254)
		(layers "F.Cu" "B.Cu")
		(net "GND")
	)
	(via
		(at 6.223 -228.411532)
		(size 0.508)
		(drill 0.254)
		(layers "F.Cu" "B.Cu")
		(net "GND")
	)
	(via
		(at 157.48 -233.68)
		(size 0.508)
		(drill 0.254)
		(layers "F.Cu" "B.Cu")
		(net "GND")
	)
	(via
		(at 147.32 -223.52)
		(size 0.508)
		(drill 0.254)
		(layers "F.Cu" "B.Cu")
		(net "GND")
	)
	(via
		(at 93.599 -314.071)
		(size 0.508)
		(drill 0.254)
		(layers "F.Cu" "B.Cu")
		(net "GND")
	)
	(via
		(at 222.616014 -60.189872)
		(size 0.508)
		(drill 0.254)
		(layers "F.Cu" "B.Cu")
		(net "GND")
	)
	(via
		(at 152.4 -279.4)
		(size 0.508)
		(drill 0.254)
		(layers "F.Cu" "B.Cu")
		(net "GND")
	)
	(via
		(at 116.84 -116.84)
		(size 0.508)
		(drill 0.254)
		(layers "F.Cu" "B.Cu")
		(net "GND")
	)
	(via
		(at 18.034 -220.726)
		(size 0.508)
		(drill 0.254)
		(layers "F.Cu" "B.Cu")
		(net "GND")
	)
	(via
		(at 254 -259.08)
		(size 0.508)
		(drill 0.254)
		(layers "F.Cu" "B.Cu")
		(net "GND")
	)
	(via
		(at 218.44 -304.8)
		(size 0.508)
		(drill 0.254)
		(layers "F.Cu" "B.Cu")
		(net "GND")
	)
	(via
		(at 198.12 -40.64)
		(size 0.508)
		(drill 0.254)
		(layers "F.Cu" "B.Cu")
		(net "GND")
	)
	(via
		(at 6.223 -323.20992)
		(size 0.508)
		(drill 0.254)
		(layers "F.Cu" "B.Cu")
		(net "GND")
	)
	(via
		(at 55.88 -487.68)
		(size 0.508)
		(drill 0.254)
		(layers "F.Cu" "B.Cu")
		(net "GND")
	)
	(via
		(at 6.223 -296.010076)
		(size 0.508)
		(drill 0.254)
		(layers "F.Cu" "B.Cu")
		(net "GND")
	)
	(via
		(at 55.88 -467.36)
		(size 0.508)
		(drill 0.254)
		(layers "F.Cu" "B.Cu")
		(net "GND")
	)
	(via
		(at 210.664552 -441.833)
		(size 0.508)
		(drill 0.254)
		(layers "F.Cu" "B.Cu")
		(net "GND")
	)
	(via
		(at 220.345 -300.2026)
		(size 0.508)
		(drill 0.254)
		(layers "F.Cu" "B.Cu")
		(net "GND")
	)
	(via
		(at 93.345 -296.672)
		(size 0.508)
		(drill 0.254)
		(layers "F.Cu" "B.Cu")
		(net "GND")
	)
	(via
		(at 162.56 -162.56)
		(size 0.508)
		(drill 0.254)
		(layers "F.Cu" "B.Cu")
		(net "GND")
	)
	(via
		(at 79.121 -352.806)
		(size 0.508)
		(drill 0.254)
		(layers "F.Cu" "B.Cu")
		(net "GND")
	)
	(via
		(at 101.6 -325.12)
		(size 0.508)
		(drill 0.254)
		(layers "F.Cu" "B.Cu")
		(net "GND")
	)
	(via
		(at 157.48 -370.84)
		(size 0.508)
		(drill 0.254)
		(layers "F.Cu" "B.Cu")
		(net "GND")
	)
	(via
		(at 167.64 -325.12)
		(size 0.508)
		(drill 0.254)
		(layers "F.Cu" "B.Cu")
		(net "GND")
	)
	(via
		(at 4.191 -305.566064)
		(size 0.508)
		(drill 0.254)
		(layers "F.Cu" "B.Cu")
		(net "GND")
	)
	(via
		(at 187.96 -502.92)
		(size 0.508)
		(drill 0.254)
		(layers "F.Cu" "B.Cu")
		(net "GND")
	)
	(via
		(at 162.56 -441.96)
		(size 0.508)
		(drill 0.254)
		(layers "F.Cu" "B.Cu")
		(net "GND")
	)
	(via
		(at 137.16 -233.68)
		(size 0.508)
		(drill 0.254)
		(layers "F.Cu" "B.Cu")
		(net "GND")
	)
	(via
		(at 177.8 -101.6)
		(size 0.508)
		(drill 0.254)
		(layers "F.Cu" "B.Cu")
		(net "GND")
	)
	(via
		(at 25.4254 -481.6602)
		(size 0.508)
		(drill 0.254)
		(layers "F.Cu" "B.Cu")
		(net "GND")
	)
	(via
		(at 142.24 -60.96)
		(size 0.508)
		(drill 0.254)
		(layers "F.Cu" "B.Cu")
		(net "GND")
	)
	(via
		(at 50.8 -375.92)
		(size 0.508)
		(drill 0.254)
		(layers "F.Cu" "B.Cu")
		(net "GND")
	)
	(via
		(at 142.24 -40.64)
		(size 0.508)
		(drill 0.254)
		(layers "F.Cu" "B.Cu")
		(net "GND")
	)
	(via
		(at 71.12 -502.92)
		(size 0.508)
		(drill 0.254)
		(layers "F.Cu" "B.Cu")
		(net "GND")
	)
	(via
		(at 262.103108 -234.598464)
		(size 0.508)
		(drill 0.254)
		(layers "F.Cu" "B.Cu")
		(net "GND")
	)
	(via
		(at 127 -111.76)
		(size 0.508)
		(drill 0.254)
		(layers "F.Cu" "B.Cu")
		(net "GND")
	)
	(via
		(at 15.24 -487.68)
		(size 0.508)
		(drill 0.254)
		(layers "F.Cu" "B.Cu")
		(net "GND")
	)
	(via
		(at 152.4 -320.04)
		(size 0.508)
		(drill 0.254)
		(layers "F.Cu" "B.Cu")
		(net "GND")
	)
	(via
		(at 104.144572 -1.397)
		(size 0.508)
		(drill 0.254)
		(layers "F.Cu" "B.Cu")
		(net "GND")
	)
	(via
		(at 101.6 -457.2)
		(size 0.508)
		(drill 0.254)
		(layers "F.Cu" "B.Cu")
		(net "GND")
	)
	(via
		(at 116.84 -30.48)
		(size 0.508)
		(drill 0.254)
		(layers "F.Cu" "B.Cu")
		(net "GND")
	)
	(via
		(at 106.68 -304.8)
		(size 0.508)
		(drill 0.254)
		(layers "F.Cu" "B.Cu")
		(net "GND")
	)
	(via
		(at 254 -467.36)
		(size 0.508)
		(drill 0.254)
		(layers "F.Cu" "B.Cu")
		(net "GND")
	)
	(via
		(at 201.309986 -504.603004)
		(size 0.508)
		(drill 0.254)
		(layers "F.Cu" "B.Cu")
		(net "GND")
	)
	(via
		(at 132.08 -284.48)
		(size 0.508)
		(drill 0.254)
		(layers "F.Cu" "B.Cu")
		(net "GND")
	)
	(via
		(at 243.84 -487.68)
		(size 0.508)
		(drill 0.254)
		(layers "F.Cu" "B.Cu")
		(net "GND")
	)
	(via
		(at 24.384 -128.009904)
		(size 0.508)
		(drill 0.254)
		(layers "F.Cu" "B.Cu")
		(net "GND")
	)
	(via
		(at 55.88 -55.88)
		(size 0.508)
		(drill 0.254)
		(layers "F.Cu" "B.Cu")
		(net "GND")
	)
	(via
		(at 209.38109 -401.93341)
		(size 0.508)
		(drill 0.254)
		(layers "F.Cu" "B.Cu")
		(net "GND")
	)
	(via
		(at 157.48 -284.48)
		(size 0.508)
		(drill 0.254)
		(layers "F.Cu" "B.Cu")
		(net "GND")
	)
	(via
		(at 157.48 -441.96)
		(size 0.508)
		(drill 0.254)
		(layers "F.Cu" "B.Cu")
		(net "GND")
	)
	(via
		(at 43.184572 -1.397)
		(size 0.508)
		(drill 0.254)
		(layers "F.Cu" "B.Cu")
		(net "GND")
	)
	(via
		(at 226.064572 -1.397)
		(size 0.508)
		(drill 0.254)
		(layers "F.Cu" "B.Cu")
		(net "GND")
	)
	(via
		(at 4.191 -284.690312)
		(size 0.508)
		(drill 0.254)
		(layers "F.Cu" "B.Cu")
		(net "GND")
	)
	(via
		(at 111.76 -60.96)
		(size 0.508)
		(drill 0.254)
		(layers "F.Cu" "B.Cu")
		(net "GND")
	)
	(via
		(at 152.4 -208.28)
		(size 0.508)
		(drill 0.254)
		(layers "F.Cu" "B.Cu")
		(net "GND")
	)
	(via
		(at 95.504 -423.418)
		(size 0.508)
		(drill 0.254)
		(layers "F.Cu" "B.Cu")
		(net "GND")
	)
	(via
		(at 259.08 -177.8)
		(size 0.508)
		(drill 0.254)
		(layers "F.Cu" "B.Cu")
		(net "GND")
	)
	(via
		(at 114.949986 -504.603004)
		(size 0.508)
		(drill 0.254)
		(layers "F.Cu" "B.Cu")
		(net "GND")
	)
	(via
		(at 81.28 -35.56)
		(size 0.508)
		(drill 0.254)
		(layers "F.Cu" "B.Cu")
		(net "GND")
	)
	(via
		(at 49.657 -134.9375)
		(size 0.508)
		(drill 0.254)
		(layers "F.Cu" "B.Cu")
		(net "GND")
	)
	(via
		(at 259.08 -116.84)
		(size 0.508)
		(drill 0.254)
		(layers "F.Cu" "B.Cu")
		(net "GND")
	)
	(via
		(at 101.6 -492.76)
		(size 0.508)
		(drill 0.254)
		(layers "F.Cu" "B.Cu")
		(net "GND")
	)
	(via
		(at 254 -441.96)
		(size 0.508)
		(drill 0.254)
		(layers "F.Cu" "B.Cu")
		(net "GND")
	)
	(via
		(at 5.08 -45.72)
		(size 0.508)
		(drill 0.254)
		(layers "F.Cu" "B.Cu")
		(net "GND")
	)
	(via
		(at 137.16 -177.8)
		(size 0.508)
		(drill 0.254)
		(layers "F.Cu" "B.Cu")
		(net "GND")
	)
	(via
		(at 203.2 -25.4)
		(size 0.508)
		(drill 0.254)
		(layers "F.Cu" "B.Cu")
		(net "GND")
	)
	(via
		(at 43.688 -405.13)
		(size 0.508)
		(drill 0.254)
		(layers "F.Cu" "B.Cu")
		(net "GND")
	)
	(via
		(at 24.384 -329.210162)
		(size 0.508)
		(drill 0.254)
		(layers "F.Cu" "B.Cu")
		(net "GND")
	)
	(via
		(at 24.384 -118.409974)
		(size 0.508)
		(drill 0.254)
		(layers "F.Cu" "B.Cu")
		(net "GND")
	)
	(via
		(at 121.92 -96.52)
		(size 0.508)
		(drill 0.254)
		(layers "F.Cu" "B.Cu")
		(net "GND")
	)
	(via
		(at 76.2 -386.08)
		(size 0.508)
		(drill 0.254)
		(layers "F.Cu" "B.Cu")
		(net "GND")
	)
	(via
		(at 177.8 -137.16)
		(size 0.508)
		(drill 0.254)
		(layers "F.Cu" "B.Cu")
		(net "GND")
	)
	(via
		(at 35.56 -474.98)
		(size 0.508)
		(drill 0.254)
		(layers "F.Cu" "B.Cu")
		(net "GND")
	)
	(via
		(at 1.397 -479.72599)
		(size 0.508)
		(drill 0.254)
		(layers "F.Cu" "B.Cu")
		(net "GND")
	)
	(via
		(at 5.08 -35.56)
		(size 0.508)
		(drill 0.254)
		(layers "F.Cu" "B.Cu")
		(net "GND")
	)
	(via
		(at 4.191 -406.781)
		(size 0.508)
		(drill 0.254)
		(layers "F.Cu" "B.Cu")
		(net "GND")
	)
	(via
		(at 248.92 -243.84)
		(size 0.508)
		(drill 0.254)
		(layers "F.Cu" "B.Cu")
		(net "GND")
	)
	(via
		(at 88.825324 -90.346022)
		(size 0.508)
		(drill 0.254)
		(layers "F.Cu" "B.Cu")
		(net "GND")
	)
	(via
		(at 177.8 -182.88)
		(size 0.508)
		(drill 0.254)
		(layers "F.Cu" "B.Cu")
		(net "GND")
	)
	(via
		(at 45.72 -182.88)
		(size 0.508)
		(drill 0.254)
		(layers "F.Cu" "B.Cu")
		(net "GND")
	)
	(via
		(at 91.186 -101.6)
		(size 0.508)
		(drill 0.254)
		(layers "F.Cu" "B.Cu")
		(net "GND")
	)
	(via
		(at 106.68 -299.72)
		(size 0.508)
		(drill 0.254)
		(layers "F.Cu" "B.Cu")
		(net "GND")
	)
	(via
		(at 43.58513 -72.114918)
		(size 0.508)
		(drill 0.254)
		(layers "F.Cu" "B.Cu")
		(net "GND")
	)
	(via
		(at 223.52 -208.28)
		(size 0.508)
		(drill 0.254)
		(layers "F.Cu" "B.Cu")
		(net "GND")
	)
	(via
		(at 11.4808 -471.0938)
		(size 0.508)
		(drill 0.254)
		(layers "F.Cu" "B.Cu")
		(net "GND")
	)
	(via
		(at 30.9118 -420.3192)
		(size 0.508)
		(drill 0.254)
		(layers "F.Cu" "B.Cu")
		(net "GND")
	)
	(via
		(at 37.61613 -71.390002)
		(size 0.508)
		(drill 0.254)
		(layers "F.Cu" "B.Cu")
		(net "GND")
	)
	(via
		(at 172.72 -325.12)
		(size 0.508)
		(drill 0.254)
		(layers "F.Cu" "B.Cu")
		(net "GND")
	)
	(via
		(at 9.7282 -472.1987)
		(size 0.508)
		(drill 0.254)
		(layers "F.Cu" "B.Cu")
		(net "GND")
	)
	(via
		(at 248.92 -162.56)
		(size 0.508)
		(drill 0.254)
		(layers "F.Cu" "B.Cu")
		(net "GND")
	)
	(via
		(at 4.191 -344.766138)
		(size 0.508)
		(drill 0.254)
		(layers "F.Cu" "B.Cu")
		(net "GND")
	)
	(via
		(at 132.08 -335.28)
		(size 0.508)
		(drill 0.254)
		(layers "F.Cu" "B.Cu")
		(net "GND")
	)
	(via
		(at 84.201 -303.403)
		(size 0.508)
		(drill 0.254)
		(layers "F.Cu" "B.Cu")
		(net "GND")
	)
	(via
		(at 27.720798 -437.501792)
		(size 0.508)
		(drill 0.254)
		(layers "F.Cu" "B.Cu")
		(net "GND")
	)
	(via
		(at 198.12 -284.48)
		(size 0.508)
		(drill 0.254)
		(layers "F.Cu" "B.Cu")
		(net "GND")
	)
	(via
		(at 238.76 -340.36)
		(size 0.508)
		(drill 0.254)
		(layers "F.Cu" "B.Cu")
		(net "GND")
	)
	(via
		(at 182.88 -482.6)
		(size 0.508)
		(drill 0.254)
		(layers "F.Cu" "B.Cu")
		(net "GND")
	)
	(via
		(at 167.64 -132.08)
		(size 0.508)
		(drill 0.254)
		(layers "F.Cu" "B.Cu")
		(net "GND")
	)
	(via
		(at 254 -121.92)
		(size 0.508)
		(drill 0.254)
		(layers "F.Cu" "B.Cu")
		(net "GND")
	)
	(via
		(at 66.04 -157.48)
		(size 0.508)
		(drill 0.254)
		(layers "F.Cu" "B.Cu")
		(net "GND")
	)
	(via
		(at 31.496 -34.508186)
		(size 0.508)
		(drill 0.254)
		(layers "F.Cu" "B.Cu")
		(net "GND")
	)
	(via
		(at 55.88 -426.72)
		(size 0.508)
		(drill 0.254)
		(layers "F.Cu" "B.Cu")
		(net "GND")
	)
	(via
		(at 34.31413 -380.781052)
		(size 0.508)
		(drill 0.254)
		(layers "F.Cu" "B.Cu")
		(net "GND")
	)
	(via
		(at 233.68 -259.08)
		(size 0.508)
		(drill 0.254)
		(layers "F.Cu" "B.Cu")
		(net "GND")
	)
	(via
		(at 127 -330.2)
		(size 0.508)
		(drill 0.254)
		(layers "F.Cu" "B.Cu")
		(net "GND")
	)
	(via
		(at 4.191 -220.290136)
		(size 0.508)
		(drill 0.254)
		(layers "F.Cu" "B.Cu")
		(net "GND")
	)
	(via
		(at 198.12 -147.32)
		(size 0.508)
		(drill 0.254)
		(layers "F.Cu" "B.Cu")
		(net "GND")
	)
	(via
		(at 6.6802 -461.01)
		(size 0.7112)
		(drill 0.4064)
		(layers "F.Cu" "B.Cu")
		(net "GND")
	)
	(via
		(at 222.616014 -53.789834)
		(size 0.508)
		(drill 0.254)
		(layers "F.Cu" "B.Cu")
		(net "GND")
	)
	(via
		(at 46.101 -416.941)
		(size 0.508)
		(drill 0.254)
		(layers "F.Cu" "B.Cu")
		(net "GND")
	)
	(via
		(at 243.84 -60.96)
		(size 0.508)
		(drill 0.254)
		(layers "F.Cu" "B.Cu")
		(net "GND")
	)
	(via
		(at 18.415 -332.155038)
		(size 0.508)
		(drill 0.254)
		(layers "F.Cu" "B.Cu")
		(net "GND")
	)
	(via
		(at 172.72 -233.68)
		(size 0.508)
		(drill 0.254)
		(layers "F.Cu" "B.Cu")
		(net "GND")
	)
	(via
		(at 137.16 -421.64)
		(size 0.508)
		(drill 0.254)
		(layers "F.Cu" "B.Cu")
		(net "GND")
	)
	(via
		(at 169.835322 -33.35401)
		(size 0.7112)
		(drill 0.3556)
		(layers "F.Cu" "B.Cu")
		(net "GND")
	)
	(via
		(at 167.64 -441.96)
		(size 0.508)
		(drill 0.254)
		(layers "F.Cu" "B.Cu")
		(net "GND")
	)
	(via
		(at 198.12 -360.68)
		(size 0.508)
		(drill 0.254)
		(layers "F.Cu" "B.Cu")
		(net "GND")
	)
	(via
		(at 187.96 -243.84)
		(size 0.508)
		(drill 0.254)
		(layers "F.Cu" "B.Cu")
		(net "GND")
	)
	(via
		(at 223.52 -254)
		(size 0.508)
		(drill 0.254)
		(layers "F.Cu" "B.Cu")
		(net "GND")
	)
	(via
		(at 238.76 -314.96)
		(size 0.508)
		(drill 0.254)
		(layers "F.Cu" "B.Cu")
		(net "GND")
	)
	(via
		(at 39.2938 -16.51)
		(size 0.508)
		(drill 0.254)
		(layers "F.Cu" "B.Cu")
		(net "GND")
	)
	(via
		(at 93.98 -209.423)
		(size 0.508)
		(drill 0.254)
		(layers "F.Cu" "B.Cu")
		(net "GND")
	)
	(via
		(at 37.61613 -472.190064)
		(size 0.508)
		(drill 0.254)
		(layers "F.Cu" "B.Cu")
		(net "GND")
	)
	(via
		(at 248.92 -132.08)
		(size 0.508)
		(drill 0.254)
		(layers "F.Cu" "B.Cu")
		(net "GND")
	)
	(via
		(at 229.828852 -367.700814)
		(size 0.508)
		(drill 0.254)
		(layers "F.Cu" "B.Cu")
		(net "GND")
	)
	(via
		(at 132.08 -76.2)
		(size 0.508)
		(drill 0.254)
		(layers "F.Cu" "B.Cu")
		(net "GND")
	)
	(via
		(at 31.051754 -213.9696)
		(size 0.508)
		(drill 0.254)
		(layers "F.Cu" "B.Cu")
		(net "GND")
	)
	(via
		(at 11.15949 -497.13261)
		(size 0.508)
		(drill 0.254)
		(layers "F.Cu" "B.Cu")
		(net "GND")
	)
	(via
		(at 48.3616 -368.487452)
		(size 0.508)
		(drill 0.254)
		(layers "F.Cu" "B.Cu")
		(net "GND")
	)
	(via
		(at 219.290138 -385.649216)
		(size 0.508)
		(drill 0.254)
		(layers "F.Cu" "B.Cu")
		(net "GND")
	)
	(via
		(at 242.3922 -358.8004)
		(size 0.508)
		(drill 0.254)
		(layers "F.Cu" "B.Cu")
		(net "GND")
	)
	(via
		(at 17.145 -137.500868)
		(size 0.508)
		(drill 0.254)
		(layers "F.Cu" "B.Cu")
		(net "GND")
	)
	(via
		(at 157.48 -238.76)
		(size 0.508)
		(drill 0.254)
		(layers "F.Cu" "B.Cu")
		(net "GND")
	)
	(via
		(at 162.56 -360.68)
		(size 0.508)
		(drill 0.254)
		(layers "F.Cu" "B.Cu")
		(net "GND")
	)
	(via
		(at 222.616014 -58.589926)
		(size 0.508)
		(drill 0.254)
		(layers "F.Cu" "B.Cu")
		(net "GND")
	)
	(via
		(at 1.397 -96.769428)
		(size 0.508)
		(drill 0.254)
		(layers "F.Cu" "B.Cu")
		(net "GND")
	)
	(via
		(at 16.256 -337.439)
		(size 0.508)
		(drill 0.254)
		(layers "F.Cu" "B.Cu")
		(net "GND")
	)
	(via
		(at 243.84 -213.36)
		(size 0.508)
		(drill 0.254)
		(layers "F.Cu" "B.Cu")
		(net "GND")
	)
	(via
		(at 116.84 -274.32)
		(size 0.508)
		(drill 0.254)
		(layers "F.Cu" "B.Cu")
		(net "GND")
	)
	(via
		(at 8.763 -234.95)
		(size 0.508)
		(drill 0.254)
		(layers "F.Cu" "B.Cu")
		(net "GND")
	)
	(via
		(at 193.04 -243.84)
		(size 0.508)
		(drill 0.254)
		(layers "F.Cu" "B.Cu")
		(net "GND")
	)
	(via
		(at 218.44 -314.96)
		(size 0.508)
		(drill 0.254)
		(layers "F.Cu" "B.Cu")
		(net "GND")
	)
	(via
		(at 147.32 -452.12)
		(size 0.508)
		(drill 0.254)
		(layers "F.Cu" "B.Cu")
		(net "GND")
	)
	(via
		(at 259.08 -106.68)
		(size 0.508)
		(drill 0.254)
		(layers "F.Cu" "B.Cu")
		(net "GND")
	)
	(via
		(at 121.92 -401.32)
		(size 0.508)
		(drill 0.254)
		(layers "F.Cu" "B.Cu")
		(net "GND")
	)
	(via
		(at 132.08 -71.12)
		(size 0.508)
		(drill 0.254)
		(layers "F.Cu" "B.Cu")
		(net "GND")
	)
	(via
		(at 96.329246 -316.428628)
		(size 0.508)
		(drill 0.254)
		(layers "F.Cu" "B.Cu")
		(net "GND")
	)
	(via
		(at 241.949986 -504.603004)
		(size 0.508)
		(drill 0.254)
		(layers "F.Cu" "B.Cu")
		(net "GND")
	)
	(via
		(at 211.469986 -504.603004)
		(size 0.508)
		(drill 0.254)
		(layers "F.Cu" "B.Cu")
		(net "GND")
	)
	(via
		(at 187.96 -45.72)
		(size 0.508)
		(drill 0.254)
		(layers "F.Cu" "B.Cu")
		(net "GND")
	)
	(via
		(at 91.186 -305.181)
		(size 0.508)
		(drill 0.254)
		(layers "F.Cu" "B.Cu")
		(net "GND")
	)
	(via
		(at 262.103108 -270.158464)
		(size 0.508)
		(drill 0.254)
		(layers "F.Cu" "B.Cu")
		(net "GND")
	)
	(via
		(at 262.103108 -26.318464)
		(size 0.508)
		(drill 0.254)
		(layers "F.Cu" "B.Cu")
		(net "GND")
	)
	(via
		(at 243.84 -325.12)
		(size 0.508)
		(drill 0.254)
		(layers "F.Cu" "B.Cu")
		(net "GND")
	)
	(via
		(at 228.6 -325.12)
		(size 0.508)
		(drill 0.254)
		(layers "F.Cu" "B.Cu")
		(net "GND")
	)
	(via
		(at 152.4 -223.52)
		(size 0.508)
		(drill 0.254)
		(layers "F.Cu" "B.Cu")
		(net "GND")
	)
	(via
		(at 101.6 -335.28)
		(size 0.508)
		(drill 0.254)
		(layers "F.Cu" "B.Cu")
		(net "GND")
	)
	(via
		(at 45.798232 -161.700718)
		(size 0.508)
		(drill 0.254)
		(layers "F.Cu" "B.Cu")
		(net "GND")
	)
	(via
		(at 207.10525 -92.1385)
		(size 0.508)
		(drill 0.254)
		(layers "F.Cu" "B.Cu")
		(net "GND")
	)
	(via
		(at 222.616014 -66.58991)
		(size 0.508)
		(drill 0.254)
		(layers "F.Cu" "B.Cu")
		(net "GND")
	)
	(via
		(at 73.152 -148.966936)
		(size 0.508)
		(drill 0.254)
		(layers "F.Cu" "B.Cu")
		(net "GND")
	)
	(via
		(at 182.88 -365.76)
		(size 0.508)
		(drill 0.254)
		(layers "F.Cu" "B.Cu")
		(net "GND")
	)
	(via
		(at 167.64 -436.88)
		(size 0.508)
		(drill 0.254)
		(layers "F.Cu" "B.Cu")
		(net "GND")
	)
	(via
		(at 37.61613 -474.59011)
		(size 0.508)
		(drill 0.254)
		(layers "F.Cu" "B.Cu")
		(net "GND")
	)
	(via
		(at 49.95291 -9.03859)
		(size 0.508)
		(drill 0.254)
		(layers "F.Cu" "B.Cu")
		(net "GND")
	)
	(via
		(at 111.76 -472.44)
		(size 0.508)
		(drill 0.254)
		(layers "F.Cu" "B.Cu")
		(net "GND")
	)
	(via
		(at 121.92 -472.44)
		(size 0.508)
		(drill 0.254)
		(layers "F.Cu" "B.Cu")
		(net "GND")
	)
	(via
		(at 203.2 -147.32)
		(size 0.508)
		(drill 0.254)
		(layers "F.Cu" "B.Cu")
		(net "GND")
	)
	(via
		(at 76.2 -5.08)
		(size 0.508)
		(drill 0.254)
		(layers "F.Cu" "B.Cu")
		(net "GND")
	)
	(via
		(at 238.76 -462.28)
		(size 0.508)
		(drill 0.254)
		(layers "F.Cu" "B.Cu")
		(net "GND")
	)
	(via
		(at 91.44 -482.6)
		(size 0.508)
		(drill 0.254)
		(layers "F.Cu" "B.Cu")
		(net "GND")
	)
	(via
		(at 116.84 -55.88)
		(size 0.508)
		(drill 0.254)
		(layers "F.Cu" "B.Cu")
		(net "GND")
	)
	(via
		(at 238.76 -208.28)
		(size 0.508)
		(drill 0.254)
		(layers "F.Cu" "B.Cu")
		(net "GND")
	)
	(via
		(at 6.223 -280.060654)
		(size 0.508)
		(drill 0.254)
		(layers "F.Cu" "B.Cu")
		(net "GND")
	)
	(via
		(at 152.4 -25.4)
		(size 0.508)
		(drill 0.254)
		(layers "F.Cu" "B.Cu")
		(net "GND")
	)
	(via
		(at 121.92 -50.8)
		(size 0.508)
		(drill 0.254)
		(layers "F.Cu" "B.Cu")
		(net "GND")
	)
	(via
		(at 127 -106.68)
		(size 0.508)
		(drill 0.254)
		(layers "F.Cu" "B.Cu")
		(net "GND")
	)
	(via
		(at 34.31413 -260.128004)
		(size 0.508)
		(drill 0.254)
		(layers "F.Cu" "B.Cu")
		(net "GND")
	)
	(via
		(at 262.103108 -46.638464)
		(size 0.508)
		(drill 0.254)
		(layers "F.Cu" "B.Cu")
		(net "GND")
	)
	(via
		(at 52.7304 -451.485)
		(size 0.508)
		(drill 0.254)
		(layers "F.Cu" "B.Cu")
		(net "GND")
	)
	(via
		(at 76.2 -269.24)
		(size 0.508)
		(drill 0.254)
		(layers "F.Cu" "B.Cu")
		(net "GND")
	)
	(via
		(at 222.616014 -183.98998)
		(size 0.508)
		(drill 0.254)
		(layers "F.Cu" "B.Cu")
		(net "GND")
	)
	(via
		(at 127 -370.84)
		(size 0.508)
		(drill 0.254)
		(layers "F.Cu" "B.Cu")
		(net "GND")
	)
	(via
		(at 222.616014 -163.18992)
		(size 0.508)
		(drill 0.254)
		(layers "F.Cu" "B.Cu")
		(net "GND")
	)
	(via
		(at 172.72 -66.04)
		(size 0.508)
		(drill 0.254)
		(layers "F.Cu" "B.Cu")
		(net "GND")
	)
	(via
		(at 37.3634 -206.8068)
		(size 0.508)
		(drill 0.254)
		(layers "F.Cu" "B.Cu")
		(net "GND")
	)
	(via
		(at 262.103108 -31.398464)
		(size 0.508)
		(drill 0.254)
		(layers "F.Cu" "B.Cu")
		(net "GND")
	)
	(via
		(at 137.16 -370.84)
		(size 0.508)
		(drill 0.254)
		(layers "F.Cu" "B.Cu")
		(net "GND")
	)
	(via
		(at 222.616014 -377.9901)
		(size 0.508)
		(drill 0.254)
		(layers "F.Cu" "B.Cu")
		(net "GND")
	)
	(via
		(at 152.4 -45.72)
		(size 0.508)
		(drill 0.254)
		(layers "F.Cu" "B.Cu")
		(net "GND")
	)
	(via
		(at 243.84 -91.44)
		(size 0.508)
		(drill 0.254)
		(layers "F.Cu" "B.Cu")
		(net "GND")
	)
	(via
		(at 213.36 -132.08)
		(size 0.508)
		(drill 0.254)
		(layers "F.Cu" "B.Cu")
		(net "GND")
	)
	(via
		(at 95.8215 -197.866)
		(size 0.508)
		(drill 0.254)
		(layers "F.Cu" "B.Cu")
		(net "GND")
	)
	(via
		(at 198.12 -218.44)
		(size 0.508)
		(drill 0.254)
		(layers "F.Cu" "B.Cu")
		(net "GND")
	)
	(via
		(at 101.6 -259.08)
		(size 0.508)
		(drill 0.254)
		(layers "F.Cu" "B.Cu")
		(net "GND")
	)
	(via
		(at 208.28 -325.12)
		(size 0.508)
		(drill 0.254)
		(layers "F.Cu" "B.Cu")
		(net "GND")
	)
	(via
		(at 219.314014 -158.852108)
		(size 0.508)
		(drill 0.254)
		(layers "F.Cu" "B.Cu")
		(net "GND")
	)
	(via
		(at 35.4584 -197.0024)
		(size 0.508)
		(drill 0.254)
		(layers "F.Cu" "B.Cu")
		(net "GND")
	)
	(via
		(at 222.616014 -56.18988)
		(size 0.508)
		(drill 0.254)
		(layers "F.Cu" "B.Cu")
		(net "GND")
	)
	(via
		(at 172.72 -25.4)
		(size 0.508)
		(drill 0.254)
		(layers "F.Cu" "B.Cu")
		(net "GND")
	)
	(via
		(at 53.989986 -504.603004)
		(size 0.508)
		(drill 0.254)
		(layers "F.Cu" "B.Cu")
		(net "GND")
	)
	(via
		(at 27.719782 -335.918048)
		(size 0.508)
		(drill 0.254)
		(layers "F.Cu" "B.Cu")
		(net "GND")
	)
	(via
		(at 132.08 -350.52)
		(size 0.508)
		(drill 0.254)
		(layers "F.Cu" "B.Cu")
		(net "GND")
	)
	(via
		(at 223.52 -304.8)
		(size 0.508)
		(drill 0.254)
		(layers "F.Cu" "B.Cu")
		(net "GND")
	)
	(via
		(at 71.12 -264.16)
		(size 0.508)
		(drill 0.254)
		(layers "F.Cu" "B.Cu")
		(net "GND")
	)
	(via
		(at 238.76 -66.04)
		(size 0.508)
		(drill 0.254)
		(layers "F.Cu" "B.Cu")
		(net "GND")
	)
	(via
		(at 147.32 -147.32)
		(size 0.508)
		(drill 0.254)
		(layers "F.Cu" "B.Cu")
		(net "GND")
	)
	(via
		(at 137.16 -162.56)
		(size 0.508)
		(drill 0.254)
		(layers "F.Cu" "B.Cu")
		(net "GND")
	)
	(via
		(at 215.904572 -1.397)
		(size 0.508)
		(drill 0.254)
		(layers "F.Cu" "B.Cu")
		(net "GND")
	)
	(via
		(at 223.52 -30.48)
		(size 0.508)
		(drill 0.254)
		(layers "F.Cu" "B.Cu")
		(net "GND")
	)
	(via
		(at 238.76 -193.04)
		(size 0.508)
		(drill 0.254)
		(layers "F.Cu" "B.Cu")
		(net "GND")
	)
	(via
		(at 213.36 -157.48)
		(size 0.508)
		(drill 0.254)
		(layers "F.Cu" "B.Cu")
		(net "GND")
	)
	(via
		(at 4.191 -324.690232)
		(size 0.508)
		(drill 0.254)
		(layers "F.Cu" "B.Cu")
		(net "GND")
	)
	(via
		(at 6.223 -349.474536)
		(size 0.508)
		(drill 0.254)
		(layers "F.Cu" "B.Cu")
		(net "GND")
	)
	(via
		(at 1.397 -254.075946)
		(size 0.508)
		(drill 0.254)
		(layers "F.Cu" "B.Cu")
		(net "GND")
	)
	(via
		(at 248.92 -15.24)
		(size 0.508)
		(drill 0.254)
		(layers "F.Cu" "B.Cu")
		(net "GND")
	)
	(via
		(at 177.8 -441.96)
		(size 0.508)
		(drill 0.254)
		(layers "F.Cu" "B.Cu")
		(net "GND")
	)
	(via
		(at 137.16 -15.24)
		(size 0.508)
		(drill 0.254)
		(layers "F.Cu" "B.Cu")
		(net "GND")
	)
	(via
		(at 218.313 -394.5128)
		(size 0.508)
		(drill 0.254)
		(layers "F.Cu" "B.Cu")
		(net "GND")
	)
	(via
		(at 177.8 -482.6)
		(size 0.508)
		(drill 0.254)
		(layers "F.Cu" "B.Cu")
		(net "GND")
	)
	(via
		(at 172.72 -55.88)
		(size 0.508)
		(drill 0.254)
		(layers "F.Cu" "B.Cu")
		(net "GND")
	)
	(via
		(at 238.76 -10.16)
		(size 0.508)
		(drill 0.254)
		(layers "F.Cu" "B.Cu")
		(net "GND")
	)
	(via
		(at 38.38575 -349.658432)
		(size 0.508)
		(drill 0.254)
		(layers "F.Cu" "B.Cu")
		(net "GND")
	)
	(via
		(at 10.16 -20.32)
		(size 0.508)
		(drill 0.254)
		(layers "F.Cu" "B.Cu")
		(net "GND")
	)
	(via
		(at 28.321 -290.83)
		(size 0.508)
		(drill 0.254)
		(layers "F.Cu" "B.Cu")
		(net "GND")
	)
	(via
		(at 86.36 -497.84)
		(size 0.508)
		(drill 0.254)
		(layers "F.Cu" "B.Cu")
		(net "GND")
	)
	(via
		(at 4.191 -201.090276)
		(size 0.508)
		(drill 0.254)
		(layers "F.Cu" "B.Cu")
		(net "GND")
	)
	(via
		(at 71.12 -304.8)
		(size 0.508)
		(drill 0.254)
		(layers "F.Cu" "B.Cu")
		(net "GND")
	)
	(via
		(at 127 -441.96)
		(size 0.508)
		(drill 0.254)
		(layers "F.Cu" "B.Cu")
		(net "GND")
	)
	(via
		(at 106.68 -198.12)
		(size 0.508)
		(drill 0.254)
		(layers "F.Cu" "B.Cu")
		(net "GND")
	)
	(via
		(at 203.2 -116.84)
		(size 0.508)
		(drill 0.254)
		(layers "F.Cu" "B.Cu")
		(net "GND")
	)
	(via
		(at 66.04 -304.8)
		(size 0.508)
		(drill 0.254)
		(layers "F.Cu" "B.Cu")
		(net "GND")
	)
	(via
		(at 91.44 -147.32)
		(size 0.508)
		(drill 0.254)
		(layers "F.Cu" "B.Cu")
		(net "GND")
	)
	(via
		(at 259.08 -91.44)
		(size 0.508)
		(drill 0.254)
		(layers "F.Cu" "B.Cu")
		(net "GND")
	)
	(via
		(at 96.52 -365.76)
		(size 0.508)
		(drill 0.254)
		(layers "F.Cu" "B.Cu")
		(net "GND")
	)
	(via
		(at 187.96 -294.64)
		(size 0.508)
		(drill 0.254)
		(layers "F.Cu" "B.Cu")
		(net "GND")
	)
	(via
		(at 152.4 -71.12)
		(size 0.508)
		(drill 0.254)
		(layers "F.Cu" "B.Cu")
		(net "GND")
	)
	(via
		(at 172.72 -91.44)
		(size 0.508)
		(drill 0.254)
		(layers "F.Cu" "B.Cu")
		(net "GND")
	)
	(via
		(at 5.08 -497.84)
		(size 0.508)
		(drill 0.254)
		(layers "F.Cu" "B.Cu")
		(net "GND")
	)
	(via
		(at 152.4 -441.96)
		(size 0.508)
		(drill 0.254)
		(layers "F.Cu" "B.Cu")
		(net "GND")
	)
	(via
		(at 238.76 -25.4)
		(size 0.508)
		(drill 0.254)
		(layers "F.Cu" "B.Cu")
		(net "GND")
	)
	(via
		(at 6.223 -388.394194)
		(size 0.508)
		(drill 0.254)
		(layers "F.Cu" "B.Cu")
		(net "GND")
	)
	(via
		(at 6.223 -329.609958)
		(size 0.508)
		(drill 0.254)
		(layers "F.Cu" "B.Cu")
		(net "GND")
	)
	(via
		(at 238.76 -177.8)
		(size 0.508)
		(drill 0.254)
		(layers "F.Cu" "B.Cu")
		(net "GND")
	)
	(via
		(at 182.88 -193.04)
		(size 0.508)
		(drill 0.254)
		(layers "F.Cu" "B.Cu")
		(net "GND")
	)
	(via
		(at 4.191 -153.966164)
		(size 0.508)
		(drill 0.254)
		(layers "F.Cu" "B.Cu")
		(net "GND")
	)
	(via
		(at 45.72 -355.6)
		(size 0.508)
		(drill 0.254)
		(layers "F.Cu" "B.Cu")
		(net "GND")
	)
	(via
		(at 37.5158 -392.557)
		(size 0.508)
		(drill 0.254)
		(layers "F.Cu" "B.Cu")
		(net "GND")
	)
	(via
		(at 233.68 -172.72)
		(size 0.508)
		(drill 0.254)
		(layers "F.Cu" "B.Cu")
		(net "GND")
	)
	(via
		(at 88.610694 -271.806416)
		(size 0.7112)
		(drill 0.3556)
		(layers "F.Cu" "B.Cu")
		(net "GND")
	)
	(via
		(at 162.56 -81.28)
		(size 0.508)
		(drill 0.254)
		(layers "F.Cu" "B.Cu")
		(net "GND")
	)
	(via
		(at 177.8 -45.72)
		(size 0.508)
		(drill 0.254)
		(layers "F.Cu" "B.Cu")
		(net "GND")
	)
	(via
		(at 243.84 -111.76)
		(size 0.508)
		(drill 0.254)
		(layers "F.Cu" "B.Cu")
		(net "GND")
	)
	(via
		(at 259.08 -314.96)
		(size 0.508)
		(drill 0.254)
		(layers "F.Cu" "B.Cu")
		(net "GND")
	)
	(via
		(at 127 -167.64)
		(size 0.508)
		(drill 0.254)
		(layers "F.Cu" "B.Cu")
		(net "GND")
	)
	(via
		(at 172.72 -502.92)
		(size 0.508)
		(drill 0.254)
		(layers "F.Cu" "B.Cu")
		(net "GND")
	)
	(via
		(at 150.509986 -504.603004)
		(size 0.508)
		(drill 0.254)
		(layers "F.Cu" "B.Cu")
		(net "GND")
	)
	(via
		(at 24.384 -231.009952)
		(size 0.508)
		(drill 0.254)
		(layers "F.Cu" "B.Cu")
		(net "GND")
	)
	(via
		(at 50.8 -457.2)
		(size 0.508)
		(drill 0.254)
		(layers "F.Cu" "B.Cu")
		(net "GND")
	)
	(via
		(at 111.76 -447.04)
		(size 0.508)
		(drill 0.254)
		(layers "F.Cu" "B.Cu")
		(net "GND")
	)
	(via
		(at 142.24 -55.88)
		(size 0.508)
		(drill 0.254)
		(layers "F.Cu" "B.Cu")
		(net "GND")
	)
	(via
		(at 147.32 -421.64)
		(size 0.508)
		(drill 0.254)
		(layers "F.Cu" "B.Cu")
		(net "GND")
	)
	(via
		(at 175.006 -404.495)
		(size 0.7112)
		(drill 0.3556)
		(layers "F.Cu" "B.Cu")
		(net "GND")
	)
	(via
		(at 121.92 -127)
		(size 0.508)
		(drill 0.254)
		(layers "F.Cu" "B.Cu")
		(net "GND")
	)
	(via
		(at 52.959 -302.26)
		(size 0.508)
		(drill 0.254)
		(layers "F.Cu" "B.Cu")
		(net "GND")
	)
	(via
		(at 167.64 -35.56)
		(size 0.508)
		(drill 0.254)
		(layers "F.Cu" "B.Cu")
		(net "GND")
	)
	(via
		(at 222.616014 -476.990156)
		(size 0.508)
		(drill 0.254)
		(layers "F.Cu" "B.Cu")
		(net "GND")
	)
	(via
		(at 86.36 -340.36)
		(size 0.508)
		(drill 0.254)
		(layers "F.Cu" "B.Cu")
		(net "GND")
	)
	(via
		(at 182.88 -233.68)
		(size 0.508)
		(drill 0.254)
		(layers "F.Cu" "B.Cu")
		(net "GND")
	)
	(via
		(at 37.61613 -268.590014)
		(size 0.508)
		(drill 0.254)
		(layers "F.Cu" "B.Cu")
		(net "GND")
	)
	(via
		(at 92.71 -302.387)
		(size 0.508)
		(drill 0.254)
		(layers "F.Cu" "B.Cu")
		(net "GND")
	)
	(via
		(at 27.69616 -223.393)
		(size 0.508)
		(drill 0.254)
		(layers "F.Cu" "B.Cu")
		(net "GND")
	)
	(via
		(at 142.24 -279.4)
		(size 0.508)
		(drill 0.254)
		(layers "F.Cu" "B.Cu")
		(net "GND")
	)
	(via
		(at 34.417 -50.927)
		(size 0.508)
		(drill 0.254)
		(layers "F.Cu" "B.Cu")
		(net "GND")
	)
	(via
		(at 54.61 -347.472)
		(size 0.508)
		(drill 0.254)
		(layers "F.Cu" "B.Cu")
		(net "GND")
	)
	(via
		(at 172.72 -330.2)
		(size 0.508)
		(drill 0.254)
		(layers "F.Cu" "B.Cu")
		(net "GND")
	)
	(via
		(at 233.68 -482.6)
		(size 0.508)
		(drill 0.254)
		(layers "F.Cu" "B.Cu")
		(net "GND")
	)
	(via
		(at 93.726 -440.563)
		(size 0.508)
		(drill 0.254)
		(layers "F.Cu" "B.Cu")
		(net "GND")
	)
	(via
		(at 147.32 -25.4)
		(size 0.508)
		(drill 0.254)
		(layers "F.Cu" "B.Cu")
		(net "GND")
	)
	(via
		(at 222.616014 -389.990076)
		(size 0.508)
		(drill 0.254)
		(layers "F.Cu" "B.Cu")
		(net "GND")
	)
	(via
		(at 162.56 -228.6)
		(size 0.508)
		(drill 0.254)
		(layers "F.Cu" "B.Cu")
		(net "GND")
	)
	(via
		(at 18.415 -23.154894)
		(size 0.508)
		(drill 0.254)
		(layers "F.Cu" "B.Cu")
		(net "GND")
	)
	(via
		(at 172.72 -436.88)
		(size 0.508)
		(drill 0.254)
		(layers "F.Cu" "B.Cu")
		(net "GND")
	)
	(via
		(at 238.76 -309.88)
		(size 0.508)
		(drill 0.254)
		(layers "F.Cu" "B.Cu")
		(net "GND")
	)
	(via
		(at 26.416 -237.744)
		(size 0.508)
		(drill 0.254)
		(layers "F.Cu" "B.Cu")
		(net "GND")
	)
	(via
		(at 4.445 -457.6826)
		(size 0.7112)
		(drill 0.4064)
		(layers "F.Cu" "B.Cu")
		(net "GND")
	)
	(via
		(at 66.04 -45.72)
		(size 0.508)
		(drill 0.254)
		(layers "F.Cu" "B.Cu")
		(net "GND")
	)
	(via
		(at 132.08 -381)
		(size 0.508)
		(drill 0.254)
		(layers "F.Cu" "B.Cu")
		(net "GND")
	)
	(via
		(at 20.32 -489.712)
		(size 0.508)
		(drill 0.254)
		(layers "F.Cu" "B.Cu")
		(net "GND")
	)
	(via
		(at 172.72 -106.68)
		(size 0.508)
		(drill 0.254)
		(layers "F.Cu" "B.Cu")
		(net "GND")
	)
	(via
		(at 167.64 -340.36)
		(size 0.508)
		(drill 0.254)
		(layers "F.Cu" "B.Cu")
		(net "GND")
	)
	(via
		(at 34.28873 -490.1311)
		(size 0.508)
		(drill 0.254)
		(layers "F.Cu" "B.Cu")
		(net "GND")
	)
	(via
		(at 111.76 -284.48)
		(size 0.508)
		(drill 0.254)
		(layers "F.Cu" "B.Cu")
		(net "GND")
	)
	(via
		(at 162.56 -10.16)
		(size 0.508)
		(drill 0.254)
		(layers "F.Cu" "B.Cu")
		(net "GND")
	)
	(via
		(at 262.103108 -453.636126)
		(size 0.508)
		(drill 0.254)
		(layers "F.Cu" "B.Cu")
		(net "GND")
	)
	(via
		(at 4.191 -177.89017)
		(size 0.508)
		(drill 0.254)
		(layers "F.Cu" "B.Cu")
		(net "GND")
	)
	(via
		(at 37.5412 -289.56)
		(size 0.508)
		(drill 0.254)
		(layers "F.Cu" "B.Cu")
		(net "GND")
	)
	(via
		(at 233.68 -76.2)
		(size 0.508)
		(drill 0.254)
		(layers "F.Cu" "B.Cu")
		(net "GND")
	)
	(via
		(at 233.68 -289.56)
		(size 0.508)
		(drill 0.254)
		(layers "F.Cu" "B.Cu")
		(net "GND")
	)
	(via
		(at 5.643626 -449.154042)
		(size 0.508)
		(drill 0.254)
		(layers "F.Cu" "B.Cu")
		(net "GND")
	)
	(via
		(at 228.585014 -261.605014)
		(size 0.508)
		(drill 0.254)
		(layers "F.Cu" "B.Cu")
		(net "GND")
	)
	(via
		(at 30.361636 -411.98165)
		(size 0.508)
		(drill 0.254)
		(layers "F.Cu" "B.Cu")
		(net "GND")
	)
	(via
		(at 24.384 -326.810116)
		(size 0.508)
		(drill 0.254)
		(layers "F.Cu" "B.Cu")
		(net "GND")
	)
	(via
		(at 6.223 -343.125552)
		(size 0.508)
		(drill 0.254)
		(layers "F.Cu" "B.Cu")
		(net "GND")
	)
	(via
		(at 238.76 -279.4)
		(size 0.508)
		(drill 0.254)
		(layers "F.Cu" "B.Cu")
		(net "GND")
	)
	(via
		(at 6.223 -176.462182)
		(size 0.508)
		(drill 0.254)
		(layers "F.Cu" "B.Cu")
		(net "GND")
	)
	(via
		(at 61.595 -432.435)
		(size 0.508)
		(drill 0.254)
		(layers "F.Cu" "B.Cu")
		(net "GND")
	)
	(via
		(at 213.36 -121.92)
		(size 0.508)
		(drill 0.254)
		(layers "F.Cu" "B.Cu")
		(net "GND")
	)
	(via
		(at 63.9572 -436.4736)
		(size 0.508)
		(drill 0.254)
		(layers "F.Cu" "B.Cu")
		(net "GND")
	)
	(via
		(at 147.32 -431.8)
		(size 0.508)
		(drill 0.254)
		(layers "F.Cu" "B.Cu")
		(net "GND")
	)
	(via
		(at 34.275014 -273.101308)
		(size 0.508)
		(drill 0.254)
		(layers "F.Cu" "B.Cu")
		(net "GND")
	)
	(via
		(at 11.4808 -468.1982)
		(size 0.508)
		(drill 0.254)
		(layers "F.Cu" "B.Cu")
		(net "GND")
	)
	(via
		(at 95.377 -306.578)
		(size 0.508)
		(drill 0.254)
		(layers "F.Cu" "B.Cu")
		(net "GND")
	)
	(via
		(at 116.84 -111.76)
		(size 0.508)
		(drill 0.254)
		(layers "F.Cu" "B.Cu")
		(net "GND")
	)
	(via
		(at 157.48 -50.8)
		(size 0.508)
		(drill 0.254)
		(layers "F.Cu" "B.Cu")
		(net "GND")
	)
	(via
		(at 111.76 -497.84)
		(size 0.508)
		(drill 0.254)
		(layers "F.Cu" "B.Cu")
		(net "GND")
	)
	(via
		(at 60.96 -35.56)
		(size 0.508)
		(drill 0.254)
		(layers "F.Cu" "B.Cu")
		(net "GND")
	)
	(via
		(at 203.2 -35.56)
		(size 0.508)
		(drill 0.254)
		(layers "F.Cu" "B.Cu")
		(net "GND")
	)
	(via
		(at 262.103108 -305.718464)
		(size 0.508)
		(drill 0.254)
		(layers "F.Cu" "B.Cu")
		(net "GND")
	)
	(via
		(at 254 -314.96)
		(size 0.508)
		(drill 0.254)
		(layers "F.Cu" "B.Cu")
		(net "GND")
	)
	(via
		(at 127 -208.28)
		(size 0.508)
		(drill 0.254)
		(layers "F.Cu" "B.Cu")
		(net "GND")
	)
	(via
		(at 116.84 -177.8)
		(size 0.508)
		(drill 0.254)
		(layers "F.Cu" "B.Cu")
		(net "GND")
	)
	(via
		(at 262.103108 -41.558464)
		(size 0.508)
		(drill 0.254)
		(layers "F.Cu" "B.Cu")
		(net "GND")
	)
	(via
		(at 182.88 -325.12)
		(size 0.508)
		(drill 0.254)
		(layers "F.Cu" "B.Cu")
		(net "GND")
	)
	(via
		(at 228.5746 -97.1042)
		(size 0.508)
		(drill 0.254)
		(layers "F.Cu" "B.Cu")
		(net "GND")
	)
	(via
		(at 60.96 -279.4)
		(size 0.508)
		(drill 0.254)
		(layers "F.Cu" "B.Cu")
		(net "GND")
	)
	(via
		(at 111.76 -147.32)
		(size 0.508)
		(drill 0.254)
		(layers "F.Cu" "B.Cu")
		(net "GND")
	)
	(via
		(at 101.6 -132.08)
		(size 0.508)
		(drill 0.254)
		(layers "F.Cu" "B.Cu")
		(net "GND")
	)
	(via
		(at 91.059 -23.749)
		(size 0.508)
		(drill 0.254)
		(layers "F.Cu" "B.Cu")
		(net "GND")
	)
	(via
		(at 24.3078 -309.8038)
		(size 0.508)
		(drill 0.254)
		(layers "F.Cu" "B.Cu")
		(net "GND")
	)
	(via
		(at 243.84 -45.72)
		(size 0.508)
		(drill 0.254)
		(layers "F.Cu" "B.Cu")
		(net "GND")
	)
	(via
		(at 91.44 -467.36)
		(size 0.508)
		(drill 0.254)
		(layers "F.Cu" "B.Cu")
		(net "GND")
	)
	(via
		(at 50.8 -91.44)
		(size 0.508)
		(drill 0.254)
		(layers "F.Cu" "B.Cu")
		(net "GND")
	)
	(via
		(at 4.191 -329.56627)
		(size 0.508)
		(drill 0.254)
		(layers "F.Cu" "B.Cu")
		(net "GND")
	)
	(via
		(at 127 -386.08)
		(size 0.508)
		(drill 0.254)
		(layers "F.Cu" "B.Cu")
		(net "GND")
	)
	(via
		(at 218.44 -365.76)
		(size 0.508)
		(drill 0.254)
		(layers "F.Cu" "B.Cu")
		(net "GND")
	)
	(via
		(at 208.28 -365.76)
		(size 0.508)
		(drill 0.254)
		(layers "F.Cu" "B.Cu")
		(net "GND")
	)
	(via
		(at 45.72 -365.76)
		(size 0.508)
		(drill 0.254)
		(layers "F.Cu" "B.Cu")
		(net "GND")
	)
	(via
		(at 7.8232 -458.5462)
		(size 0.7112)
		(drill 0.4064)
		(layers "F.Cu" "B.Cu")
		(net "GND")
	)
	(via
		(at 50.8 -279.4)
		(size 0.508)
		(drill 0.254)
		(layers "F.Cu" "B.Cu")
		(net "GND")
	)
	(via
		(at 147.32 -248.92)
		(size 0.508)
		(drill 0.254)
		(layers "F.Cu" "B.Cu")
		(net "GND")
	)
	(via
		(at 10.033 -463.1182)
		(size 0.508)
		(drill 0.254)
		(layers "F.Cu" "B.Cu")
		(net "GND")
	)
	(via
		(at 219.314014 -71.780908)
		(size 0.508)
		(drill 0.254)
		(layers "F.Cu" "B.Cu")
		(net "GND")
	)
	(via
		(at 106.68 -355.6)
		(size 0.508)
		(drill 0.254)
		(layers "F.Cu" "B.Cu")
		(net "GND")
	)
	(via
		(at 60.96 -497.84)
		(size 0.508)
		(drill 0.254)
		(layers "F.Cu" "B.Cu")
		(net "GND")
	)
	(via
		(at 6.223 -432.442874)
		(size 0.508)
		(drill 0.254)
		(layers "F.Cu" "B.Cu")
		(net "GND")
	)
	(via
		(at 5.08 -10.16)
		(size 0.508)
		(drill 0.254)
		(layers "F.Cu" "B.Cu")
		(net "GND")
	)
	(via
		(at 91.948 -202.438)
		(size 0.508)
		(drill 0.254)
		(layers "F.Cu" "B.Cu")
		(net "GND")
	)
	(via
		(at 142.24 -370.84)
		(size 0.508)
		(drill 0.254)
		(layers "F.Cu" "B.Cu")
		(net "GND")
	)
	(via
		(at 19.05 -300.355)
		(size 0.508)
		(drill 0.254)
		(layers "F.Cu" "B.Cu")
		(net "GND")
	)
	(via
		(at 40.64 -223.52)
		(size 0.508)
		(drill 0.254)
		(layers "F.Cu" "B.Cu")
		(net "GND")
	)
	(via
		(at 233.68 -193.04)
		(size 0.508)
		(drill 0.254)
		(layers "F.Cu" "B.Cu")
		(net "GND")
	)
	(via
		(at 254 -152.4)
		(size 0.508)
		(drill 0.254)
		(layers "F.Cu" "B.Cu")
		(net "GND")
	)
	(via
		(at 167.64 -96.52)
		(size 0.508)
		(drill 0.254)
		(layers "F.Cu" "B.Cu")
		(net "GND")
	)
	(via
		(at 76.835 -360.426)
		(size 0.508)
		(drill 0.254)
		(layers "F.Cu" "B.Cu")
		(net "GND")
	)
	(via
		(at 137.16 -284.48)
		(size 0.508)
		(drill 0.254)
		(layers "F.Cu" "B.Cu")
		(net "GND")
	)
	(via
		(at 20.32 -375.92)
		(size 0.508)
		(drill 0.254)
		(layers "F.Cu" "B.Cu")
		(net "GND")
	)
	(via
		(at 243.84 -452.12)
		(size 0.508)
		(drill 0.254)
		(layers "F.Cu" "B.Cu")
		(net "GND")
	)
	(via
		(at 142.24 -76.2)
		(size 0.508)
		(drill 0.254)
		(layers "F.Cu" "B.Cu")
		(net "GND")
	)
	(via
		(at 238.76 -40.64)
		(size 0.508)
		(drill 0.254)
		(layers "F.Cu" "B.Cu")
		(net "GND")
	)
	(via
		(at 132.08 -91.44)
		(size 0.508)
		(drill 0.254)
		(layers "F.Cu" "B.Cu")
		(net "GND")
	)
	(via
		(at 243.84 -5.08)
		(size 0.508)
		(drill 0.254)
		(layers "F.Cu" "B.Cu")
		(net "GND")
	)
	(via
		(at 6.223 -302.40986)
		(size 0.508)
		(drill 0.254)
		(layers "F.Cu" "B.Cu")
		(net "GND")
	)
	(via
		(at 172.72 -111.76)
		(size 0.508)
		(drill 0.254)
		(layers "F.Cu" "B.Cu")
		(net "GND")
	)
	(via
		(at 259.08 -441.96)
		(size 0.508)
		(drill 0.254)
		(layers "F.Cu" "B.Cu")
		(net "GND")
	)
	(via
		(at 262.103108 -77.118464)
		(size 0.508)
		(drill 0.254)
		(layers "F.Cu" "B.Cu")
		(net "GND")
	)
	(via
		(at 71.12 -30.48)
		(size 0.508)
		(drill 0.254)
		(layers "F.Cu" "B.Cu")
		(net "GND")
	)
	(via
		(at 76.2 -86.36)
		(size 0.508)
		(drill 0.254)
		(layers "F.Cu" "B.Cu")
		(net "GND")
	)
	(via
		(at 228.585014 -381.115062)
		(size 0.508)
		(drill 0.254)
		(layers "F.Cu" "B.Cu")
		(net "GND")
	)
	(via
		(at 35.56 -166.116)
		(size 0.508)
		(drill 0.254)
		(layers "F.Cu" "B.Cu")
		(net "GND")
	)
	(via
		(at 1.397 -81.529428)
		(size 0.508)
		(drill 0.254)
		(layers "F.Cu" "B.Cu")
		(net "GND")
	)
	(segment
		(start 1.868932 -193.542158)
		(end 3.767074 -193.542158)
		(width 0.508)
		(layer "B.Cu")
		(net "GND")
	)
	(segment
		(start 3.76682 -334.742028)
		(end 4.191 -335.166208)
		(width 0.508)
		(layer "B.Cu")
		(net "GND")
	)
	(segment
		(start 3.801872 -412.741872)
		(end 4.191 -413.131)
		(width 0.508)
		(layer "B.Cu")
		(net "GND")
	)
	(segment
		(start 1.868932 -204.742034)
		(end 3.739134 -204.742034)
		(width 0.508)
		(layer "B.Cu")
		(net "GND")
	)
	(segment
		(start 3.767074 -337.942174)
		(end 4.191 -338.3661)
		(width 0.508)
		(layer "B.Cu")
		(net "GND")
	)
	(segment
		(start 1.868932 -440.741816)
		(end 3.861816 -440.741816)
		(width 0.508)
		(layer "B.Cu")
		(net "GND")
	)
	(segment
		(start 3.7592 -448.7418)
		(end 4.191 -448.31)
		(width 0.508)
		(layer "B.Cu")
		(net "GND")
	)
	(segment
		(start 1.868932 -304.342038)
		(end 3.739134 -304.342038)
		(width 0.508)
		(layer "B.Cu")
		(net "GND")
	)
	(segment
		(start 3.76682 -298.7421)
		(end 4.191 -299.16628)
		(width 0.508)
		(layer "B.Cu")
		(net "GND")
	)
	(segment
		(start 3.739134 -359.54208)
		(end 4.191 -359.090214)
		(width 0.508)
		(layer "B.Cu")
		(net "GND")
	)
	(segment
		(start 3.76682 -159.942022)
		(end 4.191 -160.366202)
		(width 0.508)
		(layer "B.Cu")
		(net "GND")
	)
	(segment
		(start 3.61188 -316.342014)
		(end 4.191 -316.921134)
		(width 0.508)
		(layer "B.Cu")
		(net "GND")
	)
	(segment
		(start 3.76682 -153.541984)
		(end 4.191 -153.966164)
		(width 0.508)
		(layer "B.Cu")
		(net "GND")
	)
	(segment
		(start 3.861562 -443.141862)
		(end 1.868932 -443.141862)
		(width 0.508)
		(layer "B.Cu")
		(net "GND")
	)
	(segment
		(start 1.868932 -179.142136)
		(end 3.767074 -179.142136)
		(width 0.508)
		(layer "B.Cu")
		(net "GND")
	)
	(segment
		(start 3.774948 -425.541948)
		(end 4.191 -425.958)
		(width 0.508)
		(layer "B.Cu")
		(net "GND")
	)
	(segment
		(start 1.868932 -297.942)
		(end 3.739134 -297.942)
		(width 0.508)
		(layer "B.Cu")
		(net "GND")
	)
	(segment
		(start 1.868932 -227.94214)
		(end 3.767074 -227.94214)
		(width 0.508)
		(layer "B.Cu")
		(net "GND")
	)
	(segment
		(start 1.868932 -408.74188)
		(end 3.75412 -408.74188)
		(width 0.508)
		(layer "B.Cu")
		(net "GND")
	)
	(segment
		(start 1.868932 -308.34203)
		(end 3.76682 -308.34203)
		(width 0.508)
		(layer "B.Cu")
		(net "GND")
	)
	(segment
		(start 3.767074 -344.342212)
		(end 4.191 -344.766138)
		(width 0.508)
		(layer "B.Cu")
		(net "GND")
	)
	(segment
		(start 1.868932 -223.942148)
		(end 3.739134 -223.942148)
		(width 0.508)
		(layer "B.Cu")
		(net "GND")
	)
	(segment
		(start 3.739134 -331.542136)
		(end 4.191 -331.09027)
		(width 0.508)
		(layer "B.Cu")
		(net "GND")
	)
	(segment
		(start 256.093976 -420.649908)
		(end 252.73 -420.649908)
		(width 0.8128)
		(layer "B.Cu")
		(net "GND")
	)
	(segment
		(start 3.739134 -211.142072)
		(end 4.191 -210.690206)
		(width 0.508)
		(layer "B.Cu")
		(net "GND")
	)
	(segment
		(start 3.76682 -357.142034)
		(end 4.191 -357.566214)
		(width 0.508)
		(layer "B.Cu")
		(net "GND")
	)
	(segment
		(start 3.739134 -297.942)
		(end 4.191 -297.490134)
		(width 0.508)
		(layer "B.Cu")
		(net "GND")
	)
	(segment
		(start 3.73888 -356.342188)
		(end 4.191 -355.890068)
		(width 0.508)
		(layer "B.Cu")
		(net "GND")
	)
	(segment
		(start 1.868932 -347.542104)
		(end 3.76682 -347.542104)
		(width 0.508)
		(layer "B.Cu")
		(net "GND")
	)
	(segment
		(start 8.501126 -257.142234)
		(end 8.501126 -261.498842)
		(width 0.508)
		(layer "B.Cu")
		(net "GND")
	)
	(segment
		(start 3.739134 -175.142144)
		(end 4.191 -174.690278)
		(width 0.508)
		(layer "B.Cu")
		(net "GND")
	)
	(segment
		(start 4.191 -436.235348)
		(end 3.684524 -436.741824)
		(width 0.508)
		(layer "B.Cu")
		(net "GND")
	)
	(segment
		(start 3.73888 -214.342218)
		(end 4.191 -213.890098)
		(width 0.508)
		(layer "B.Cu")
		(net "GND")
	)
	(segment
		(start 3.76682 -199.142096)
		(end 4.191 -199.566276)
		(width 0.508)
		(layer "B.Cu")
		(net "GND")
	)
	(segment
		(start 3.791966 -391.141966)
		(end 4.191 -391.541)
		(width 0.508)
		(layer "B.Cu")
		(net "GND")
	)
	(segment
		(start 3.840988 -393.542012)
		(end 4.191 -393.192)
		(width 0.508)
		(layer "B.Cu")
		(net "GND")
	)
	(segment
		(start 1.868932 -298.7421)
		(end 3.76682 -298.7421)
		(width 0.508)
		(layer "B.Cu")
		(net "GND")
	)
	(segment
		(start 3.76682 -175.94199)
		(end 4.191 -176.36617)
		(width 0.508)
		(layer "B.Cu")
		(net "GND")
	)
	(segment
		(start 256.093976 -425.729908)
		(end 252.755908 -425.729908)
		(width 0.8128)
		(layer "B.Cu")
		(net "GND")
	)
	(segment
		(start 1.868932 -343.542112)
		(end 3.739134 -343.542112)
		(width 0.508)
		(layer "B.Cu")
		(net "GND")
	)
	(segment
		(start 3.612388 -415.942018)
		(end 1.868932 -415.942018)
		(width 0.508)
		(layer "B.Cu")
		(net "GND")
	)
	(segment
		(start 3.684778 -434.341778)
		(end 4.191 -434.848)
		(width 0.508)
		(layer "B.Cu")
		(net "GND")
	)
	(segment
		(start 1.868932 -434.341778)
		(end 3.684778 -434.341778)
		(width 0.508)
		(layer "B.Cu")
		(net "GND")
	)
	(segment
		(start 3.73888 -230.342186)
		(end 4.191 -229.890066)
		(width 0.508)
		(layer "B.Cu")
		(net "GND")
	)
	(segment
		(start 1.868932 -443.941962)
		(end 3.886962 -443.941962)
		(width 0.508)
		(layer "B.Cu")
		(net "GND")
	)
	(segment
		(start 1.868932 -386.341874)
		(end 4.191 -386.341874)
		(width 0.508)
		(layer "B.Cu")
		(net "GND")
	)
	(segment
		(start 1.868932 -233.542078)
		(end 3.739134 -233.542078)
		(width 0.508)
		(layer "B.Cu")
		(net "GND")
	)
	(segment
		(start 1.868932 -169.542206)
		(end 3.767074 -169.542206)
		(width 0.508)
		(layer "B.Cu")
		(net "GND")
	)
	(segment
		(start 1.868932 -409.54198)
		(end 3.77698 -409.54198)
		(width 0.508)
		(layer "B.Cu")
		(net "GND")
	)
	(segment
		(start 1.868932 -301.142146)
		(end 3.739134 -301.142146)
		(width 0.508)
		(layer "B.Cu")
		(net "GND")
	)
	(segment
		(start 1.868932 -215.142064)
		(end 3.76682 -215.142064)
		(width 0.508)
		(layer "B.Cu")
		(net "GND")
	)
	(segment
		(start 3.61188 -190.342012)
		(end 4.191 -190.921132)
		(width 0.508)
		(layer "B.Cu")
		(net "GND")
	)
	(segment
		(start 1.868932 -428.74184)
		(end 3.79984 -428.74184)
		(width 0.508)
		(layer "B.Cu")
		(net "GND")
	)
	(segment
		(start 4.191 -424.162982)
		(end 3.612134 -424.741848)
		(width 0.508)
		(layer "B.Cu")
		(net "GND")
	)
	(segment
		(start 3.739134 -233.542078)
		(end 4.191 -233.090212)
		(width 0.508)
		(layer "B.Cu")
		(net "GND")
	)
	(segment
		(start 1.868932 -403.141942)
		(end 3.853942 -403.141942)
		(width 0.508)
		(layer "B.Cu")
		(net "GND")
	)
	(segment
		(start 1.868932 -390.341866)
		(end 3.739134 -390.341866)
		(width 0.508)
		(layer "B.Cu")
		(net "GND")
	)
	(segment
		(start 1.868932 -230.342186)
		(end 3.73888 -230.342186)
		(width 0.508)
		(layer "B.Cu")
		(net "GND")
	)
	(segment
		(start 3.76682 -347.542104)
		(end 4.191 -347.966284)
		(width 0.508)
		(layer "B.Cu")
		(net "GND")
	)
	(segment
		(start 1.868932 -165.542214)
		(end 3.621786 -165.542214)
		(width 0.508)
		(layer "B.Cu")
		(net "GND")
	)
	(segment
		(start 1.868932 -231.142032)
		(end 3.76682 -231.142032)
		(width 0.508)
		(layer "B.Cu")
		(net "GND")
	)
	(segment
		(start 1.868932 -349.94215)
		(end 3.739134 -349.94215)
		(width 0.508)
		(layer "B.Cu")
		(net "GND")
	)
	(segment
		(start 3.767074 -218.34221)
		(end 4.191 -218.766136)
		(width 0.508)
		(layer "B.Cu")
		(net "GND")
	)
	(segment
		(start 1.868932 -356.342188)
		(end 3.73888 -356.342188)
		(width 0.508)
		(layer "B.Cu")
		(net "GND")
	)
	(segment
		(start 3.767074 -169.542206)
		(end 4.191 -169.966132)
		(width 0.508)
		(layer "B.Cu")
		(net "GND")
	)
	(segment
		(start 1.868932 -415.141918)
		(end 3.831082 -415.141918)
		(width 0.508)
		(layer "B.Cu")
		(net "GND")
	)
	(segment
		(start 1.868932 -391.141966)
		(end 3.791966 -391.141966)
		(width 0.508)
		(layer "B.Cu")
		(net "GND")
	)
	(segment
		(start 3.767074 -289.14217)
		(end 4.191 -289.566096)
		(width 0.508)
		(layer "B.Cu")
		(net "GND")
	)
	(segment
		(start 1.868932 -328.34199)
		(end 3.739134 -328.34199)
		(width 0.508)
		(layer "B.Cu")
		(net "GND")
	)
	(segment
		(start 3.73888 -195.942204)
		(end 4.191 -195.490084)
		(width 0.508)
		(layer "B.Cu")
		(net "GND")
	)
	(segment
		(start 3.739134 -162.342068)
		(end 4.191 -161.890202)
		(width 0.508)
		(layer "B.Cu")
		(net "GND")
	)
	(segment
		(start 3.76682 -205.542134)
		(end 4.191 -205.966314)
		(width 0.508)
		(layer "B.Cu")
		(net "GND")
	)
	(segment
		(start 3.73888 -181.542182)
		(end 4.191 -181.090062)
		(width 0.508)
		(layer "B.Cu")
		(net "GND")
	)
	(segment
		(start 3.77698 -409.54198)
		(end 4.191 -409.956)
		(width 0.508)
		(layer "B.Cu")
		(net "GND")
	)
	(segment
		(start 8.501126 -261.498842)
		(end 8.501126 -265.85545)
		(width 0.508)
		(layer "B.Cu")
		(net "GND")
	)
	(segment
		(start 64.144652 -378.498608)
		(end 68.50126 -378.498608)
		(width 0.508)
		(layer "B.Cu")
		(net "GND")
	)
	(segment
		(start 3.767074 -319.54216)
		(end 4.191 -319.966086)
		(width 0.508)
		(layer "B.Cu")
		(net "GND")
	)
	(segment
		(start 1.868932 -159.942022)
		(end 3.76682 -159.942022)
		(width 0.508)
		(layer "B.Cu")
		(net "GND")
	)
	(segment
		(start 1.868932 -337.942174)
		(end 3.767074 -337.942174)
		(width 0.508)
		(layer "B.Cu")
		(net "GND")
	)
	(segment
		(start 3.73888 -340.34222)
		(end 4.191 -339.8901)
		(width 0.508)
		(layer "B.Cu")
		(net "GND")
	)
	(segment
		(start 1.868932 -437.541924)
		(end 3.836924 -437.541924)
		(width 0.508)
		(layer "B.Cu")
		(net "GND")
	)
	(segment
		(start 1.868932 -184.742074)
		(end 3.739134 -184.742074)
		(width 0.508)
		(layer "B.Cu")
		(net "GND")
	)
	(segment
		(start 1.868932 -159.142176)
		(end 3.739134 -159.142176)
		(width 0.508)
		(layer "B.Cu")
		(net "GND")
	)
	(segment
		(start 1.868932 -214.342218)
		(end 3.73888 -214.342218)
		(width 0.508)
		(layer "B.Cu")
		(net "GND")
	)
	(segment
		(start 68.50126 -378.498608)
		(end 68.50126 -382.855216)
		(width 0.508)
		(layer "B.Cu")
		(net "GND")
	)
	(segment
		(start 3.611626 -422.341802)
		(end 4.191 -422.921176)
		(width 0.508)
		(layer "B.Cu")
		(net "GND")
	)
	(segment
		(start 3.791204 -399.941796)
		(end 4.191 -399.542)
		(width 0.508)
		(layer "B.Cu")
		(net "GND")
	)
	(segment
		(start 1.868932 -162.342068)
		(end 3.739134 -162.342068)
		(width 0.508)
		(layer "B.Cu")
		(net "GND")
	)
	(segment
		(start 3.739134 -171.941998)
		(end 4.191 -171.490132)
		(width 0.508)
		(layer "B.Cu")
		(net "GND")
	)
	(segment
		(start 1.868932 -201.542142)
		(end 3.739134 -201.542142)
		(width 0.508)
		(layer "B.Cu")
		(net "GND")
	)
	(segment
		(start 1.868932 -192.742058)
		(end 3.739134 -192.742058)
		(width 0.508)
		(layer "B.Cu")
		(net "GND")
	)
	(segment
		(start 1.868932 -285.142178)
		(end 3.739134 -285.142178)
		(width 0.508)
		(layer "B.Cu")
		(net "GND")
	)
	(segment
		(start 1.868932 -331.542136)
		(end 3.739134 -331.542136)
		(width 0.508)
		(layer "B.Cu")
		(net "GND")
	)
	(segment
		(start 1.868932 -289.14217)
		(end 3.767074 -289.14217)
		(width 0.508)
		(layer "B.Cu")
		(net "GND")
	)
	(segment
		(start 3.76682 -208.742026)
		(end 4.191 -209.166206)
		(width 0.508)
		(layer "B.Cu")
		(net "GND")
	)
	(segment
		(start 1.868932 -305.142138)
		(end 3.767074 -305.142138)
		(width 0.508)
		(layer "B.Cu")
		(net "GND")
	)
	(segment
		(start 1.868932 -425.541948)
		(end 3.774948 -425.541948)
		(width 0.508)
		(layer "B.Cu")
		(net "GND")
	)
	(segment
		(start 1.868932 -207.94218)
		(end 3.739134 -207.94218)
		(width 0.508)
		(layer "B.Cu")
		(net "GND")
	)
	(segment
		(start 1.868932 -310.742076)
		(end 3.739134 -310.742076)
		(width 0.508)
		(layer "B.Cu")
		(net "GND")
	)
	(segment
		(start 1.868932 -166.34206)
		(end 3.65506 -166.34206)
		(width 0.508)
		(layer "B.Cu")
		(net "GND")
	)
	(segment
		(start 1.868932 -319.54216)
		(end 3.767074 -319.54216)
		(width 0.508)
		(layer "B.Cu")
		(net "GND")
	)
	(segment
		(start 3.779012 -405.541988)
		(end 4.191 -405.13)
		(width 0.508)
		(layer "B.Cu")
		(net "GND")
	)
	(segment
		(start 1.868932 -393.542012)
		(end 3.840988 -393.542012)
		(width 0.508)
		(layer "B.Cu")
		(net "GND")
	)
	(segment
		(start 3.767074 -193.542158)
		(end 4.191 -193.966084)
		(width 0.508)
		(layer "B.Cu")
		(net "GND")
	)
	(segment
		(start 3.684524 -436.741824)
		(end 1.868932 -436.741824)
		(width 0.508)
		(layer "B.Cu")
		(net "GND")
	)
	(segment
		(start 1.868932 -340.34222)
		(end 3.73888 -340.34222)
		(width 0.508)
		(layer "B.Cu")
		(net "GND")
	)
	(segment
		(start 4.144518 -261.498842)
		(end 8.501126 -261.498842)
		(width 0.508)
		(layer "B.Cu")
		(net "GND")
	)
	(segment
		(start 3.73888 -291.542216)
		(end 4.191 -291.090096)
		(width 0.508)
		(layer "B.Cu")
		(net "GND")
	)
	(segment
		(start 3.853942 -403.141942)
		(end 4.191 -403.479)
		(width 0.508)
		(layer "B.Cu")
		(net "GND")
	)
	(segment
		(start 4.191 -427.52518)
		(end 3.774186 -427.941994)
		(width 0.508)
		(layer "B.Cu")
		(net "GND")
	)
	(segment
		(start 1.868932 -175.94199)
		(end 3.76682 -175.94199)
		(width 0.508)
		(layer "B.Cu")
		(net "GND")
	)
	(segment
		(start 1.868932 -205.542134)
		(end 3.76682 -205.542134)
		(width 0.508)
		(layer "B.Cu")
		(net "GND")
	)
	(segment
		(start 3.772154 -451.141846)
		(end 4.191 -450.723)
		(width 0.508)
		(layer "B.Cu")
		(net "GND")
	)
	(segment
		(start 1.868932 -279.541986)
		(end 3.76682 -279.541986)
		(width 0.508)
		(layer "B.Cu")
		(net "GND")
	)
	(segment
		(start 3.621786 -165.542214)
		(end 4.191 -164.973)
		(width 0.508)
		(layer "B.Cu")
		(net "GND")
	)
	(segment
		(start 1.868932 -411.941772)
		(end 3.729228 -411.941772)
		(width 0.508)
		(layer "B.Cu")
		(net "GND")
	)
	(segment
		(start 1.868932 -412.741872)
		(end 3.801872 -412.741872)
		(width 0.508)
		(layer "B.Cu")
		(net "GND")
	)
	(segment
		(start 3.739134 -207.94218)
		(end 4.191 -207.490314)
		(width 0.508)
		(layer "B.Cu")
		(net "GND")
	)
	(segment
		(start 3.76682 -341.142066)
		(end 4.191 -341.566246)
		(width 0.508)
		(layer "B.Cu")
		(net "GND")
	)
	(segment
		(start 3.76682 -387.94182)
		(end 4.191 -388.366)
		(width 0.508)
		(layer "B.Cu")
		(net "GND")
	)
	(segment
		(start 3.739134 -328.34199)
		(end 4.191 -327.890124)
		(width 0.508)
		(layer "B.Cu")
		(net "GND")
	)
	(segment
		(start 3.739134 -285.142178)
		(end 4.191 -284.690312)
		(width 0.508)
		(layer "B.Cu")
		(net "GND")
	)
	(segment
		(start 1.868932 -282.742132)
		(end 3.76682 -282.742132)
		(width 0.508)
		(layer "B.Cu")
		(net "GND")
	)
	(segment
		(start 3.767074 -353.942142)
		(end 4.191 -354.366068)
		(width 0.508)
		(layer "B.Cu")
		(net "GND")
	)
	(segment
		(start 1.868932 -172.742098)
		(end 3.76682 -172.742098)
		(width 0.508)
		(layer "B.Cu")
		(net "GND")
	)
	(segment
		(start 4.191 -439.587132)
		(end 3.836162 -439.94197)
		(width 0.508)
		(layer "B.Cu")
		(net "GND")
	)
	(segment
		(start 256.093976 -411.759908)
		(end 252.222 -411.759908)
		(width 0.8128)
		(layer "B.Cu")
		(net "GND")
	)
	(segment
		(start 3.739134 -178.342036)
		(end 4.191 -177.89017)
		(width 0.508)
		(layer "B.Cu")
		(net "GND")
	)
	(segment
		(start 1.868932 -406.341834)
		(end 3.751834 -406.341834)
		(width 0.508)
		(layer "B.Cu")
		(net "GND")
	)
	(segment
		(start 3.739134 -223.942148)
		(end 4.191 -223.490282)
		(width 0.508)
		(layer "B.Cu")
		(net "GND")
	)
	(segment
		(start 1.868932 -301.941992)
		(end 3.76682 -301.941992)
		(width 0.508)
		(layer "B.Cu")
		(net "GND")
	)
	(segment
		(start 4.191 -417.957)
		(end 4.191 -417.76269)
		(width 0.508)
		(layer "B.Cu")
		(net "GND")
	)
	(segment
		(start 1.868932 -396.741904)
		(end 3.816096 -396.741904)
		(width 0.508)
		(layer "B.Cu")
		(net "GND")
	)
	(segment
		(start 3.76682 -322.742052)
		(end 4.191 -323.166232)
		(width 0.508)
		(layer "B.Cu")
		(net "GND")
	)
	(segment
		(start 3.739134 -349.94215)
		(end 4.191 -349.490284)
		(width 0.508)
		(layer "B.Cu")
		(net "GND")
	)
	(segment
		(start 3.739134 -346.742004)
		(end 4.191 -346.290138)
		(width 0.508)
		(layer "B.Cu")
		(net "GND")
	)
	(segment
		(start 1.868932 -292.342062)
		(end 3.76682 -292.342062)
		(width 0.508)
		(layer "B.Cu")
		(net "GND")
	)
	(segment
		(start 1.868932 -334.742028)
		(end 3.76682 -334.742028)
		(width 0.508)
		(layer "B.Cu")
		(net "GND")
	)
	(segment
		(start 1.868932 -394.341858)
		(end 3.816858 -394.341858)
		(width 0.508)
		(layer "B.Cu")
		(net "GND")
	)
	(segment
		(start 3.739134 -220.742002)
		(end 4.191 -220.290136)
		(width 0.508)
		(layer "B.Cu")
		(net "GND")
	)
	(segment
		(start 1.868932 -329.14209)
		(end 3.76682 -329.14209)
		(width 0.508)
		(layer "B.Cu")
		(net "GND")
	)
	(segment
		(start 3.76682 -231.142032)
		(end 4.191 -231.566212)
		(width 0.508)
		(layer "B.Cu")
		(net "GND")
	)
	(segment
		(start 1.868932 -208.742026)
		(end 3.76682 -208.742026)
		(width 0.508)
		(layer "B.Cu")
		(net "GND")
	)
	(segment
		(start 3.76682 -215.142064)
		(end 4.191 -215.566244)
		(width 0.508)
		(layer "B.Cu")
		(net "GND")
	)
	(segment
		(start 3.767074 -325.942198)
		(end 4.191 -326.366124)
		(width 0.508)
		(layer "B.Cu")
		(net "GND")
	)
	(segment
		(start 1.868932 -182.342028)
		(end 3.76682 -182.342028)
		(width 0.508)
		(layer "B.Cu")
		(net "GND")
	)
	(segment
		(start 1.868932 -325.942198)
		(end 3.767074 -325.942198)
		(width 0.508)
		(layer "B.Cu")
		(net "GND")
	)
	(segment
		(start 4.191 -416.52063)
		(end 3.612388 -415.942018)
		(width 0.508)
		(layer "B.Cu")
		(net "GND")
	)
	(segment
		(start 3.739134 -155.94203)
		(end 4.191 -155.490164)
		(width 0.508)
		(layer "B.Cu")
		(net "GND")
	)
	(segment
		(start 3.739134 -325.142098)
		(end 4.191 -324.690232)
		(width 0.508)
		(layer "B.Cu")
		(net "GND")
	)
	(segment
		(start 3.739134 -294.742108)
		(end 4.191 -294.290242)
		(width 0.508)
		(layer "B.Cu")
		(net "GND")
	)
	(segment
		(start 3.76682 -172.742098)
		(end 4.191 -173.166278)
		(width 0.508)
		(layer "B.Cu")
		(net "GND")
	)
	(segment
		(start 1.868932 -325.142098)
		(end 3.739134 -325.142098)
		(width 0.508)
		(layer "B.Cu")
		(net "GND")
	)
	(segment
		(start 3.767074 -227.94214)
		(end 4.191 -228.366066)
		(width 0.508)
		(layer "B.Cu")
		(net "GND")
	)
	(segment
		(start 3.76682 -308.34203)
		(end 4.191 -308.76621)
		(width 0.508)
		(layer "B.Cu")
		(net "GND")
	)
	(segment
		(start 3.816858 -394.341858)
		(end 4.191 -394.716)
		(width 0.508)
		(layer "B.Cu")
		(net "GND")
	)
	(segment
		(start 252.222 -411.759908)
		(end 251.866908 -412.115)
		(width 0.8128)
		(layer "B.Cu")
		(net "GND")
	)
	(segment
		(start 3.739134 -343.542112)
		(end 4.191 -343.090246)
		(width 0.508)
		(layer "B.Cu")
		(net "GND")
	)
	(segment
		(start 1.868932 -397.542004)
		(end 3.842004 -397.542004)
		(width 0.508)
		(layer "B.Cu")
		(net "GND")
	)
	(segment
		(start 1.868932 -217.54211)
		(end 3.739134 -217.54211)
		(width 0.508)
		(layer "B.Cu")
		(net "GND")
	)
	(segment
		(start 3.886962 -443.941962)
		(end 4.191 -444.246)
		(width 0.508)
		(layer "B.Cu")
		(net "GND")
	)
	(segment
		(start 1.868932 -195.942204)
		(end 3.73888 -195.942204)
		(width 0.508)
		(layer "B.Cu")
		(net "GND")
	)
	(segment
		(start 3.831082 -415.141918)
		(end 4.191 -414.782)
		(width 0.508)
		(layer "B.Cu")
		(net "GND")
	)
	(segment
		(start 1.868932 -451.141846)
		(end 3.772154 -451.141846)
		(width 0.508)
		(layer "B.Cu")
		(net "GND")
	)
	(segment
		(start 3.739134 -318.74206)
		(end 4.191 -318.290194)
		(width 0.508)
		(layer "B.Cu")
		(net "GND")
	)
	(segment
		(start 3.774186 -427.941994)
		(end 1.868932 -427.941994)
		(width 0.508)
		(layer "B.Cu")
		(net "GND")
	)
	(segment
		(start 3.76682 -292.342062)
		(end 4.191 -292.766242)
		(width 0.508)
		(layer "B.Cu")
		(net "GND")
	)
	(segment
		(start 1.868932 -155.94203)
		(end 3.739134 -155.94203)
		(width 0.508)
		(layer "B.Cu")
		(net "GND")
	)
	(segment
		(start 68.50126 -374.142)
		(end 68.50126 -378.498608)
		(width 0.508)
		(layer "B.Cu")
		(net "GND")
	)
	(segment
		(start 3.76682 -279.541986)
		(end 4.191 -279.966166)
		(width 0.508)
		(layer "B.Cu")
		(net "GND")
	)
	(segment
		(start 1.868932 -405.541988)
		(end 3.779012 -405.541988)
		(width 0.508)
		(layer "B.Cu")
		(net "GND")
	)
	(segment
		(start 1.868932 -350.741996)
		(end 3.76682 -350.741996)
		(width 0.508)
		(layer "B.Cu")
		(net "GND")
	)
	(segment
		(start 3.739134 -201.542142)
		(end 4.191 -201.090276)
		(width 0.508)
		(layer "B.Cu")
		(net "GND")
	)
	(segment
		(start 3.739134 -390.341866)
		(end 4.191 -389.89)
		(width 0.508)
		(layer "B.Cu")
		(net "GND")
	)
	(segment
		(start 1.868932 -291.542216)
		(end 3.73888 -291.542216)
		(width 0.508)
		(layer "B.Cu")
		(net "GND")
	)
	(segment
		(start 1.868932 -220.742002)
		(end 3.739134 -220.742002)
		(width 0.508)
		(layer "B.Cu")
		(net "GND")
	)
	(segment
		(start 3.76682 -182.342028)
		(end 4.191 -182.766208)
		(width 0.508)
		(layer "B.Cu")
		(net "GND")
	)
	(segment
		(start 3.75412 -408.74188)
		(end 4.191 -408.305)
		(width 0.508)
		(layer "B.Cu")
		(net "GND")
	)
	(segment
		(start 3.76682 -156.74213)
		(end 4.191 -157.16631)
		(width 0.508)
		(layer "B.Cu")
		(net "GND")
	)
	(segment
		(start 1.868932 -431.141886)
		(end 3.833114 -431.141886)
		(width 0.508)
		(layer "B.Cu")
		(net "GND")
	)
	(segment
		(start 1.868932 -178.342036)
		(end 3.739134 -178.342036)
		(width 0.508)
		(layer "B.Cu")
		(net "GND")
	)
	(segment
		(start 3.739134 -184.742074)
		(end 4.191 -184.290208)
		(width 0.508)
		(layer "B.Cu")
		(net "GND")
	)
	(segment
		(start 1.868932 -181.542182)
		(end 3.73888 -181.542182)
		(width 0.508)
		(layer "B.Cu")
		(net "GND")
	)
	(segment
		(start 1.868932 -321.942206)
		(end 3.73888 -321.942206)
		(width 0.508)
		(layer "B.Cu")
		(net "GND")
	)
	(segment
		(start 3.751834 -406.341834)
		(end 4.191 -406.781)
		(width 0.508)
		(layer "B.Cu")
		(net "GND")
	)
	(segment
		(start 3.836162 -439.94197)
		(end 1.868932 -439.94197)
		(width 0.508)
		(layer "B.Cu")
		(net "GND")
	)
	(segment
		(start 1.868932 -341.142066)
		(end 3.76682 -341.142066)
		(width 0.508)
		(layer "B.Cu")
		(net "GND")
	)
	(segment
		(start 1.868932 -344.342212)
		(end 3.767074 -344.342212)
		(width 0.508)
		(layer "B.Cu")
		(net "GND")
	)
	(segment
		(start 1.868932 -156.74213)
		(end 3.76682 -156.74213)
		(width 0.508)
		(layer "B.Cu")
		(net "GND")
	)
	(segment
		(start 1.868932 -153.541984)
		(end 3.76682 -153.541984)
		(width 0.508)
		(layer "B.Cu")
		(net "GND")
	)
	(segment
		(start 1.868932 -448.7418)
		(end 3.7592 -448.7418)
		(width 0.508)
		(layer "B.Cu")
		(net "GND")
	)
	(segment
		(start 3.816096 -396.741904)
		(end 4.191 -396.367)
		(width 0.508)
		(layer "B.Cu")
		(net "GND")
	)
	(segment
		(start 3.739134 -353.142042)
		(end 4.191 -352.690176)
		(width 0.508)
		(layer "B.Cu")
		(net "GND")
	)
	(segment
		(start 1.868932 -318.74206)
		(end 3.739134 -318.74206)
		(width 0.508)
		(layer "B.Cu")
		(net "GND")
	)
	(segment
		(start 3.76682 -202.341988)
		(end 4.191 -202.766168)
		(width 0.508)
		(layer "B.Cu")
		(net "GND")
	)
	(segment
		(start 3.65506 -166.34206)
		(end 4.191 -166.878)
		(width 0.508)
		(layer "B.Cu")
		(net "GND")
	)
	(segment
		(start 3.739134 -304.342038)
		(end 4.191 -303.890172)
		(width 0.508)
		(layer "B.Cu")
		(net "GND")
	)
	(segment
		(start 3.767074 -179.142136)
		(end 4.191 -179.566062)
		(width 0.508)
		(layer "B.Cu")
		(net "GND")
	)
	(segment
		(start 1.868932 -307.542184)
		(end 3.73888 -307.542184)
		(width 0.508)
		(layer "B.Cu")
		(net "GND")
	)
	(segment
		(start 1.868932 -294.742108)
		(end 3.739134 -294.742108)
		(width 0.508)
		(layer "B.Cu")
		(net "GND")
	)
	(segment
		(start 1.868932 -221.542102)
		(end 3.76682 -221.542102)
		(width 0.508)
		(layer "B.Cu")
		(net "GND")
	)
	(segment
		(start 3.739134 -217.54211)
		(end 4.191 -217.090244)
		(width 0.508)
		(layer "B.Cu")
		(net "GND")
	)
	(segment
		(start 1.868932 -346.742004)
		(end 3.739134 -346.742004)
		(width 0.508)
		(layer "B.Cu")
		(net "GND")
	)
	(segment
		(start 3.76682 -301.941992)
		(end 4.191 -302.366172)
		(width 0.508)
		(layer "B.Cu")
		(net "GND")
	)
	(segment
		(start 3.842004 -397.542004)
		(end 4.191 -397.891)
		(width 0.508)
		(layer "B.Cu")
		(net "GND")
	)
	(segment
		(start 8.501126 -261.498842)
		(end 12.857734 -261.498842)
		(width 0.508)
		(layer "B.Cu")
		(net "GND")
	)
	(segment
		(start 3.76682 -350.741996)
		(end 4.191 -351.166176)
		(width 0.508)
		(layer "B.Cu")
		(net "GND")
	)
	(segment
		(start 3.739134 -204.742034)
		(end 4.191 -204.290168)
		(width 0.508)
		(layer "B.Cu")
		(net "GND")
	)
	(segment
		(start 3.861816 -440.741816)
		(end 4.191 -441.071)
		(width 0.508)
		(layer "B.Cu")
		(net "GND")
	)
	(segment
		(start 3.836924 -437.541924)
		(end 4.191 -437.896)
		(width 0.508)
		(layer "B.Cu")
		(net "GND")
	)
	(segment
		(start 1.868932 -171.941998)
		(end 3.739134 -171.941998)
		(width 0.508)
		(layer "B.Cu")
		(net "GND")
	)
	(segment
		(start 1.868932 -202.341988)
		(end 3.76682 -202.341988)
		(width 0.508)
		(layer "B.Cu")
		(net "GND")
	)
	(segment
		(start 3.76682 -282.742132)
		(end 4.191 -283.166312)
		(width 0.508)
		(layer "B.Cu")
		(net "GND")
	)
	(segment
		(start 1.868932 -316.342014)
		(end 3.61188 -316.342014)
		(width 0.508)
		(layer "B.Cu")
		(net "GND")
	)
	(segment
		(start 1.868932 -295.542208)
		(end 3.767074 -295.542208)
		(width 0.508)
		(layer "B.Cu")
		(net "GND")
	)
	(segment
		(start 1.868932 -218.34221)
		(end 3.767074 -218.34221)
		(width 0.508)
		(layer "B.Cu")
		(net "GND")
	)
	(segment
		(start 4.191 -163.71062)
		(end 3.622548 -163.142168)
		(width 0.508)
		(layer "B.Cu")
		(net "GND")
	)
	(segment
		(start 3.73888 -307.542184)
		(end 4.191 -307.090064)
		(width 0.508)
		(layer "B.Cu")
		(net "GND")
	)
	(segment
		(start 3.767074 -295.542208)
		(end 4.191 -295.966134)
		(width 0.508)
		(layer "B.Cu")
		(net "GND")
	)
	(segment
		(start 3.739134 -281.942032)
		(end 4.191 -281.490166)
		(width 0.508)
		(layer "B.Cu")
		(net "GND")
	)
	(segment
		(start 3.654298 -168.742106)
		(end 1.868932 -168.742106)
		(width 0.508)
		(layer "B.Cu")
		(net "GND")
	)
	(segment
		(start 4.191 -442.812424)
		(end 3.861562 -443.141862)
		(width 0.508)
		(layer "B.Cu")
		(net "GND")
	)
	(segment
		(start 3.622548 -163.142168)
		(end 1.868932 -163.142168)
		(width 0.508)
		(layer "B.Cu")
		(net "GND")
	)
	(segment
		(start 1.868932 -322.742052)
		(end 3.76682 -322.742052)
		(width 0.508)
		(layer "B.Cu")
		(net "GND")
	)
	(segment
		(start 1.868932 -211.942172)
		(end 3.767074 -211.942172)
		(width 0.508)
		(layer "B.Cu")
		(net "GND")
	)
	(segment
		(start 1.868932 -211.142072)
		(end 3.739134 -211.142072)
		(width 0.508)
		(layer "B.Cu")
		(net "GND")
	)
	(segment
		(start 3.80619 -418.34181)
		(end 4.191 -417.957)
		(width 0.508)
		(layer "B.Cu")
		(net "GND")
	)
	(segment
		(start 1.868932 -357.142034)
		(end 3.76682 -357.142034)
		(width 0.508)
		(layer "B.Cu")
		(net "GND")
	)
	(segment
		(start 3.739134 -301.142146)
		(end 4.191 -300.69028)
		(width 0.508)
		(layer "B.Cu")
		(net "GND")
	)
	(segment
		(start 3.739134 -192.742058)
		(end 4.191 -192.290192)
		(width 0.508)
		(layer "B.Cu")
		(net "GND")
	)
	(segment
		(start 3.767074 -305.142138)
		(end 4.191 -305.566064)
		(width 0.508)
		(layer "B.Cu")
		(net "GND")
	)
	(segment
		(start 4.191 -168.205404)
		(end 3.654298 -168.742106)
		(width 0.508)
		(layer "B.Cu")
		(net "GND")
	)
	(segment
		(start 3.8862 -446.342008)
		(end 1.868932 -446.342008)
		(width 0.508)
		(layer "B.Cu")
		(net "GND")
	)
	(segment
		(start 256.093976 -423.189908)
		(end 252.73 -423.189908)
		(width 0.508)
		(layer "B.Cu")
		(net "GND")
	)
	(segment
		(start 3.76682 -221.542102)
		(end 4.191 -221.966282)
		(width 0.508)
		(layer "B.Cu")
		(net "GND")
	)
	(segment
		(start 1.868932 -359.54208)
		(end 3.739134 -359.54208)
		(width 0.508)
		(layer "B.Cu")
		(net "GND")
	)
	(segment
		(start 1.868932 -353.942142)
		(end 3.767074 -353.942142)
		(width 0.508)
		(layer "B.Cu")
		(net "GND")
	)
	(segment
		(start 1.868932 -175.142144)
		(end 3.739134 -175.142144)
		(width 0.508)
		(layer "B.Cu")
		(net "GND")
	)
	(segment
		(start 1.868932 -199.142096)
		(end 3.76682 -199.142096)
		(width 0.508)
		(layer "B.Cu")
		(net "GND")
	)
	(segment
		(start 1.868932 -387.94182)
		(end 3.76682 -387.94182)
		(width 0.508)
		(layer "B.Cu")
		(net "GND")
	)
	(segment
		(start 3.73888 -321.942206)
		(end 4.191 -321.490086)
		(width 0.508)
		(layer "B.Cu")
		(net "GND")
	)
	(segment
		(start 3.767074 -211.942172)
		(end 4.191 -212.366098)
		(width 0.508)
		(layer "B.Cu")
		(net "GND")
	)
	(segment
		(start 1.868932 -281.942032)
		(end 3.739134 -281.942032)
		(width 0.508)
		(layer "B.Cu")
		(net "GND")
	)
	(segment
		(start 3.833114 -431.141886)
		(end 4.191 -430.784)
		(width 0.508)
		(layer "B.Cu")
		(net "GND")
	)
	(segment
		(start 4.191 -446.037208)
		(end 3.8862 -446.342008)
		(width 0.508)
		(layer "B.Cu")
		(net "GND")
	)
	(segment
		(start 3.739134 -310.742076)
		(end 4.191 -310.29021)
		(width 0.508)
		(layer "B.Cu")
		(net "GND")
	)
	(segment
		(start 1.868932 -418.34181)
		(end 3.80619 -418.34181)
		(width 0.508)
		(layer "B.Cu")
		(net "GND")
	)
	(segment
		(start 3.739134 -337.142074)
		(end 4.191 -336.690208)
		(width 0.508)
		(layer "B.Cu")
		(net "GND")
	)
	(segment
		(start 3.739134 -159.142176)
		(end 4.191 -158.69031)
		(width 0.508)
		(layer "B.Cu")
		(net "GND")
	)
	(segment
		(start 68.50126 -378.498608)
		(end 72.857868 -378.498608)
		(width 0.508)
		(layer "B.Cu")
		(net "GND")
	)
	(segment
		(start 1.868932 -337.142074)
		(end 3.739134 -337.142074)
		(width 0.508)
		(layer "B.Cu")
		(net "GND")
	)
	(segment
		(start 1.868932 -399.941796)
		(end 3.791204 -399.941796)
		(width 0.508)
		(layer "B.Cu")
		(net "GND")
	)
	(segment
		(start 1.868932 -353.142042)
		(end 3.739134 -353.142042)
		(width 0.508)
		(layer "B.Cu")
		(net "GND")
	)
	(segment
		(start 3.79984 -428.74184)
		(end 4.191 -429.133)
		(width 0.508)
		(layer "B.Cu")
		(net "GND")
	)
	(segment
		(start 3.729228 -411.941772)
		(end 4.191 -411.48)
		(width 0.508)
		(layer "B.Cu")
		(net "GND")
	)
	(segment
		(start 1.868932 -422.341802)
		(end 3.611626 -422.341802)
		(width 0.508)
		(layer "B.Cu")
		(net "GND")
	)
	(segment
		(start 1.868932 -190.342012)
		(end 3.61188 -190.342012)
		(width 0.508)
		(layer "B.Cu")
		(net "GND")
	)
	(segment
		(start 3.76682 -329.14209)
		(end 4.191 -329.56627)
		(width 0.508)
		(layer "B.Cu")
		(net "GND")
	)
	(segment
		(start 3.612134 -424.741848)
		(end 1.868932 -424.741848)
		(width 0.508)
		(layer "B.Cu")
		(net "GND")
	)
	(segment
		(start 253.898908 -420.649908)
		(end 256.474976 -420.649908)
		(width 0.17145)
		(layer "F.Cu")
		(net "FCB_HW_REVISION")
	)
	(segment
		(start 236.474 -421.386)
		(end 238.379 -421.386)
		(width 0.17145)
		(layer "F.Cu")
		(net "FCB_HW_REVISION")
	)
	(segment
		(start 250.063 -419.608)
		(end 250.571 -420.116)
		(width 0.17145)
		(layer "F.Cu")
		(net "FCB_HW_REVISION")
	)
	(segment
		(start 240.157 -419.608)
		(end 250.063 -419.608)
		(width 0.17145)
		(layer "F.Cu")
		(net "FCB_HW_REVISION")
	)
	(segment
		(start 253.365 -420.116)
		(end 253.898908 -420.649908)
		(width 0.17145)
		(layer "F.Cu")
		(net "FCB_HW_REVISION")
	)
	(segment
		(start 250.571 -420.116)
		(end 253.365 -420.116)
		(width 0.17145)
		(layer "F.Cu")
		(net "FCB_HW_REVISION")
	)
	(segment
		(start 238.379 -421.386)
		(end 240.157 -419.608)
		(width 0.17145)
		(layer "F.Cu")
		(net "FCB_HW_REVISION")
	)
	(via
		(at 236.474 -424.561)
		(size 0.7112)
		(drill 0.3556)
		(layers "F.Cu" "B.Cu")
		(net "FCB_HW_REVISION")
	)
	(via
		(at 236.474 -421.386)
		(size 0.508)
		(drill 0.254)
		(layers "F.Cu" "B.Cu")
		(net "FCB_HW_REVISION")
	)
	(segment
		(start 31.874206 -492.3282)
		(end 32.854392 -492.3282)
		(width 0.17145)
		(layer "B.Cu")
		(net "FCB_HW_REVISION")
	)
	(segment
		(start 13.76045 -479.74885)
		(end 14.660626 -480.649026)
		(width 0.17145)
		(layer "B.Cu")
		(net "FCB_HW_REVISION")
	)
	(segment
		(start 13.76045 -458.066648)
		(end 13.76045 -473.114116)
		(width 0.17145)
		(layer "B.Cu")
		(net "FCB_HW_REVISION")
	)
	(segment
		(start 14.106652 -476.767652)
		(end 13.76045 -477.113854)
		(width 0.17145)
		(layer "B.Cu")
		(net "FCB_HW_REVISION")
	)
	(segment
		(start 220.1799 -453.720708)
		(end 229.032308 -444.8683)
		(width 0.17145)
		(layer "B.Cu")
		(net "FCB_HW_REVISION")
	)
	(segment
		(start 229.032308 -444.8683)
		(end 236.271308 -444.8683)
		(width 0.17145)
		(layer "B.Cu")
		(net "FCB_HW_REVISION")
	)
	(segment
		(start 35.445192 -494.919)
		(end 184.315608 -494.919)
		(width 0.17145)
		(layer "B.Cu")
		(net "FCB_HW_REVISION")
	)
	(segment
		(start 236.271308 -444.8683)
		(end 239.3569 -441.782708)
		(width 0.17145)
		(layer "B.Cu")
		(net "FCB_HW_REVISION")
	)
	(segment
		(start 184.315608 -494.919)
		(end 220.1799 -459.054708)
		(width 0.17145)
		(layer "B.Cu")
		(net "FCB_HW_REVISION")
	)
	(segment
		(start 1.868932 -454.341992)
		(end 3.620008 -454.341992)
		(width 0.17145)
		(layer "B.Cu")
		(net "FCB_HW_REVISION")
	)
	(segment
		(start 13.76045 -477.113854)
		(end 13.76045 -479.74885)
		(width 0.17145)
		(layer "B.Cu")
		(net "FCB_HW_REVISION")
	)
	(segment
		(start 14.106652 -473.460318)
		(end 14.106652 -476.767652)
		(width 0.17145)
		(layer "B.Cu")
		(net "FCB_HW_REVISION")
	)
	(segment
		(start 3.620008 -454.341992)
		(end 3.7338 -454.2282)
		(width 0.17145)
		(layer "B.Cu")
		(net "FCB_HW_REVISION")
	)
	(segment
		(start 236.474 -425.45)
		(end 236.474 -424.561)
		(width 0.17145)
		(layer "B.Cu")
		(net "FCB_HW_REVISION")
	)
	(segment
		(start 13.76045 -473.114116)
		(end 14.106652 -473.460318)
		(width 0.17145)
		(layer "B.Cu")
		(net "FCB_HW_REVISION")
	)
	(segment
		(start 6.879336 -455.89825)
		(end 11.592052 -455.89825)
		(width 0.17145)
		(layer "B.Cu")
		(net "FCB_HW_REVISION")
	)
	(segment
		(start 11.592052 -455.89825)
		(end 13.76045 -458.066648)
		(width 0.17145)
		(layer "B.Cu")
		(net "FCB_HW_REVISION")
	)
	(segment
		(start 220.1799 -459.054708)
		(end 220.1799 -453.720708)
		(width 0.17145)
		(layer "B.Cu")
		(net "FCB_HW_REVISION")
	)
	(segment
		(start 239.3569 -428.3329)
		(end 236.474 -425.45)
		(width 0.17145)
		(layer "B.Cu")
		(net "FCB_HW_REVISION")
	)
	(segment
		(start 32.854392 -492.3282)
		(end 35.445192 -494.919)
		(width 0.17145)
		(layer "B.Cu")
		(net "FCB_HW_REVISION")
	)
	(segment
		(start 5.209286 -454.2282)
		(end 6.879336 -455.89825)
		(width 0.17145)
		(layer "B.Cu")
		(net "FCB_HW_REVISION")
	)
	(segment
		(start 14.660626 -480.649026)
		(end 20.195032 -480.649026)
		(width 0.17145)
		(layer "B.Cu")
		(net "FCB_HW_REVISION")
	)
	(segment
		(start 236.474 -424.561)
		(end 236.474 -421.386)
		(width 0.17145)
		(layer "B.Cu")
		(net "FCB_HW_REVISION")
	)
	(segment
		(start 3.7338 -454.2282)
		(end 5.209286 -454.2282)
		(width 0.17145)
		(layer "B.Cu")
		(net "FCB_HW_REVISION")
	)
	(segment
		(start 239.3569 -441.782708)
		(end 239.3569 -428.3329)
		(width 0.17145)
		(layer "B.Cu")
		(net "FCB_HW_REVISION")
	)
	(segment
		(start 20.195032 -480.649026)
		(end 31.874206 -492.3282)
		(width 0.17145)
		(layer "B.Cu")
		(net "FCB_HW_REVISION")
	)
	(segment
		(start 70.68312 -445.1096)
		(end 70.68312 -444.30188)
		(width 0.17145)
		(layer "F.Cu")
		(net "EEPROM_WP")
	)
	(segment
		(start 71.247 -440.6265)
		(end 71.374 -440.7535)
		(width 0.17145)
		(layer "F.Cu")
		(net "EEPROM_WP")
	)
	(segment
		(start 70.68312 -444.30188)
		(end 71.628 -443.357)
		(width 0.17145)
		(layer "F.Cu")
		(net "EEPROM_WP")
	)
	(segment
		(start 71.374 -443.103)
		(end 71.628 -443.357)
		(width 0.17145)
		(layer "F.Cu")
		(net "EEPROM_WP")
	)
	(segment
		(start 71.374 -440.7535)
		(end 71.374 -443.103)
		(width 0.17145)
		(layer "F.Cu")
		(net "EEPROM_WP")
	)
	(via
		(at 71.628 -443.357)
		(size 0.7112)
		(drill 0.3556)
		(layers "F.Cu" "B.Cu")
		(net "EEPROM_WP")
	)
	(segment
		(start 68.834 -443.357)
		(end 68.834 -441.0075)
		(width 0.17145)
		(layer "F.Cu")
		(net "EEPROM_SDA")
	)
	(segment
		(start 69.38264 -445.1096)
		(end 69.38264 -443.90564)
		(width 0.17145)
		(layer "F.Cu")
		(net "EEPROM_SDA")
	)
	(segment
		(start 69.38264 -443.90564)
		(end 68.834 -443.357)
		(width 0.17145)
		(layer "F.Cu")
		(net "EEPROM_SDA")
	)
	(segment
		(start 68.834 -441.0075)
		(end 69.215 -440.6265)
		(width 0.17145)
		(layer "F.Cu")
		(net "EEPROM_SDA")
	)
	(via
		(at 68.834 -443.357)
		(size 0.7112)
		(drill 0.3556)
		(layers "F.Cu" "B.Cu")
		(net "EEPROM_SDA")
	)
	(segment
		(start 70.231 -442.849)
		(end 70.231 -441.96)
		(width 0.17145)
		(layer "F.Cu")
		(net "EEPROM_SCL")
	)
	(segment
		(start 70.231 -440.6265)
		(end 70.231 -441.96)
		(width 0.17145)
		(layer "F.Cu")
		(net "EEPROM_SCL")
	)
	(segment
		(start 70.03288 -443.04712)
		(end 70.231 -442.849)
		(width 0.17145)
		(layer "F.Cu")
		(net "EEPROM_SCL")
	)
	(segment
		(start 70.03288 -445.1096)
		(end 70.03288 -443.04712)
		(width 0.17145)
		(layer "F.Cu")
		(net "EEPROM_SCL")
	)
	(via
		(at 70.231 -441.96)
		(size 0.7112)
		(drill 0.3556)
		(layers "F.Cu" "B.Cu")
		(net "EEPROM_SCL")
	)
	(segment
		(start 69.977 -454.2155)
		(end 68.961 -454.2155)
		(width 0.17145)
		(layer "F.Cu")
		(net "EEPROM_A2")
	)
	(segment
		(start 68.961 -452.882)
		(end 68.961 -454.2155)
		(width 0.17145)
		(layer "F.Cu")
		(net "EEPROM_A2")
	)
	(segment
		(start 70.03288 -450.7484)
		(end 70.03288 -451.81012)
		(width 0.17145)
		(layer "F.Cu")
		(net "EEPROM_A2")
	)
	(segment
		(start 70.03288 -451.81012)
		(end 68.961 -452.882)
		(width 0.17145)
		(layer "F.Cu")
		(net "EEPROM_A2")
	)
	(via
		(at 68.961 -452.882)
		(size 0.7112)
		(drill 0.3556)
		(layers "F.Cu" "B.Cu")
		(net "EEPROM_A2")
	)
	(segment
		(start 70.993 -452.2216)
		(end 70.993 -452.882)
		(width 0.17145)
		(layer "F.Cu")
		(net "EEPROM_A1")
	)
	(segment
		(start 72.009 -454.2155)
		(end 70.993 -454.2155)
		(width 0.17145)
		(layer "F.Cu")
		(net "EEPROM_A1")
	)
	(segment
		(start 70.68312 -451.91172)
		(end 70.993 -452.2216)
		(width 0.17145)
		(layer "F.Cu")
		(net "EEPROM_A1")
	)
	(segment
		(start 70.993 -454.2155)
		(end 70.993 -452.882)
		(width 0.17145)
		(layer "F.Cu")
		(net "EEPROM_A1")
	)
	(segment
		(start 70.68312 -450.7484)
		(end 70.68312 -451.91172)
		(width 0.17145)
		(layer "F.Cu")
		(net "EEPROM_A1")
	)
	(via
		(at 70.993 -452.882)
		(size 0.7112)
		(drill 0.3556)
		(layers "F.Cu" "B.Cu")
		(net "EEPROM_A1")
	)
	(segment
		(start 71.33336 -451.57136)
		(end 71.8566 -452.0946)
		(width 0.17145)
		(layer "F.Cu")
		(net "EEPROM_A0")
	)
	(segment
		(start 72.2376 -452.0946)
		(end 73.025 -452.882)
		(width 0.17145)
		(layer "F.Cu")
		(net "EEPROM_A0")
	)
	(segment
		(start 73.025 -454.2155)
		(end 73.025 -452.882)
		(width 0.17145)
		(layer "F.Cu")
		(net "EEPROM_A0")
	)
	(segment
		(start 71.8566 -452.0946)
		(end 72.2376 -452.0946)
		(width 0.17145)
		(layer "F.Cu")
		(net "EEPROM_A0")
	)
	(segment
		(start 74.041 -454.2155)
		(end 73.025 -454.2155)
		(width 0.17145)
		(layer "F.Cu")
		(net "EEPROM_A0")
	)
	(segment
		(start 71.33336 -450.7484)
		(end 71.33336 -451.57136)
		(width 0.17145)
		(layer "F.Cu")
		(net "EEPROM_A0")
	)
	(via
		(at 73.025 -452.882)
		(size 0.7112)
		(drill 0.3556)
		(layers "F.Cu" "B.Cu")
		(net "EEPROM_A0")
	)
	(segment
		(start 47.309278 -40.132)
		(end 48.8315 -40.132)
		(width 0.17145)
		(layer "F.Cu")
		(net "DRV_ACT_9")
	)
	(segment
		(start 45.031406 -40.693594)
		(end 45.350938 -40.374062)
		(width 0.17145)
		(layer "F.Cu")
		(net "DRV_ACT_9")
	)
	(segment
		(start 47.067216 -40.374062)
		(end 47.309278 -40.132)
		(width 0.17145)
		(layer "F.Cu")
		(net "DRV_ACT_9")
	)
	(segment
		(start 46.072298 -40.374062)
		(end 47.067216 -40.374062)
		(width 0.17145)
		(layer "F.Cu")
		(net "DRV_ACT_9")
	)
	(segment
		(start 48.8315 -41.275)
		(end 48.8315 -40.132)
		(width 0.17145)
		(layer "F.Cu")
		(net "DRV_ACT_9")
	)
	(segment
		(start 44.23029 -40.693594)
		(end 45.031406 -40.693594)
		(width 0.17145)
		(layer "F.Cu")
		(net "DRV_ACT_9")
	)
	(segment
		(start 45.350938 -40.374062)
		(end 46.072298 -40.374062)
		(width 0.17145)
		(layer "F.Cu")
		(net "DRV_ACT_9")
	)
	(via
		(at 46.072298 -40.374062)
		(size 0.7112)
		(drill 0.3556)
		(layers "F.Cu" "B.Cu")
		(net "DRV_ACT_9")
	)
	(segment
		(start 48.006 -143.37411)
		(end 46.072298 -143.37411)
		(width 0.17145)
		(layer "F.Cu")
		(net "DRV_ACT_8")
	)
	(segment
		(start 45.404532 -143.37411)
		(end 46.072298 -143.37411)
		(width 0.17145)
		(layer "F.Cu")
		(net "DRV_ACT_8")
	)
	(segment
		(start 45.085 -143.693642)
		(end 45.404532 -143.37411)
		(width 0.17145)
		(layer "F.Cu")
		(net "DRV_ACT_8")
	)
	(segment
		(start 48.7045 -144.526)
		(end 48.7045 -143.383)
		(width 0.17145)
		(layer "F.Cu")
		(net "DRV_ACT_8")
	)
	(segment
		(start 48.7045 -143.383)
		(end 48.01489 -143.383)
		(width 0.17145)
		(layer "F.Cu")
		(net "DRV_ACT_8")
	)
	(segment
		(start 44.23029 -143.693642)
		(end 45.085 -143.693642)
		(width 0.17145)
		(layer "F.Cu")
		(net "DRV_ACT_8")
	)
	(segment
		(start 48.01489 -143.383)
		(end 48.006 -143.37411)
		(width 0.17145)
		(layer "F.Cu")
		(net "DRV_ACT_8")
	)
	(via
		(at 46.072298 -143.37411)
		(size 0.7112)
		(drill 0.3556)
		(layers "F.Cu" "B.Cu")
		(net "DRV_ACT_8")
	)
	(segment
		(start 45.90415 -245.94185)
		(end 45.15231 -246.69369)
		(width 0.17145)
		(layer "F.Cu")
		(net "DRV_ACT_7")
	)
	(segment
		(start 48.8315 -247.396)
		(end 48.8315 -246.253)
		(width 0.17145)
		(layer "F.Cu")
		(net "DRV_ACT_7")
	)
	(segment
		(start 46.694852 -245.94185)
		(end 45.90415 -245.94185)
		(width 0.17145)
		(layer "F.Cu")
		(net "DRV_ACT_7")
	)
	(segment
		(start 45.15231 -246.69369)
		(end 44.23029 -246.69369)
		(width 0.17145)
		(layer "F.Cu")
		(net "DRV_ACT_7")
	)
	(segment
		(start 46.694852 -245.94185)
		(end 47.82185 -245.94185)
		(width 0.17145)
		(layer "F.Cu")
		(net "DRV_ACT_7")
	)
	(segment
		(start 48.133 -246.253)
		(end 48.8315 -246.253)
		(width 0.17145)
		(layer "F.Cu")
		(net "DRV_ACT_7")
	)
	(segment
		(start 47.82185 -245.94185)
		(end 48.133 -246.253)
		(width 0.17145)
		(layer "F.Cu")
		(net "DRV_ACT_7")
	)
	(via
		(at 46.694852 -245.94185)
		(size 0.7112)
		(drill 0.3556)
		(layers "F.Cu" "B.Cu")
		(net "DRV_ACT_7")
	)
	(segment
		(start 47.4345 -348.742)
		(end 46.99 -348.742)
		(width 0.17145)
		(layer "F.Cu")
		(net "DRV_ACT_6")
	)
	(segment
		(start 44.23029 -349.693484)
		(end 44.895516 -349.693484)
		(width 0.17145)
		(layer "F.Cu")
		(net "DRV_ACT_6")
	)
	(segment
		(start 45.3898 -349.1992)
		(end 46.0502 -349.1992)
		(width 0.17145)
		(layer "F.Cu")
		(net "DRV_ACT_6")
	)
	(segment
		(start 46.99 -348.742)
		(end 46.5328 -349.1992)
		(width 0.17145)
		(layer "F.Cu")
		(net "DRV_ACT_6")
	)
	(segment
		(start 46.5328 -349.1992)
		(end 46.0502 -349.1992)
		(width 0.17145)
		(layer "F.Cu")
		(net "DRV_ACT_6")
	)
	(segment
		(start 44.895516 -349.693484)
		(end 45.3898 -349.1992)
		(width 0.17145)
		(layer "F.Cu")
		(net "DRV_ACT_6")
	)
	(segment
		(start 47.4345 -349.885)
		(end 47.4345 -348.742)
		(width 0.17145)
		(layer "F.Cu")
		(net "DRV_ACT_6")
	)
	(via
		(at 46.0502 -349.1992)
		(size 0.7112)
		(drill 0.3556)
		(layers "F.Cu" "B.Cu")
		(net "DRV_ACT_6")
	)
	(segment
		(start 47.117 -452.374)
		(end 46.072298 -452.374)
		(width 0.17145)
		(layer "F.Cu")
		(net "DRV_ACT_5")
	)
	(segment
		(start 45.277532 -452.374)
		(end 46.072298 -452.374)
		(width 0.17145)
		(layer "F.Cu")
		(net "DRV_ACT_5")
	)
	(segment
		(start 44.958 -452.693532)
		(end 45.277532 -452.374)
		(width 0.17145)
		(layer "F.Cu")
		(net "DRV_ACT_5")
	)
	(segment
		(start 48.5775 -453.644)
		(end 48.5775 -452.501)
		(width 0.17145)
		(layer "F.Cu")
		(net "DRV_ACT_5")
	)
	(segment
		(start 47.244 -452.501)
		(end 47.117 -452.374)
		(width 0.17145)
		(layer "F.Cu")
		(net "DRV_ACT_5")
	)
	(segment
		(start 44.23029 -452.693532)
		(end 44.958 -452.693532)
		(width 0.17145)
		(layer "F.Cu")
		(net "DRV_ACT_5")
	)
	(segment
		(start 48.5775 -452.501)
		(end 47.244 -452.501)
		(width 0.17145)
		(layer "F.Cu")
		(net "DRV_ACT_5")
	)
	(via
		(at 46.072298 -452.374)
		(size 0.7112)
		(drill 0.3556)
		(layers "F.Cu" "B.Cu")
		(net "DRV_ACT_5")
	)
	(segment
		(start 232.269538 -40.374062)
		(end 233.1466 -39.497)
		(width 0.17145)
		(layer "F.Cu")
		(net "DRV_ACT_4")
	)
	(segment
		(start 233.1466 -39.497)
		(end 233.6165 -39.497)
		(width 0.17145)
		(layer "F.Cu")
		(net "DRV_ACT_4")
	)
	(segment
		(start 233.6165 -40.64)
		(end 233.6165 -39.497)
		(width 0.17145)
		(layer "F.Cu")
		(net "DRV_ACT_4")
	)
	(segment
		(start 231.072182 -40.374062)
		(end 232.269538 -40.374062)
		(width 0.17145)
		(layer "F.Cu")
		(net "DRV_ACT_4")
	)
	(segment
		(start 230.189532 -40.374062)
		(end 231.072182 -40.374062)
		(width 0.17145)
		(layer "F.Cu")
		(net "DRV_ACT_4")
	)
	(segment
		(start 229.230174 -40.693594)
		(end 229.87 -40.693594)
		(width 0.17145)
		(layer "F.Cu")
		(net "DRV_ACT_4")
	)
	(segment
		(start 229.87 -40.693594)
		(end 230.189532 -40.374062)
		(width 0.17145)
		(layer "F.Cu")
		(net "DRV_ACT_4")
	)
	(via
		(at 231.072182 -40.374062)
		(size 0.7112)
		(drill 0.3556)
		(layers "F.Cu" "B.Cu")
		(net "DRV_ACT_4")
	)
	(segment
		(start 233.0704 -142.494)
		(end 233.6165 -142.494)
		(width 0.17145)
		(layer "F.Cu")
		(net "DRV_ACT_3")
	)
	(segment
		(start 229.997 -143.693642)
		(end 230.316532 -143.37411)
		(width 0.17145)
		(layer "F.Cu")
		(net "DRV_ACT_3")
	)
	(segment
		(start 231.072182 -143.37411)
		(end 232.19029 -143.37411)
		(width 0.17145)
		(layer "F.Cu")
		(net "DRV_ACT_3")
	)
	(segment
		(start 230.316532 -143.37411)
		(end 231.072182 -143.37411)
		(width 0.17145)
		(layer "F.Cu")
		(net "DRV_ACT_3")
	)
	(segment
		(start 229.230174 -143.693642)
		(end 229.997 -143.693642)
		(width 0.17145)
		(layer "F.Cu")
		(net "DRV_ACT_3")
	)
	(segment
		(start 232.19029 -143.37411)
		(end 233.0704 -142.494)
		(width 0.17145)
		(layer "F.Cu")
		(net "DRV_ACT_3")
	)
	(segment
		(start 233.6165 -142.494)
		(end 233.6165 -143.637)
		(width 0.17145)
		(layer "F.Cu")
		(net "DRV_ACT_3")
	)
	(via
		(at 231.072182 -143.37411)
		(size 0.7112)
		(drill 0.3556)
		(layers "F.Cu" "B.Cu")
		(net "DRV_ACT_3")
	)
	(segment
		(start 233.6165 -246.634)
		(end 233.6165 -245.491)
		(width 0.17145)
		(layer "F.Cu")
		(net "DRV_ACT_2")
	)
	(segment
		(start 229.997 -246.69369)
		(end 230.316532 -246.374158)
		(width 0.17145)
		(layer "F.Cu")
		(net "DRV_ACT_2")
	)
	(segment
		(start 229.230174 -246.69369)
		(end 229.997 -246.69369)
		(width 0.17145)
		(layer "F.Cu")
		(net "DRV_ACT_2")
	)
	(segment
		(start 231.072182 -246.374158)
		(end 231.907842 -246.374158)
		(width 0.17145)
		(layer "F.Cu")
		(net "DRV_ACT_2")
	)
	(segment
		(start 231.907842 -246.374158)
		(end 232.791 -245.491)
		(width 0.17145)
		(layer "F.Cu")
		(net "DRV_ACT_2")
	)
	(segment
		(start 230.316532 -246.374158)
		(end 231.072182 -246.374158)
		(width 0.17145)
		(layer "F.Cu")
		(net "DRV_ACT_2")
	)
	(segment
		(start 232.791 -245.491)
		(end 233.6165 -245.491)
		(width 0.17145)
		(layer "F.Cu")
		(net "DRV_ACT_2")
	)
	(via
		(at 231.072182 -246.374158)
		(size 0.7112)
		(drill 0.3556)
		(layers "F.Cu" "B.Cu")
		(net "DRV_ACT_2")
	)
	(segment
		(start 23.5585 -52.197)
		(end 23.5585 -51.054)
		(width 0.17145)
		(layer "F.Cu")
		(net "DRV_ACT_14")
	)
	(segment
		(start 19.23034 -52.493672)
		(end 21.039328 -52.493672)
		(width 0.17145)
		(layer "F.Cu")
		(net "DRV_ACT_14")
	)
	(segment
		(start 21.039328 -52.493672)
		(end 22.225 -51.308)
		(width 0.17145)
		(layer "F.Cu")
		(net "DRV_ACT_14")
	)
	(segment
		(start 23.5585 -51.054)
		(end 22.479 -51.054)
		(width 0.17145)
		(layer "F.Cu")
		(net "DRV_ACT_14")
	)
	(segment
		(start 22.479 -51.054)
		(end 22.225 -51.308)
		(width 0.17145)
		(layer "F.Cu")
		(net "DRV_ACT_14")
	)
	(via
		(at 22.225 -51.308)
		(size 0.7112)
		(drill 0.3556)
		(layers "F.Cu" "B.Cu")
		(net "DRV_ACT_14")
	)
	(segment
		(start 23.495 -154.1145)
		(end 23.495 -154.6225)
		(width 0.17145)
		(layer "F.Cu")
		(net "DRV_ACT_13")
	)
	(segment
		(start 19.23034 -155.49372)
		(end 20.93468 -155.49372)
		(width 0.17145)
		(layer "F.Cu")
		(net "DRV_ACT_13")
	)
	(segment
		(start 20.93468 -155.49372)
		(end 21.971 -154.4574)
		(width 0.17145)
		(layer "F.Cu")
		(net "DRV_ACT_13")
	)
	(segment
		(start 23.495 -154.6225)
		(end 23.5585 -154.686)
		(width 0.17145)
		(layer "F.Cu")
		(net "DRV_ACT_13")
	)
	(segment
		(start 23.495 -154.1145)
		(end 22.3139 -154.1145)
		(width 0.17145)
		(layer "F.Cu")
		(net "DRV_ACT_13")
	)
	(segment
		(start 22.3139 -154.1145)
		(end 21.971 -154.4574)
		(width 0.17145)
		(layer "F.Cu")
		(net "DRV_ACT_13")
	)
	(segment
		(start 23.5585 -154.686)
		(end 23.5585 -155.194)
		(width 0.17145)
		(layer "F.Cu")
		(net "DRV_ACT_13")
	)
	(via
		(at 21.971 -154.4574)
		(size 0.7112)
		(drill 0.3556)
		(layers "F.Cu" "B.Cu")
		(net "DRV_ACT_13")
	)
	(segment
		(start 23.5585 -258.191)
		(end 23.5585 -257.6449)
		(width 0.17145)
		(layer "F.Cu")
		(net "DRV_ACT_12")
	)
	(segment
		(start 22.3393 -257.1115)
		(end 21.844 -257.6068)
		(width 0.17145)
		(layer "F.Cu")
		(net "DRV_ACT_12")
	)
	(segment
		(start 23.622 -257.1115)
		(end 22.3393 -257.1115)
		(width 0.17145)
		(layer "F.Cu")
		(net "DRV_ACT_12")
	)
	(segment
		(start 19.23034 -258.493514)
		(end 20.957286 -258.493514)
		(width 0.17145)
		(layer "F.Cu")
		(net "DRV_ACT_12")
	)
	(segment
		(start 23.5585 -257.6449)
		(end 23.622 -257.5814)
		(width 0.17145)
		(layer "F.Cu")
		(net "DRV_ACT_12")
	)
	(segment
		(start 20.957286 -258.493514)
		(end 21.844 -257.6068)
		(width 0.17145)
		(layer "F.Cu")
		(net "DRV_ACT_12")
	)
	(segment
		(start 23.622 -257.5814)
		(end 23.622 -257.1115)
		(width 0.17145)
		(layer "F.Cu")
		(net "DRV_ACT_12")
	)
	(via
		(at 21.844 -257.6068)
		(size 0.7112)
		(drill 0.3556)
		(layers "F.Cu" "B.Cu")
		(net "DRV_ACT_12")
	)
	(segment
		(start 19.23034 -361.493562)
		(end 21.538438 -361.493562)
		(width 0.17145)
		(layer "F.Cu")
		(net "DRV_ACT_11")
	)
	(segment
		(start 23.5585 -360.045)
		(end 22.987 -360.045)
		(width 0.17145)
		(layer "F.Cu")
		(net "DRV_ACT_11")
	)
	(segment
		(start 23.5585 -361.188)
		(end 23.5585 -360.045)
		(width 0.17145)
		(layer "F.Cu")
		(net "DRV_ACT_11")
	)
	(segment
		(start 22.987 -360.045)
		(end 22.225 -360.807)
		(width 0.17145)
		(layer "F.Cu")
		(net "DRV_ACT_11")
	)
	(segment
		(start 21.538438 -361.493562)
		(end 22.225 -360.807)
		(width 0.17145)
		(layer "F.Cu")
		(net "DRV_ACT_11")
	)
	(via
		(at 22.225 -360.807)
		(size 0.7112)
		(drill 0.3556)
		(layers "F.Cu" "B.Cu")
		(net "DRV_ACT_11")
	)
	(segment
		(start 22.3774 -464.115658)
		(end 21.999448 -464.49361)
		(width 0.17145)
		(layer "F.Cu")
		(net "DRV_ACT_10")
	)
	(segment
		(start 21.999448 -464.49361)
		(end 19.23034 -464.49361)
		(width 0.17145)
		(layer "F.Cu")
		(net "DRV_ACT_10")
	)
	(segment
		(start 23.2664 -462.661)
		(end 22.3774 -463.55)
		(width 0.17145)
		(layer "F.Cu")
		(net "DRV_ACT_10")
	)
	(segment
		(start 22.3774 -463.55)
		(end 22.3774 -464.115658)
		(width 0.17145)
		(layer "F.Cu")
		(net "DRV_ACT_10")
	)
	(segment
		(start 23.809198 -463.78241)
		(end 23.809198 -462.664302)
		(width 0.17145)
		(layer "F.Cu")
		(net "DRV_ACT_10")
	)
	(segment
		(start 23.809198 -462.664302)
		(end 23.8125 -462.661)
		(width 0.17145)
		(layer "F.Cu")
		(net "DRV_ACT_10")
	)
	(segment
		(start 23.8125 -462.661)
		(end 23.2664 -462.661)
		(width 0.17145)
		(layer "F.Cu")
		(net "DRV_ACT_10")
	)
	(via
		(at 22.3774 -463.55)
		(size 0.7112)
		(drill 0.3556)
		(layers "F.Cu" "B.Cu")
		(net "DRV_ACT_10")
	)
	(segment
		(start 233.6165 -348.488)
		(end 233.045 -348.488)
		(width 0.17145)
		(layer "F.Cu")
		(net "DRV_ACT_1")
	)
	(segment
		(start 233.6165 -349.631)
		(end 233.6165 -348.488)
		(width 0.17145)
		(layer "F.Cu")
		(net "DRV_ACT_1")
	)
	(segment
		(start 229.230174 -349.693484)
		(end 229.997 -349.693484)
		(width 0.17145)
		(layer "F.Cu")
		(net "DRV_ACT_1")
	)
	(segment
		(start 233.045 -348.488)
		(end 232.159048 -349.373952)
		(width 0.17145)
		(layer "F.Cu")
		(net "DRV_ACT_1")
	)
	(segment
		(start 232.159048 -349.373952)
		(end 231.072182 -349.373952)
		(width 0.17145)
		(layer "F.Cu")
		(net "DRV_ACT_1")
	)
	(segment
		(start 229.997 -349.693484)
		(end 230.316532 -349.373952)
		(width 0.17145)
		(layer "F.Cu")
		(net "DRV_ACT_1")
	)
	(segment
		(start 230.316532 -349.373952)
		(end 231.072182 -349.373952)
		(width 0.17145)
		(layer "F.Cu")
		(net "DRV_ACT_1")
	)
	(via
		(at 231.072182 -349.373952)
		(size 0.7112)
		(drill 0.3556)
		(layers "F.Cu" "B.Cu")
		(net "DRV_ACT_1")
	)
	(segment
		(start 13.208 -477.7105)
		(end 14.224 -477.7105)
		(width 0.17145)
		(layer "F.Cu")
		(net "DPB_HW_REVISION")
	)
	(segment
		(start 13.208 -477.7105)
		(end 13.208 -476.885)
		(width 0.17145)
		(layer "F.Cu")
		(net "DPB_HW_REVISION")
	)
	(via
		(at 13.5128 -473.9132)
		(size 0.7112)
		(drill 0.3556)
		(layers "F.Cu" "B.Cu")
		(net "DPB_HW_REVISION")
	)
	(via
		(at 13.208 -476.885)
		(size 0.508)
		(drill 0.254)
		(layers "F.Cu" "B.Cu")
		(net "DPB_HW_REVISION")
	)
	(segment
		(start 13.5128 -473.648024)
		(end 13.208 -473.343224)
		(width 0.17145)
		(layer "B.Cu")
		(net "DPB_HW_REVISION")
	)
	(segment
		(start 13.166852 -458.254354)
		(end 11.363198 -456.4507)
		(width 0.17145)
		(layer "B.Cu")
		(net "DPB_HW_REVISION")
	)
	(segment
		(start 13.166852 -458.711554)
		(end 13.166852 -458.254354)
		(width 0.17145)
		(layer "B.Cu")
		(net "DPB_HW_REVISION")
	)
	(segment
		(start 5.850636 -455.422)
		(end 3.963162 -455.422)
		(width 0.17145)
		(layer "B.Cu")
		(net "DPB_HW_REVISION")
	)
	(segment
		(start 13.166598 -473.301568)
		(end 13.166598 -458.711808)
		(width 0.17145)
		(layer "B.Cu")
		(net "DPB_HW_REVISION")
	)
	(segment
		(start 13.208 -473.343224)
		(end 13.208 -473.34297)
		(width 0.17145)
		(layer "B.Cu")
		(net "DPB_HW_REVISION")
	)
	(segment
		(start 13.5128 -473.9132)
		(end 13.5128 -476.5802)
		(width 0.17145)
		(layer "B.Cu")
		(net "DPB_HW_REVISION")
	)
	(segment
		(start 11.363198 -456.4507)
		(end 6.879336 -456.4507)
		(width 0.17145)
		(layer "B.Cu")
		(net "DPB_HW_REVISION")
	)
	(segment
		(start 13.5128 -473.9132)
		(end 13.5128 -473.648024)
		(width 0.17145)
		(layer "B.Cu")
		(net "DPB_HW_REVISION")
	)
	(segment
		(start 13.208 -473.34297)
		(end 13.166598 -473.301568)
		(width 0.17145)
		(layer "B.Cu")
		(net "DPB_HW_REVISION")
	)
	(segment
		(start 6.879336 -456.4507)
		(end 5.850636 -455.422)
		(width 0.17145)
		(layer "B.Cu")
		(net "DPB_HW_REVISION")
	)
	(segment
		(start 3.683 -455.141838)
		(end 1.868932 -455.141838)
		(width 0.17145)
		(layer "B.Cu")
		(net "DPB_HW_REVISION")
	)
	(segment
		(start 13.166598 -458.711808)
		(end 13.166852 -458.711554)
		(width 0.17145)
		(layer "B.Cu")
		(net "DPB_HW_REVISION")
	)
	(segment
		(start 3.963162 -455.422)
		(end 3.683 -455.141838)
		(width 0.17145)
		(layer "B.Cu")
		(net "DPB_HW_REVISION")
	)
	(segment
		(start 13.5128 -476.5802)
		(end 13.208 -476.885)
		(width 0.17145)
		(layer "B.Cu")
		(net "DPB_HW_REVISION")
	)
	(segment
		(start 81.661 -301.6758)
		(end 81.661 -302.96231)
		(width 0.17145)
		(layer "F.Cu")
		(net "BMC_I2C_SDA_BUF_9")
	)
	(segment
		(start 82.20075 -301.13605)
		(end 81.661 -301.6758)
		(width 0.17145)
		(layer "F.Cu")
		(net "BMC_I2C_SDA_BUF_9")
	)
	(segment
		(start 81.661 -302.96231)
		(end 81.83245 -303.13376)
		(width 0.17145)
		(layer "F.Cu")
		(net "BMC_I2C_SDA_BUF_9")
	)
	(segment
		(start 74.4474 -353.1235)
		(end 73.6854 -353.8855)
		(width 0.17145)
		(layer "F.Cu")
		(net "BMC_I2C_SDA_BUF_9")
	)
	(segment
		(start 73.90638 -350.52)
		(end 73.66 -350.76638)
		(width 0.17145)
		(layer "F.Cu")
		(net "BMC_I2C_SDA_BUF_9")
	)
	(segment
		(start 14.318234 -475.333314)
		(end 14.31798 -475.333314)
		(width 0.17145)
		(layer "F.Cu")
		(net "BMC_I2C_SDA_BUF_9")
	)
	(segment
		(start 63.119 -436.069232)
		(end 62.913768 -435.864)
		(width 0.17145)
		(layer "F.Cu")
		(net "BMC_I2C_SDA_BUF_9")
	)
	(segment
		(start 82.08645 -429.87976)
		(end 82.716624 -429.87976)
		(width 0.17145)
		(layer "F.Cu")
		(net "BMC_I2C_SDA_BUF_9")
	)
	(segment
		(start 4.959096 -454.2282)
		(end 3.770884 -454.2282)
		(width 0.17145)
		(layer "F.Cu")
		(net "BMC_I2C_SDA_BUF_9")
	)
	(segment
		(start 81.915 -428.244)
		(end 81.915 -429.70831)
		(width 0.17145)
		(layer "F.Cu")
		(net "BMC_I2C_SDA_BUF_9")
	)
	(segment
		(start 82.3722 -427.7868)
		(end 81.915 -428.244)
		(width 0.17145)
		(layer "F.Cu")
		(net "BMC_I2C_SDA_BUF_9")
	)
	(segment
		(start 51.420014 -435.864)
		(end 35.859466 -451.424548)
		(width 0.17145)
		(layer "F.Cu")
		(net "BMC_I2C_SDA_BUF_9")
	)
	(segment
		(start 83.58124 -427.99)
		(end 83.37804 -427.7868)
		(width 0.17145)
		(layer "F.Cu")
		(net "BMC_I2C_SDA_BUF_9")
	)
	(segment
		(start 83.58124 -301.371)
		(end 83.34629 -301.13605)
		(width 0.17145)
		(layer "F.Cu")
		(net "BMC_I2C_SDA_BUF_9")
	)
	(segment
		(start 62.913768 -435.864)
		(end 51.420014 -435.864)
		(width 0.17145)
		(layer "F.Cu")
		(net "BMC_I2C_SDA_BUF_9")
	)
	(segment
		(start 16.454628 -477.469708)
		(end 14.318234 -475.333314)
		(width 0.17145)
		(layer "F.Cu")
		(net "BMC_I2C_SDA_BUF_9")
	)
	(segment
		(start 29.67736 -460.892144)
		(end 29.67736 -472.403678)
		(width 0.17145)
		(layer "F.Cu")
		(net "BMC_I2C_SDA_BUF_9")
	)
	(segment
		(start 35.859466 -454.710038)
		(end 29.67736 -460.892144)
		(width 0.17145)
		(layer "F.Cu")
		(net "BMC_I2C_SDA_BUF_9")
	)
	(segment
		(start 13.3477 -458.395832)
		(end 11.281156 -456.329288)
		(width 0.17145)
		(layer "F.Cu")
		(net "BMC_I2C_SDA_BUF_9")
	)
	(segment
		(start 7.060184 -456.329288)
		(end 4.959096 -454.2282)
		(width 0.17145)
		(layer "F.Cu")
		(net "BMC_I2C_SDA_BUF_9")
	)
	(segment
		(start 11.281156 -456.329288)
		(end 7.060184 -456.329288)
		(width 0.17145)
		(layer "F.Cu")
		(net "BMC_I2C_SDA_BUF_9")
	)
	(segment
		(start 84.0105 -427.99)
		(end 83.58124 -427.99)
		(width 0.17145)
		(layer "F.Cu")
		(net "BMC_I2C_SDA_BUF_9")
	)
	(segment
		(start 83.34629 -301.13605)
		(end 82.20075 -301.13605)
		(width 0.17145)
		(layer "F.Cu")
		(net "BMC_I2C_SDA_BUF_9")
	)
	(segment
		(start 3.770884 -454.2282)
		(end 3.657092 -454.341992)
		(width 0.17145)
		(layer "F.Cu")
		(net "BMC_I2C_SDA_BUF_9")
	)
	(segment
		(start 35.859466 -451.424548)
		(end 35.859466 -454.710038)
		(width 0.17145)
		(layer "F.Cu")
		(net "BMC_I2C_SDA_BUF_9")
	)
	(segment
		(start 81.915 -429.70831)
		(end 82.08645 -429.87976)
		(width 0.17145)
		(layer "F.Cu")
		(net "BMC_I2C_SDA_BUF_9")
	)
	(segment
		(start 73.6854 -354.2919)
		(end 73.914 -354.5205)
		(width 0.17145)
		(layer "F.Cu")
		(net "BMC_I2C_SDA_BUF_9")
	)
	(segment
		(start 14.31798 -475.333314)
		(end 13.3477 -474.363034)
		(width 0.17145)
		(layer "F.Cu")
		(net "BMC_I2C_SDA_BUF_9")
	)
	(segment
		(start 84.0105 -301.371)
		(end 83.58124 -301.371)
		(width 0.17145)
		(layer "F.Cu")
		(net "BMC_I2C_SDA_BUF_9")
	)
	(segment
		(start 24.61133 -477.469708)
		(end 16.454628 -477.469708)
		(width 0.17145)
		(layer "F.Cu")
		(net "BMC_I2C_SDA_BUF_9")
	)
	(segment
		(start 29.67736 -472.403678)
		(end 24.61133 -477.469708)
		(width 0.17145)
		(layer "F.Cu")
		(net "BMC_I2C_SDA_BUF_9")
	)
	(segment
		(start 73.66 -350.76638)
		(end 73.66 -352.3361)
		(width 0.17145)
		(layer "F.Cu")
		(net "BMC_I2C_SDA_BUF_9")
	)
	(segment
		(start 81.83245 -303.13376)
		(end 82.462624 -303.13376)
		(width 0.17145)
		(layer "F.Cu")
		(net "BMC_I2C_SDA_BUF_9")
	)
	(segment
		(start 73.6854 -353.8855)
		(end 73.6854 -354.2919)
		(width 0.17145)
		(layer "F.Cu")
		(net "BMC_I2C_SDA_BUF_9")
	)
	(segment
		(start 3.657092 -454.341992)
		(end 2.249932 -454.341992)
		(width 0.17145)
		(layer "F.Cu")
		(net "BMC_I2C_SDA_BUF_9")
	)
	(segment
		(start 73.66 -352.3361)
		(end 74.4474 -353.1235)
		(width 0.17145)
		(layer "F.Cu")
		(net "BMC_I2C_SDA_BUF_9")
	)
	(segment
		(start 83.37804 -427.7868)
		(end 82.3722 -427.7868)
		(width 0.17145)
		(layer "F.Cu")
		(net "BMC_I2C_SDA_BUF_9")
	)
	(segment
		(start 13.3477 -474.363034)
		(end 13.3477 -458.395832)
		(width 0.17145)
		(layer "F.Cu")
		(net "BMC_I2C_SDA_BUF_9")
	)
	(via
		(at 63.119 -436.069232)
		(size 0.508)
		(drill 0.254)
		(layers "F.Cu" "B.Cu")
		(net "BMC_I2C_SDA_BUF_9")
	)
	(via
		(at 73.90638 -350.52)
		(size 0.508)
		(drill 0.254)
		(layers "F.Cu" "B.Cu")
		(net "BMC_I2C_SDA_BUF_9")
	)
	(via
		(at 82.462624 -303.13376)
		(size 0.5588)
		(drill 0.3048)
		(layers "F.Cu" "B.Cu")
		(net "BMC_I2C_SDA_BUF_9")
	)
	(via
		(at 82.716624 -429.87976)
		(size 0.508)
		(drill 0.254)
		(layers "F.Cu" "B.Cu")
		(net "BMC_I2C_SDA_BUF_9")
	)
	(segment
		(start 84.4296 -426.2628)
		(end 82.03565 -428.65675)
		(width 0.17145)
		(layer "B.Cu")
		(net "BMC_I2C_SDA_BUF_9")
	)
	(segment
		(start 82.03565 -430.560734)
		(end 82.03565 -431.39868)
		(width 0.17145)
		(layer "B.Cu")
		(net "BMC_I2C_SDA_BUF_9")
	)
	(segment
		(start 82.03565 -429.198786)
		(end 82.716624 -429.87976)
		(width 0.17145)
		(layer "B.Cu")
		(net "BMC_I2C_SDA_BUF_9")
	)
	(segment
		(start 76.684632 -354.460302)
		(end 81.01965 -358.79532)
		(width 0.17145)
		(layer "B.Cu")
		(net "BMC_I2C_SDA_BUF_9")
	)
	(segment
		(start 82.716624 -429.87976)
		(end 82.03565 -430.560734)
		(width 0.17145)
		(layer "B.Cu")
		(net "BMC_I2C_SDA_BUF_9")
	)
	(segment
		(start 67.211702 -433.701698)
		(end 65.05575 -435.85765)
		(width 0.17145)
		(layer "B.Cu")
		(net "BMC_I2C_SDA_BUF_9")
	)
	(segment
		(start 73.70445 -307.822854)
		(end 73.70445 -350.31807)
		(width 0.17145)
		(layer "B.Cu")
		(net "BMC_I2C_SDA_BUF_9")
	)
	(segment
		(start 73.70445 -353.38512)
		(end 74.779632 -354.460302)
		(width 0.17145)
		(layer "B.Cu")
		(net "BMC_I2C_SDA_BUF_9")
	)
	(segment
		(start 84.4296 -384.68427)
		(end 84.4296 -426.2628)
		(width 0.17145)
		(layer "B.Cu")
		(net "BMC_I2C_SDA_BUF_9")
	)
	(segment
		(start 65.05575 -435.85765)
		(end 63.330582 -435.85765)
		(width 0.17145)
		(layer "B.Cu")
		(net "BMC_I2C_SDA_BUF_9")
	)
	(segment
		(start 73.90638 -350.52)
		(end 73.70445 -350.72193)
		(width 0.17145)
		(layer "B.Cu")
		(net "BMC_I2C_SDA_BUF_9")
	)
	(segment
		(start 73.70445 -350.31807)
		(end 73.90638 -350.52)
		(width 0.17145)
		(layer "B.Cu")
		(net "BMC_I2C_SDA_BUF_9")
	)
	(segment
		(start 74.779632 -354.460302)
		(end 76.684632 -354.460302)
		(width 0.17145)
		(layer "B.Cu")
		(net "BMC_I2C_SDA_BUF_9")
	)
	(segment
		(start 81.01965 -358.79532)
		(end 81.01965 -381.27432)
		(width 0.17145)
		(layer "B.Cu")
		(net "BMC_I2C_SDA_BUF_9")
	)
	(segment
		(start 80.340454 -305.86045)
		(end 75.666854 -305.86045)
		(width 0.17145)
		(layer "B.Cu")
		(net "BMC_I2C_SDA_BUF_9")
	)
	(segment
		(start 81.01965 -381.27432)
		(end 84.4296 -384.68427)
		(width 0.17145)
		(layer "B.Cu")
		(net "BMC_I2C_SDA_BUF_9")
	)
	(segment
		(start 81.740248 -304.460656)
		(end 80.340454 -305.86045)
		(width 0.17145)
		(layer "B.Cu")
		(net "BMC_I2C_SDA_BUF_9")
	)
	(segment
		(start 63.330582 -435.85765)
		(end 63.119 -436.069232)
		(width 0.17145)
		(layer "B.Cu")
		(net "BMC_I2C_SDA_BUF_9")
	)
	(segment
		(start 81.93024 -303.13376)
		(end 81.740248 -303.323752)
		(width 0.17145)
		(layer "B.Cu")
		(net "BMC_I2C_SDA_BUF_9")
	)
	(segment
		(start 82.462624 -303.13376)
		(end 81.93024 -303.13376)
		(width 0.17145)
		(layer "B.Cu")
		(net "BMC_I2C_SDA_BUF_9")
	)
	(segment
		(start 73.70445 -350.72193)
		(end 73.70445 -353.38512)
		(width 0.17145)
		(layer "B.Cu")
		(net "BMC_I2C_SDA_BUF_9")
	)
	(segment
		(start 81.740248 -303.323752)
		(end 81.740248 -304.460656)
		(width 0.17145)
		(layer "B.Cu")
		(net "BMC_I2C_SDA_BUF_9")
	)
	(segment
		(start 82.03565 -428.65675)
		(end 82.03565 -429.198786)
		(width 0.17145)
		(layer "B.Cu")
		(net "BMC_I2C_SDA_BUF_9")
	)
	(segment
		(start 79.732632 -433.701698)
		(end 67.211702 -433.701698)
		(width 0.17145)
		(layer "B.Cu")
		(net "BMC_I2C_SDA_BUF_9")
	)
	(segment
		(start 82.03565 -431.39868)
		(end 79.732632 -433.701698)
		(width 0.17145)
		(layer "B.Cu")
		(net "BMC_I2C_SDA_BUF_9")
	)
	(segment
		(start 75.666854 -305.86045)
		(end 73.70445 -307.822854)
		(width 0.17145)
		(layer "B.Cu")
		(net "BMC_I2C_SDA_BUF_9")
	)
	(segment
		(start 82.042 -97.9678)
		(end 82.042 -99.25431)
		(width 0.17145)
		(layer "F.Cu")
		(net "BMC_I2C_SDA_BUF_8")
	)
	(segment
		(start 86.78672 -146.19605)
		(end 87.887302 -147.296632)
		(width 0.17145)
		(layer "F.Cu")
		(net "BMC_I2C_SDA_BUF_8")
	)
	(segment
		(start 71.81215 -206.324454)
		(end 73.180194 -207.692498)
		(width 0.17145)
		(layer "F.Cu")
		(net "BMC_I2C_SDA_BUF_8")
	)
	(segment
		(start 82.4611 -146.2024)
		(end 82.8675 -146.2024)
		(width 0.17145)
		(layer "F.Cu")
		(net "BMC_I2C_SDA_BUF_8")
	)
	(segment
		(start 82.61096 -206.74965)
		(end 82.846418 -206.985108)
		(width 0.17145)
		(layer "F.Cu")
		(net "BMC_I2C_SDA_BUF_8")
	)
	(segment
		(start 86.233 -146.42338)
		(end 86.46033 -146.19605)
		(width 0.17145)
		(layer "F.Cu")
		(net "BMC_I2C_SDA_BUF_8")
	)
	(segment
		(start 84.0105 -207.01)
		(end 83.75015 -206.74965)
		(width 0.17145)
		(layer "F.Cu")
		(net "BMC_I2C_SDA_BUF_8")
	)
	(segment
		(start 83.34629 -97.55505)
		(end 82.45475 -97.55505)
		(width 0.17145)
		(layer "F.Cu")
		(net "BMC_I2C_SDA_BUF_8")
	)
	(segment
		(start 86.03742 -146.2278)
		(end 84.3661 -146.2278)
		(width 0.17145)
		(layer "F.Cu")
		(net "BMC_I2C_SDA_BUF_8")
	)
	(segment
		(start 87.887302 -183.411368)
		(end 71.81215 -199.48652)
		(width 0.17145)
		(layer "F.Cu")
		(net "BMC_I2C_SDA_BUF_8")
	)
	(segment
		(start 84.0105 -97.79)
		(end 83.58124 -97.79)
		(width 0.17145)
		(layer "F.Cu")
		(net "BMC_I2C_SDA_BUF_8")
	)
	(segment
		(start 82.042 -99.25431)
		(end 82.21345 -99.42576)
		(width 0.17145)
		(layer "F.Cu")
		(net "BMC_I2C_SDA_BUF_8")
	)
	(segment
		(start 83.081876 -206.74965)
		(end 82.846418 -206.985108)
		(width 0.17145)
		(layer "F.Cu")
		(net "BMC_I2C_SDA_BUF_8")
	)
	(segment
		(start 82.8675 -146.2024)
		(end 83.6295 -146.9644)
		(width 0.17145)
		(layer "F.Cu")
		(net "BMC_I2C_SDA_BUF_8")
	)
	(segment
		(start 84.3661 -146.2278)
		(end 83.6295 -146.9644)
		(width 0.17145)
		(layer "F.Cu")
		(net "BMC_I2C_SDA_BUF_8")
	)
	(segment
		(start 81.156302 -207.692498)
		(end 82.09915 -206.74965)
		(width 0.17145)
		(layer "F.Cu")
		(net "BMC_I2C_SDA_BUF_8")
	)
	(segment
		(start 86.46033 -146.19605)
		(end 86.78672 -146.19605)
		(width 0.17145)
		(layer "F.Cu")
		(net "BMC_I2C_SDA_BUF_8")
	)
	(segment
		(start 83.75015 -206.74965)
		(end 83.081876 -206.74965)
		(width 0.17145)
		(layer "F.Cu")
		(net "BMC_I2C_SDA_BUF_8")
	)
	(segment
		(start 82.45475 -97.55505)
		(end 82.042 -97.9678)
		(width 0.17145)
		(layer "F.Cu")
		(net "BMC_I2C_SDA_BUF_8")
	)
	(segment
		(start 82.2325 -146.431)
		(end 82.4611 -146.2024)
		(width 0.17145)
		(layer "F.Cu")
		(net "BMC_I2C_SDA_BUF_8")
	)
	(segment
		(start 71.81215 -199.48652)
		(end 71.81215 -206.324454)
		(width 0.17145)
		(layer "F.Cu")
		(net "BMC_I2C_SDA_BUF_8")
	)
	(segment
		(start 82.09915 -206.74965)
		(end 82.61096 -206.74965)
		(width 0.17145)
		(layer "F.Cu")
		(net "BMC_I2C_SDA_BUF_8")
	)
	(segment
		(start 86.233 -146.42338)
		(end 86.03742 -146.2278)
		(width 0.17145)
		(layer "F.Cu")
		(net "BMC_I2C_SDA_BUF_8")
	)
	(segment
		(start 73.180194 -207.692498)
		(end 81.156302 -207.692498)
		(width 0.17145)
		(layer "F.Cu")
		(net "BMC_I2C_SDA_BUF_8")
	)
	(segment
		(start 83.58124 -97.79)
		(end 83.34629 -97.55505)
		(width 0.17145)
		(layer "F.Cu")
		(net "BMC_I2C_SDA_BUF_8")
	)
	(segment
		(start 82.21345 -99.42576)
		(end 82.843624 -99.42576)
		(width 0.17145)
		(layer "F.Cu")
		(net "BMC_I2C_SDA_BUF_8")
	)
	(segment
		(start 87.887302 -147.296632)
		(end 87.887302 -183.411368)
		(width 0.17145)
		(layer "F.Cu")
		(net "BMC_I2C_SDA_BUF_8")
	)
	(via
		(at 86.233 -146.42338)
		(size 0.508)
		(drill 0.254)
		(layers "F.Cu" "B.Cu")
		(net "BMC_I2C_SDA_BUF_8")
	)
	(via
		(at 82.846418 -206.985108)
		(size 0.508)
		(drill 0.254)
		(layers "F.Cu" "B.Cu")
		(net "BMC_I2C_SDA_BUF_8")
	)
	(via
		(at 82.843624 -99.42576)
		(size 0.508)
		(drill 0.254)
		(layers "F.Cu" "B.Cu")
		(net "BMC_I2C_SDA_BUF_8")
	)
	(via
		(at 80.9498 -119.3292)
		(size 0.7112)
		(drill 0.3556)
		(layers "F.Cu" "B.Cu")
		(net "BMC_I2C_SDA_BUF_8")
	)
	(segment
		(start 111.804704 -200.533)
		(end 119.06885 -207.797146)
		(width 0.17145)
		(layer "B.Cu")
		(net "BMC_I2C_SDA_BUF_8")
	)
	(segment
		(start 15.970504 -457.151232)
		(end 12.463272 -453.644)
		(width 0.17145)
		(layer "B.Cu")
		(net "BMC_I2C_SDA_BUF_8")
	)
	(segment
		(start 43.564302 -470.176098)
		(end 42.0624 -471.678)
		(width 0.17145)
		(layer "B.Cu")
		(net "BMC_I2C_SDA_BUF_8")
	)
	(segment
		(start 82.292698 -99.59721)
		(end 82.464148 -99.42576)
		(width 0.17145)
		(layer "B.Cu")
		(net "BMC_I2C_SDA_BUF_8")
	)
	(segment
		(start 5.3848 -450.793104)
		(end 4.825746 -450.23405)
		(width 0.17145)
		(layer "B.Cu")
		(net "BMC_I2C_SDA_BUF_8")
	)
	(segment
		(start 4.825746 -450.23405)
		(end 3.660394 -450.23405)
		(width 0.17145)
		(layer "B.Cu")
		(net "BMC_I2C_SDA_BUF_8")
	)
	(segment
		(start 3.660394 -450.23405)
		(end 3.552444 -450.342)
		(width 0.17145)
		(layer "B.Cu")
		(net "BMC_I2C_SDA_BUF_8")
	)
	(segment
		(start 7.4676 -453.644)
		(end 5.3848 -451.5612)
		(width 0.17145)
		(layer "B.Cu")
		(net "BMC_I2C_SDA_BUF_8")
	)
	(segment
		(start 82.292698 -100.809298)
		(end 82.292698 -99.59721)
		(width 0.17145)
		(layer "B.Cu")
		(net "BMC_I2C_SDA_BUF_8")
	)
	(segment
		(start 80.66405 -119.3292)
		(end 80.66405 -112.04575)
		(width 0.17145)
		(layer "B.Cu")
		(net "BMC_I2C_SDA_BUF_8")
	)
	(segment
		(start 86.233 -146.42338)
		(end 86.46033 -146.19605)
		(width 0.17145)
		(layer "B.Cu")
		(net "BMC_I2C_SDA_BUF_8")
	)
	(segment
		(start 119.06885 -447.802254)
		(end 116.027454 -450.84365)
		(width 0.17145)
		(layer "B.Cu")
		(net "BMC_I2C_SDA_BUF_8")
	)
	(segment
		(start 80.66405 -124.37872)
		(end 80.66405 -119.3292)
		(width 0.17145)
		(layer "B.Cu")
		(net "BMC_I2C_SDA_BUF_8")
	)
	(segment
		(start 82.464148 -99.42576)
		(end 82.843624 -99.42576)
		(width 0.17145)
		(layer "B.Cu")
		(net "BMC_I2C_SDA_BUF_8")
	)
	(segment
		(start 12.463272 -453.644)
		(end 7.4676 -453.644)
		(width 0.17145)
		(layer "B.Cu")
		(net "BMC_I2C_SDA_BUF_8")
	)
	(segment
		(start 78.94955 -204.26045)
		(end 80.41005 -202.79995)
		(width 0.17145)
		(layer "B.Cu")
		(net "BMC_I2C_SDA_BUF_8")
	)
	(segment
		(start 82.8802 -101.3968)
		(end 82.292698 -100.809298)
		(width 0.17145)
		(layer "B.Cu")
		(net "BMC_I2C_SDA_BUF_8")
	)
	(segment
		(start 91.182698 -144.121632)
		(end 91.182698 -134.897368)
		(width 0.17145)
		(layer "B.Cu")
		(net "BMC_I2C_SDA_BUF_8")
	)
	(segment
		(start 86.46033 -146.19605)
		(end 89.10828 -146.19605)
		(width 0.17145)
		(layer "B.Cu")
		(net "BMC_I2C_SDA_BUF_8")
	)
	(segment
		(start 70.736206 -470.176098)
		(end 43.564302 -470.176098)
		(width 0.17145)
		(layer "B.Cu")
		(net "BMC_I2C_SDA_BUF_8")
	)
	(segment
		(start 82.764884 -206.903574)
		(end 80.311244 -206.903574)
		(width 0.17145)
		(layer "B.Cu")
		(net "BMC_I2C_SDA_BUF_8")
	)
	(segment
		(start 80.66405 -112.04575)
		(end 82.8802 -109.8296)
		(width 0.17145)
		(layer "B.Cu")
		(net "BMC_I2C_SDA_BUF_8")
	)
	(segment
		(start 80.311244 -206.903574)
		(end 78.94955 -205.54188)
		(width 0.17145)
		(layer "B.Cu")
		(net "BMC_I2C_SDA_BUF_8")
	)
	(segment
		(start 90.068654 -450.84365)
		(end 70.736206 -470.176098)
		(width 0.17145)
		(layer "B.Cu")
		(net "BMC_I2C_SDA_BUF_8")
	)
	(segment
		(start 5.3848 -451.5612)
		(end 5.3848 -450.793104)
		(width 0.17145)
		(layer "B.Cu")
		(net "BMC_I2C_SDA_BUF_8")
	)
	(segment
		(start 116.027454 -450.84365)
		(end 90.068654 -450.84365)
		(width 0.17145)
		(layer "B.Cu")
		(net "BMC_I2C_SDA_BUF_8")
	)
	(segment
		(start 91.182698 -134.897368)
		(end 80.66405 -124.37872)
		(width 0.17145)
		(layer "B.Cu")
		(net "BMC_I2C_SDA_BUF_8")
	)
	(segment
		(start 42.0624 -471.678)
		(end 36.29533 -471.678)
		(width 0.17145)
		(layer "B.Cu")
		(net "BMC_I2C_SDA_BUF_8")
	)
	(segment
		(start 78.94955 -205.54188)
		(end 78.94955 -204.26045)
		(width 0.17145)
		(layer "B.Cu")
		(net "BMC_I2C_SDA_BUF_8")
	)
	(segment
		(start 82.8802 -109.8296)
		(end 82.8802 -101.3968)
		(width 0.17145)
		(layer "B.Cu")
		(net "BMC_I2C_SDA_BUF_8")
	)
	(segment
		(start 89.10828 -146.19605)
		(end 91.182698 -144.121632)
		(width 0.17145)
		(layer "B.Cu")
		(net "BMC_I2C_SDA_BUF_8")
	)
	(segment
		(start 3.552444 -450.342)
		(end 1.868932 -450.342)
		(width 0.17145)
		(layer "B.Cu")
		(net "BMC_I2C_SDA_BUF_8")
	)
	(segment
		(start 119.06885 -207.797146)
		(end 119.06885 -447.802254)
		(width 0.17145)
		(layer "B.Cu")
		(net "BMC_I2C_SDA_BUF_8")
	)
	(segment
		(start 19.338798 -475.415102)
		(end 15.970504 -472.046808)
		(width 0.17145)
		(layer "B.Cu")
		(net "BMC_I2C_SDA_BUF_8")
	)
	(segment
		(start 15.970504 -472.046808)
		(end 15.970504 -457.151232)
		(width 0.17145)
		(layer "B.Cu")
		(net "BMC_I2C_SDA_BUF_8")
	)
	(segment
		(start 86.841076 -202.79995)
		(end 89.108026 -200.533)
		(width 0.17145)
		(layer "B.Cu")
		(net "BMC_I2C_SDA_BUF_8")
	)
	(segment
		(start 82.846418 -206.985108)
		(end 82.764884 -206.903574)
		(width 0.17145)
		(layer "B.Cu")
		(net "BMC_I2C_SDA_BUF_8")
	)
	(segment
		(start 80.41005 -202.79995)
		(end 86.841076 -202.79995)
		(width 0.17145)
		(layer "B.Cu")
		(net "BMC_I2C_SDA_BUF_8")
	)
	(segment
		(start 36.29533 -471.678)
		(end 32.558228 -475.415102)
		(width 0.17145)
		(layer "B.Cu")
		(net "BMC_I2C_SDA_BUF_8")
	)
	(segment
		(start 89.108026 -200.533)
		(end 111.804704 -200.533)
		(width 0.17145)
		(layer "B.Cu")
		(net "BMC_I2C_SDA_BUF_8")
	)
	(segment
		(start 32.558228 -475.415102)
		(end 19.338798 -475.415102)
		(width 0.17145)
		(layer "B.Cu")
		(net "BMC_I2C_SDA_BUF_8")
	)
	(segment
		(start 80.66405 -119.3292)
		(end 80.9498 -119.3292)
		(width 0.17145)
		(layer "B.Cu")
		(net "BMC_I2C_SDA_BUF_8")
	)
	(segment
		(start 24.382476 -476.917258)
		(end 16.683482 -476.917258)
		(width 0.17145)
		(layer "F.Cu")
		(net "BMC_I2C_SCL_BUF_9")
	)
	(segment
		(start 80.9371 -303.13376)
		(end 80.557624 -303.13376)
		(width 0.17145)
		(layer "F.Cu")
		(net "BMC_I2C_SCL_BUF_9")
	)
	(segment
		(start 14.546834 -474.780864)
		(end 13.90015 -474.13418)
		(width 0.17145)
		(layer "F.Cu")
		(net "BMC_I2C_SCL_BUF_9")
	)
	(segment
		(start 82.143346 -427.23435)
		(end 83.32089 -427.23435)
		(width 0.17145)
		(layer "F.Cu")
		(net "BMC_I2C_SCL_BUF_9")
	)
	(segment
		(start 81.36255 -428.015146)
		(end 82.143346 -427.23435)
		(width 0.17145)
		(layer "F.Cu")
		(net "BMC_I2C_SCL_BUF_9")
	)
	(segment
		(start 80.811624 -429.87976)
		(end 81.1911 -429.87976)
		(width 0.17145)
		(layer "F.Cu")
		(net "BMC_I2C_SCL_BUF_9")
	)
	(segment
		(start 72.940418 -350.52)
		(end 73.10755 -350.687132)
		(width 0.17145)
		(layer "F.Cu")
		(net "BMC_I2C_SCL_BUF_9")
	)
	(segment
		(start 3.79095 -453.67575)
		(end 3.657092 -453.541892)
		(width 0.17145)
		(layer "F.Cu")
		(net "BMC_I2C_SCL_BUF_9")
	)
	(segment
		(start 84.0105 -300.355)
		(end 83.58124 -300.355)
		(width 0.17145)
		(layer "F.Cu")
		(net "BMC_I2C_SCL_BUF_9")
	)
	(segment
		(start 81.10855 -302.96231)
		(end 80.9371 -303.13376)
		(width 0.17145)
		(layer "F.Cu")
		(net "BMC_I2C_SCL_BUF_9")
	)
	(segment
		(start 29.12491 -460.66329)
		(end 29.12491 -472.174824)
		(width 0.17145)
		(layer "F.Cu")
		(net "BMC_I2C_SCL_BUF_9")
	)
	(segment
		(start 73.1266 -354.2919)
		(end 72.898 -354.5205)
		(width 0.17145)
		(layer "F.Cu")
		(net "BMC_I2C_SCL_BUF_9")
	)
	(segment
		(start 83.58124 -426.974)
		(end 84.0105 -426.974)
		(width 0.17145)
		(layer "F.Cu")
		(net "BMC_I2C_SCL_BUF_9")
	)
	(segment
		(start 7.289038 -455.776838)
		(end 5.18795 -453.67575)
		(width 0.17145)
		(layer "F.Cu")
		(net "BMC_I2C_SCL_BUF_9")
	)
	(segment
		(start 83.32089 -427.23435)
		(end 83.58124 -426.974)
		(width 0.17145)
		(layer "F.Cu")
		(net "BMC_I2C_SCL_BUF_9")
	)
	(segment
		(start 16.683482 -476.917258)
		(end 14.547088 -474.780864)
		(width 0.17145)
		(layer "F.Cu")
		(net "BMC_I2C_SCL_BUF_9")
	)
	(segment
		(start 35.307016 -454.481184)
		(end 29.12491 -460.66329)
		(width 0.17145)
		(layer "F.Cu")
		(net "BMC_I2C_SCL_BUF_9")
	)
	(segment
		(start 63.119 -435.10327)
		(end 62.91072 -435.31155)
		(width 0.17145)
		(layer "F.Cu")
		(net "BMC_I2C_SCL_BUF_9")
	)
	(segment
		(start 35.307016 -451.195694)
		(end 35.307016 -454.481184)
		(width 0.17145)
		(layer "F.Cu")
		(net "BMC_I2C_SCL_BUF_9")
	)
	(segment
		(start 11.51001 -455.776838)
		(end 7.289038 -455.776838)
		(width 0.17145)
		(layer "F.Cu")
		(net "BMC_I2C_SCL_BUF_9")
	)
	(segment
		(start 81.36255 -429.70831)
		(end 81.36255 -428.015146)
		(width 0.17145)
		(layer "F.Cu")
		(net "BMC_I2C_SCL_BUF_9")
	)
	(segment
		(start 81.1911 -429.87976)
		(end 81.36255 -429.70831)
		(width 0.17145)
		(layer "F.Cu")
		(net "BMC_I2C_SCL_BUF_9")
	)
	(segment
		(start 73.10755 -350.687132)
		(end 73.10755 -352.38055)
		(width 0.17145)
		(layer "F.Cu")
		(net "BMC_I2C_SCL_BUF_9")
	)
	(segment
		(start 62.91072 -435.31155)
		(end 51.19116 -435.31155)
		(width 0.17145)
		(layer "F.Cu")
		(net "BMC_I2C_SCL_BUF_9")
	)
	(segment
		(start 83.35264 -300.5836)
		(end 81.971896 -300.5836)
		(width 0.17145)
		(layer "F.Cu")
		(net "BMC_I2C_SCL_BUF_9")
	)
	(segment
		(start 73.1266 -353.8855)
		(end 73.1266 -354.2919)
		(width 0.17145)
		(layer "F.Cu")
		(net "BMC_I2C_SCL_BUF_9")
	)
	(segment
		(start 29.12491 -472.174824)
		(end 24.382476 -476.917258)
		(width 0.17145)
		(layer "F.Cu")
		(net "BMC_I2C_SCL_BUF_9")
	)
	(segment
		(start 14.547088 -474.780864)
		(end 14.546834 -474.780864)
		(width 0.17145)
		(layer "F.Cu")
		(net "BMC_I2C_SCL_BUF_9")
	)
	(segment
		(start 5.18795 -453.67575)
		(end 3.79095 -453.67575)
		(width 0.17145)
		(layer "F.Cu")
		(net "BMC_I2C_SCL_BUF_9")
	)
	(segment
		(start 13.90015 -458.166978)
		(end 11.51001 -455.776838)
		(width 0.17145)
		(layer "F.Cu")
		(net "BMC_I2C_SCL_BUF_9")
	)
	(segment
		(start 3.657092 -453.541892)
		(end 2.249932 -453.541892)
		(width 0.17145)
		(layer "F.Cu")
		(net "BMC_I2C_SCL_BUF_9")
	)
	(segment
		(start 51.19116 -435.31155)
		(end 35.307016 -451.195694)
		(width 0.17145)
		(layer "F.Cu")
		(net "BMC_I2C_SCL_BUF_9")
	)
	(segment
		(start 83.58124 -300.355)
		(end 83.35264 -300.5836)
		(width 0.17145)
		(layer "F.Cu")
		(net "BMC_I2C_SCL_BUF_9")
	)
	(segment
		(start 81.971896 -300.5836)
		(end 81.10855 -301.446946)
		(width 0.17145)
		(layer "F.Cu")
		(net "BMC_I2C_SCL_BUF_9")
	)
	(segment
		(start 72.3646 -353.1235)
		(end 73.1266 -353.8855)
		(width 0.17145)
		(layer "F.Cu")
		(net "BMC_I2C_SCL_BUF_9")
	)
	(segment
		(start 81.10855 -301.446946)
		(end 81.10855 -302.96231)
		(width 0.17145)
		(layer "F.Cu")
		(net "BMC_I2C_SCL_BUF_9")
	)
	(segment
		(start 73.10755 -352.38055)
		(end 72.3646 -353.1235)
		(width 0.17145)
		(layer "F.Cu")
		(net "BMC_I2C_SCL_BUF_9")
	)
	(segment
		(start 13.90015 -474.13418)
		(end 13.90015 -458.166978)
		(width 0.17145)
		(layer "F.Cu")
		(net "BMC_I2C_SCL_BUF_9")
	)
	(via
		(at 80.811624 -429.87976)
		(size 0.508)
		(drill 0.254)
		(layers "F.Cu" "B.Cu")
		(net "BMC_I2C_SCL_BUF_9")
	)
	(via
		(at 80.557624 -303.13376)
		(size 0.5588)
		(drill 0.3048)
		(layers "F.Cu" "B.Cu")
		(net "BMC_I2C_SCL_BUF_9")
	)
	(via
		(at 72.940418 -350.52)
		(size 0.508)
		(drill 0.254)
		(layers "F.Cu" "B.Cu")
		(net "BMC_I2C_SCL_BUF_9")
	)
	(via
		(at 63.119 -435.10327)
		(size 0.508)
		(drill 0.254)
		(layers "F.Cu" "B.Cu")
		(net "BMC_I2C_SCL_BUF_9")
	)
	(segment
		(start 75.438 -305.308)
		(end 73.152 -307.594)
		(width 0.17145)
		(layer "B.Cu")
		(net "BMC_I2C_SCL_BUF_9")
	)
	(segment
		(start 73.152 -350.731582)
		(end 73.152 -353.613974)
		(width 0.17145)
		(layer "B.Cu")
		(net "BMC_I2C_SCL_BUF_9")
	)
	(segment
		(start 80.4672 -381.503174)
		(end 83.87715 -384.913124)
		(width 0.17145)
		(layer "B.Cu")
		(net "BMC_I2C_SCL_BUF_9")
	)
	(segment
		(start 73.152 -350.308418)
		(end 72.940418 -350.52)
		(width 0.17145)
		(layer "B.Cu")
		(net "BMC_I2C_SCL_BUF_9")
	)
	(segment
		(start 81.4832 -430.551336)
		(end 80.811624 -429.87976)
		(width 0.17145)
		(layer "B.Cu")
		(net "BMC_I2C_SCL_BUF_9")
	)
	(segment
		(start 64.826896 -435.3052)
		(end 66.982848 -433.149248)
		(width 0.17145)
		(layer "B.Cu")
		(net "BMC_I2C_SCL_BUF_9")
	)
	(segment
		(start 80.557624 -303.13376)
		(end 80.98536 -303.13376)
		(width 0.17145)
		(layer "B.Cu")
		(net "BMC_I2C_SCL_BUF_9")
	)
	(segment
		(start 83.87715 -426.033946)
		(end 81.4832 -428.427896)
		(width 0.17145)
		(layer "B.Cu")
		(net "BMC_I2C_SCL_BUF_9")
	)
	(segment
		(start 80.1116 -305.308)
		(end 75.438 -305.308)
		(width 0.17145)
		(layer "B.Cu")
		(net "BMC_I2C_SCL_BUF_9")
	)
	(segment
		(start 81.187798 -304.231802)
		(end 80.1116 -305.308)
		(width 0.17145)
		(layer "B.Cu")
		(net "BMC_I2C_SCL_BUF_9")
	)
	(segment
		(start 81.4832 -431.169826)
		(end 81.4832 -430.551336)
		(width 0.17145)
		(layer "B.Cu")
		(net "BMC_I2C_SCL_BUF_9")
	)
	(segment
		(start 81.4832 -429.208184)
		(end 80.811624 -429.87976)
		(width 0.17145)
		(layer "B.Cu")
		(net "BMC_I2C_SCL_BUF_9")
	)
	(segment
		(start 66.982848 -433.149248)
		(end 79.503778 -433.149248)
		(width 0.17145)
		(layer "B.Cu")
		(net "BMC_I2C_SCL_BUF_9")
	)
	(segment
		(start 81.4832 -428.427896)
		(end 81.4832 -429.208184)
		(width 0.17145)
		(layer "B.Cu")
		(net "BMC_I2C_SCL_BUF_9")
	)
	(segment
		(start 83.87715 -384.913124)
		(end 83.87715 -426.033946)
		(width 0.17145)
		(layer "B.Cu")
		(net "BMC_I2C_SCL_BUF_9")
	)
	(segment
		(start 73.152 -353.613974)
		(end 74.550778 -355.012752)
		(width 0.17145)
		(layer "B.Cu")
		(net "BMC_I2C_SCL_BUF_9")
	)
	(segment
		(start 80.4672 -359.024174)
		(end 80.4672 -381.503174)
		(width 0.17145)
		(layer "B.Cu")
		(net "BMC_I2C_SCL_BUF_9")
	)
	(segment
		(start 74.550778 -355.012752)
		(end 76.455778 -355.012752)
		(width 0.17145)
		(layer "B.Cu")
		(net "BMC_I2C_SCL_BUF_9")
	)
	(segment
		(start 76.455778 -355.012752)
		(end 80.4672 -359.024174)
		(width 0.17145)
		(layer "B.Cu")
		(net "BMC_I2C_SCL_BUF_9")
	)
	(segment
		(start 63.32093 -435.3052)
		(end 64.826896 -435.3052)
		(width 0.17145)
		(layer "B.Cu")
		(net "BMC_I2C_SCL_BUF_9")
	)
	(segment
		(start 63.119 -435.10327)
		(end 63.32093 -435.3052)
		(width 0.17145)
		(layer "B.Cu")
		(net "BMC_I2C_SCL_BUF_9")
	)
	(segment
		(start 79.503778 -433.149248)
		(end 81.4832 -431.169826)
		(width 0.17145)
		(layer "B.Cu")
		(net "BMC_I2C_SCL_BUF_9")
	)
	(segment
		(start 81.187798 -303.336198)
		(end 81.187798 -304.231802)
		(width 0.17145)
		(layer "B.Cu")
		(net "BMC_I2C_SCL_BUF_9")
	)
	(segment
		(start 72.940418 -350.52)
		(end 73.152 -350.731582)
		(width 0.17145)
		(layer "B.Cu")
		(net "BMC_I2C_SCL_BUF_9")
	)
	(segment
		(start 73.152 -307.594)
		(end 73.152 -350.308418)
		(width 0.17145)
		(layer "B.Cu")
		(net "BMC_I2C_SCL_BUF_9")
	)
	(segment
		(start 80.98536 -303.13376)
		(end 81.187798 -303.336198)
		(width 0.17145)
		(layer "B.Cu")
		(net "BMC_I2C_SCL_BUF_9")
	)
	(segment
		(start 86.419182 -145.6436)
		(end 87.015574 -145.6436)
		(width 0.17145)
		(layer "F.Cu")
		(net "BMC_I2C_SCL_BUF_8")
	)
	(segment
		(start 81.870296 -206.1972)
		(end 82.668364 -206.1972)
		(width 0.17145)
		(layer "F.Cu")
		(net "BMC_I2C_SCL_BUF_8")
	)
	(segment
		(start 82.90687 -145.64995)
		(end 83.6295 -144.92732)
		(width 0.17145)
		(layer "F.Cu")
		(net "BMC_I2C_SCL_BUF_8")
	)
	(segment
		(start 86.015068 -145.67535)
		(end 84.37753 -145.67535)
		(width 0.17145)
		(layer "F.Cu")
		(net "BMC_I2C_SCL_BUF_8")
	)
	(segment
		(start 82.46745 -145.64995)
		(end 82.90687 -145.64995)
		(width 0.17145)
		(layer "F.Cu")
		(net "BMC_I2C_SCL_BUF_8")
	)
	(segment
		(start 81.48955 -99.25431)
		(end 81.3181 -99.42576)
		(width 0.17145)
		(layer "F.Cu")
		(net "BMC_I2C_SCL_BUF_8")
	)
	(segment
		(start 73.409048 -207.140048)
		(end 80.927448 -207.140048)
		(width 0.17145)
		(layer "F.Cu")
		(net "BMC_I2C_SCL_BUF_8")
	)
	(segment
		(start 80.927448 -207.140048)
		(end 81.870296 -206.1972)
		(width 0.17145)
		(layer "F.Cu")
		(net "BMC_I2C_SCL_BUF_8")
	)
	(segment
		(start 72.3646 -199.715374)
		(end 72.3646 -206.0956)
		(width 0.17145)
		(layer "F.Cu")
		(net "BMC_I2C_SCL_BUF_8")
	)
	(segment
		(start 84.0105 -205.994)
		(end 83.8073 -206.1972)
		(width 0.17145)
		(layer "F.Cu")
		(net "BMC_I2C_SCL_BUF_8")
	)
	(segment
		(start 86.233 -145.457418)
		(end 86.015068 -145.67535)
		(width 0.17145)
		(layer "F.Cu")
		(net "BMC_I2C_SCL_BUF_8")
	)
	(segment
		(start 84.37753 -145.67535)
		(end 83.6295 -144.92732)
		(width 0.17145)
		(layer "F.Cu")
		(net "BMC_I2C_SCL_BUF_8")
	)
	(segment
		(start 88.439752 -147.067778)
		(end 88.439752 -183.640222)
		(width 0.17145)
		(layer "F.Cu")
		(net "BMC_I2C_SCL_BUF_8")
	)
	(segment
		(start 83.024472 -206.1972)
		(end 82.846418 -206.019146)
		(width 0.17145)
		(layer "F.Cu")
		(net "BMC_I2C_SCL_BUF_8")
	)
	(segment
		(start 82.2325 -145.415)
		(end 82.46745 -145.64995)
		(width 0.17145)
		(layer "F.Cu")
		(net "BMC_I2C_SCL_BUF_8")
	)
	(segment
		(start 82.668364 -206.1972)
		(end 82.846418 -206.019146)
		(width 0.17145)
		(layer "F.Cu")
		(net "BMC_I2C_SCL_BUF_8")
	)
	(segment
		(start 88.439752 -183.640222)
		(end 72.3646 -199.715374)
		(width 0.17145)
		(layer "F.Cu")
		(net "BMC_I2C_SCL_BUF_8")
	)
	(segment
		(start 83.8073 -206.1972)
		(end 83.024472 -206.1972)
		(width 0.17145)
		(layer "F.Cu")
		(net "BMC_I2C_SCL_BUF_8")
	)
	(segment
		(start 83.35264 -97.0026)
		(end 82.225896 -97.0026)
		(width 0.17145)
		(layer "F.Cu")
		(net "BMC_I2C_SCL_BUF_8")
	)
	(segment
		(start 81.3181 -99.42576)
		(end 80.938624 -99.42576)
		(width 0.17145)
		(layer "F.Cu")
		(net "BMC_I2C_SCL_BUF_8")
	)
	(segment
		(start 72.3646 -206.0956)
		(end 73.409048 -207.140048)
		(width 0.17145)
		(layer "F.Cu")
		(net "BMC_I2C_SCL_BUF_8")
	)
	(segment
		(start 83.58124 -96.774)
		(end 83.35264 -97.0026)
		(width 0.17145)
		(layer "F.Cu")
		(net "BMC_I2C_SCL_BUF_8")
	)
	(segment
		(start 86.233 -145.457418)
		(end 86.419182 -145.6436)
		(width 0.17145)
		(layer "F.Cu")
		(net "BMC_I2C_SCL_BUF_8")
	)
	(segment
		(start 82.225896 -97.0026)
		(end 81.48955 -97.738946)
		(width 0.17145)
		(layer "F.Cu")
		(net "BMC_I2C_SCL_BUF_8")
	)
	(segment
		(start 87.015574 -145.6436)
		(end 88.439752 -147.067778)
		(width 0.17145)
		(layer "F.Cu")
		(net "BMC_I2C_SCL_BUF_8")
	)
	(segment
		(start 84.0105 -96.774)
		(end 83.58124 -96.774)
		(width 0.17145)
		(layer "F.Cu")
		(net "BMC_I2C_SCL_BUF_8")
	)
	(segment
		(start 81.48955 -97.738946)
		(end 81.48955 -99.25431)
		(width 0.17145)
		(layer "F.Cu")
		(net "BMC_I2C_SCL_BUF_8")
	)
	(via
		(at 86.233 -145.457418)
		(size 0.508)
		(drill 0.254)
		(layers "F.Cu" "B.Cu")
		(net "BMC_I2C_SCL_BUF_8")
	)
	(via
		(at 80.938624 -99.42576)
		(size 0.508)
		(drill 0.254)
		(layers "F.Cu" "B.Cu")
		(net "BMC_I2C_SCL_BUF_8")
	)
	(via
		(at 81.4578 -100.6094)
		(size 0.7112)
		(drill 0.3556)
		(layers "F.Cu" "B.Cu")
		(net "BMC_I2C_SCL_BUF_8")
	)
	(via
		(at 82.846418 -206.019146)
		(size 0.508)
		(drill 0.254)
		(layers "F.Cu" "B.Cu")
		(net "BMC_I2C_SCL_BUF_8")
	)
	(segment
		(start 41.833546 -471.12555)
		(end 36.066476 -471.12555)
		(width 0.17145)
		(layer "B.Cu")
		(net "BMC_I2C_SCL_BUF_8")
	)
	(segment
		(start 5.93725 -450.56425)
		(end 5.0546 -449.6816)
		(width 0.17145)
		(layer "B.Cu")
		(net "BMC_I2C_SCL_BUF_8")
	)
	(segment
		(start 111.57585 -201.08545)
		(end 118.5164 -208.026)
		(width 0.17145)
		(layer "B.Cu")
		(net "BMC_I2C_SCL_BUF_8")
	)
	(segment
		(start 32.329374 -474.862652)
		(end 19.567652 -474.862652)
		(width 0.17145)
		(layer "B.Cu")
		(net "BMC_I2C_SCL_BUF_8")
	)
	(segment
		(start 70.507352 -469.623648)
		(end 43.335448 -469.623648)
		(width 0.17145)
		(layer "B.Cu")
		(net "BMC_I2C_SCL_BUF_8")
	)
	(segment
		(start 82.32775 -109.600746)
		(end 80.1116 -111.816896)
		(width 0.17145)
		(layer "B.Cu")
		(net "BMC_I2C_SCL_BUF_8")
	)
	(segment
		(start 87.06993 -203.3524)
		(end 89.33688 -201.08545)
		(width 0.17145)
		(layer "B.Cu")
		(net "BMC_I2C_SCL_BUF_8")
	)
	(segment
		(start 79.502 -204.489304)
		(end 80.638904 -203.3524)
		(width 0.17145)
		(layer "B.Cu")
		(net "BMC_I2C_SCL_BUF_8")
	)
	(segment
		(start 118.5164 -208.026)
		(end 118.5164 -447.5734)
		(width 0.17145)
		(layer "B.Cu")
		(net "BMC_I2C_SCL_BUF_8")
	)
	(segment
		(start 90.630248 -135.126222)
		(end 90.630248 -143.892778)
		(width 0.17145)
		(layer "B.Cu")
		(net "BMC_I2C_SCL_BUF_8")
	)
	(segment
		(start 115.7986 -450.2912)
		(end 89.8398 -450.2912)
		(width 0.17145)
		(layer "B.Cu")
		(net "BMC_I2C_SCL_BUF_8")
	)
	(segment
		(start 82.51444 -206.351124)
		(end 80.540098 -206.351124)
		(width 0.17145)
		(layer "B.Cu")
		(net "BMC_I2C_SCL_BUF_8")
	)
	(segment
		(start 79.502 -205.313026)
		(end 79.502 -204.489304)
		(width 0.17145)
		(layer "B.Cu")
		(net "BMC_I2C_SCL_BUF_8")
	)
	(segment
		(start 89.33688 -201.08545)
		(end 111.57585 -201.08545)
		(width 0.17145)
		(layer "B.Cu")
		(net "BMC_I2C_SCL_BUF_8")
	)
	(segment
		(start 81.740248 -99.59721)
		(end 81.740248 -100.6094)
		(width 0.17145)
		(layer "B.Cu")
		(net "BMC_I2C_SCL_BUF_8")
	)
	(segment
		(start 12.692126 -453.09155)
		(end 7.696454 -453.09155)
		(width 0.17145)
		(layer "B.Cu")
		(net "BMC_I2C_SCL_BUF_8")
	)
	(segment
		(start 3.7338 -449.6816)
		(end 3.5941 -449.5419)
		(width 0.17145)
		(layer "B.Cu")
		(net "BMC_I2C_SCL_BUF_8")
	)
	(segment
		(start 82.32775 -101.625654)
		(end 82.32775 -109.600746)
		(width 0.17145)
		(layer "B.Cu")
		(net "BMC_I2C_SCL_BUF_8")
	)
	(segment
		(start 88.879426 -145.6436)
		(end 86.419182 -145.6436)
		(width 0.17145)
		(layer "B.Cu")
		(net "BMC_I2C_SCL_BUF_8")
	)
	(segment
		(start 90.630248 -143.892778)
		(end 88.879426 -145.6436)
		(width 0.17145)
		(layer "B.Cu")
		(net "BMC_I2C_SCL_BUF_8")
	)
	(segment
		(start 5.93725 -451.332346)
		(end 5.93725 -450.56425)
		(width 0.17145)
		(layer "B.Cu")
		(net "BMC_I2C_SCL_BUF_8")
	)
	(segment
		(start 89.8398 -450.2912)
		(end 70.507352 -469.623648)
		(width 0.17145)
		(layer "B.Cu")
		(net "BMC_I2C_SCL_BUF_8")
	)
	(segment
		(start 19.567652 -474.862652)
		(end 16.522954 -471.817954)
		(width 0.17145)
		(layer "B.Cu")
		(net "BMC_I2C_SCL_BUF_8")
	)
	(segment
		(start 80.540098 -206.351124)
		(end 79.502 -205.313026)
		(width 0.17145)
		(layer "B.Cu")
		(net "BMC_I2C_SCL_BUF_8")
	)
	(segment
		(start 3.5941 -449.5419)
		(end 1.868932 -449.5419)
		(width 0.17145)
		(layer "B.Cu")
		(net "BMC_I2C_SCL_BUF_8")
	)
	(segment
		(start 81.568798 -99.42576)
		(end 81.740248 -99.59721)
		(width 0.17145)
		(layer "B.Cu")
		(net "BMC_I2C_SCL_BUF_8")
	)
	(segment
		(start 82.846418 -206.019146)
		(end 82.51444 -206.351124)
		(width 0.17145)
		(layer "B.Cu")
		(net "BMC_I2C_SCL_BUF_8")
	)
	(segment
		(start 43.335448 -469.623648)
		(end 41.833546 -471.12555)
		(width 0.17145)
		(layer "B.Cu")
		(net "BMC_I2C_SCL_BUF_8")
	)
	(segment
		(start 16.522954 -456.922378)
		(end 12.692126 -453.09155)
		(width 0.17145)
		(layer "B.Cu")
		(net "BMC_I2C_SCL_BUF_8")
	)
	(segment
		(start 81.740248 -100.6094)
		(end 81.740248 -101.038152)
		(width 0.17145)
		(layer "B.Cu")
		(net "BMC_I2C_SCL_BUF_8")
	)
	(segment
		(start 86.419182 -145.6436)
		(end 86.233 -145.457418)
		(width 0.17145)
		(layer "B.Cu")
		(net "BMC_I2C_SCL_BUF_8")
	)
	(segment
		(start 80.1116 -124.607574)
		(end 90.630248 -135.126222)
		(width 0.17145)
		(layer "B.Cu")
		(net "BMC_I2C_SCL_BUF_8")
	)
	(segment
		(start 5.0546 -449.6816)
		(end 3.7338 -449.6816)
		(width 0.17145)
		(layer "B.Cu")
		(net "BMC_I2C_SCL_BUF_8")
	)
	(segment
		(start 81.740248 -100.6094)
		(end 81.4578 -100.6094)
		(width 0.17145)
		(layer "B.Cu")
		(net "BMC_I2C_SCL_BUF_8")
	)
	(segment
		(start 81.740248 -101.038152)
		(end 82.32775 -101.625654)
		(width 0.17145)
		(layer "B.Cu")
		(net "BMC_I2C_SCL_BUF_8")
	)
	(segment
		(start 36.066476 -471.12555)
		(end 32.329374 -474.862652)
		(width 0.17145)
		(layer "B.Cu")
		(net "BMC_I2C_SCL_BUF_8")
	)
	(segment
		(start 80.938624 -99.42576)
		(end 81.568798 -99.42576)
		(width 0.17145)
		(layer "B.Cu")
		(net "BMC_I2C_SCL_BUF_8")
	)
	(segment
		(start 118.5164 -447.5734)
		(end 115.7986 -450.2912)
		(width 0.17145)
		(layer "B.Cu")
		(net "BMC_I2C_SCL_BUF_8")
	)
	(segment
		(start 7.696454 -453.09155)
		(end 5.93725 -451.332346)
		(width 0.17145)
		(layer "B.Cu")
		(net "BMC_I2C_SCL_BUF_8")
	)
	(segment
		(start 80.638904 -203.3524)
		(end 87.06993 -203.3524)
		(width 0.17145)
		(layer "B.Cu")
		(net "BMC_I2C_SCL_BUF_8")
	)
	(segment
		(start 16.522954 -471.817954)
		(end 16.522954 -456.922378)
		(width 0.17145)
		(layer "B.Cu")
		(net "BMC_I2C_SCL_BUF_8")
	)
	(segment
		(start 80.1116 -111.816896)
		(end 80.1116 -124.607574)
		(width 0.17145)
		(layer "B.Cu")
		(net "BMC_I2C_SCL_BUF_8")
	)
	(zone
		(net "GND")
		(layer "F.Cu")
		(hatch none 0.5)
		(connect_pads
			(clearance 0.5)
		)
		(min_thickness 0.25)
		(fill yes
			(thermal_gap 0.5)
			(thermal_bridge_width 0.5)
			(island_removal_mode 0)
		)
		(polygon
			(pts
				(xy 200.042526 -461.265524) (xy 199.537828 -461.770222) (xy 199.537828 -462.822798) (xy 210.565492 -473.850462)
				(xy 210.565492 -487.350562) (xy 213.804754 -490.589824) (xy 219.336366 -490.589824) (xy 219.742258 -490.183932)
				(xy 219.742258 -475.916498) (xy 218.216734 -474.390974) (xy 214.057992 -474.390974) (xy 207.207358 -467.54034)
				(xy 207.207358 -466.650832) (xy 207.624172 -466.234018) (xy 208.58988 -466.234018) (xy 215.010238 -472.654376)
				(xy 219.202508 -472.654376) (xy 219.696284 -472.1606) (xy 219.696284 -465.50961) (xy 218.006422 -463.819748)
				(xy 211.747354 -463.819748) (xy 211.456524 -463.528918) (xy 211.456524 -461.358996) (xy 211.363052 -461.265524)
			)
		)
		(polygon
			(pts
				(xy 210.9216 -461.7212) (xy 210.7184 -461.7212) (xy 210.7184 -461.9244) (xy 210.9216 -461.9244)
			)
		)
	)
	(zone
		(net "GND")
		(layer "F.Cu")
		(hatch none 0.5)
		(connect_pads
			(clearance 0.5)
		)
		(min_thickness 0.25)
		(fill yes
			(thermal_gap 0.5)
			(thermal_bridge_width 0.5)
			(island_removal_mode 0)
		)
		(polygon
			(pts
				(xy 124.897134 -260.35) (xy 104.716072 -280.531062) (xy 104.716072 -284.308042) (xy 106.66603 -286.258)
				(xy 218.059 -286.258) (xy 219.583 -284.734) (xy 219.583 -271.399) (xy 216.916 -268.732) (xy 167.513 -268.732)
				(xy 166.243 -267.462) (xy 166.243 -266.7) (xy 166.751 -266.192) (xy 216.027 -266.192) (xy 217.17 -265.049)
				(xy 217.17 -261.874) (xy 215.646 -260.35)
			)
		)
	)
	(zone
		(layer "F.Cu")
		(hatch none 0.5)
		(connect_pads
			(clearance 0)
		)
		(min_thickness 0.25)
		(keepout
			(tracks not_allowed)
			(vias allowed)
			(pads allowed)
			(copperpour not_allowed)
			(footprints allowed)
		)
		(placement
			(enabled no)
			(sheetname "")
		)
		(fill
			(thermal_gap 0.5)
			(thermal_bridge_width 0.5)
			(island_removal_mode 0)
		)
		(polygon
			(pts
				(arc
					(start 17.78254 -444.603378)
					(mid 17.272 -444.092838)
					(end 16.76146 -444.603378)
				)
				(arc
					(start 16.76146 -445.415924)
					(mid 17.271873 -445.926718)
					(end 17.78254 -445.416178)
				)
				(xy 17.78254 -445.262254) (xy 17.567402 -445.262254)
				(arc
					(start 17.517618 -445.312038)
					(mid 17.083356 -445.604822)
					(end 17.37614 -445.17056)
				)
				(xy 17.484598 -445.062102) (xy 17.78254 -445.062102) (xy 17.78254 -444.9572) (xy 17.484344 -444.9572)
				(arc
					(start 17.37614 -444.848996)
					(mid 17.083356 -444.414734)
					(end 17.517618 -444.707518)
				)
				(xy 17.567148 -444.757048) (xy 17.78254 -444.757048)
			)
		)
	)
	(zone
		(layer "F.Cu")
		(hatch none 0.5)
		(connect_pads
			(clearance 0)
		)
		(min_thickness 0.25)
		(keepout
			(tracks not_allowed)
			(vias allowed)
			(pads allowed)
			(copperpour not_allowed)
			(footprints allowed)
		)
		(placement
			(enabled no)
			(sheetname "")
		)
		(fill
			(thermal_gap 0.5)
			(thermal_bridge_width 0.5)
			(island_removal_mode 0)
		)
		(polygon
			(pts
				(arc
					(start 27.18054 -38.603428)
					(mid 26.67 -38.092888)
					(end 26.15946 -38.603428)
				)
				(xy 26.15946 -38.757098) (xy 26.374852 -38.757098)
				(arc
					(start 26.424382 -38.707568)
					(mid 26.858644 -38.414784)
					(end 26.56586 -38.849046)
				)
				(xy 26.457656 -38.95725) (xy 26.15946 -38.95725) (xy 26.15946 -39.062152) (xy 26.457402 -39.062152)
				(arc
					(start 26.56586 -39.17061)
					(mid 26.858644 -39.604872)
					(end 26.424382 -39.312088)
				)
				(xy 26.374598 -39.262304) (xy 26.15946 -39.262304)
				(arc
					(start 26.15946 -39.415974)
					(mid 26.669873 -39.926768)
					(end 27.18054 -39.416228)
				)
			)
		)
	)
	(zone
		(net "GND")
		(layer "F.Cu")
		(hatch none 0.5)
		(connect_pads
			(clearance 0.5)
		)
		(min_thickness 0.25)
		(fill yes
			(thermal_gap 0.5)
			(thermal_bridge_width 0.5)
			(island_removal_mode 0)
		)
		(polygon
			(pts
				(xy 208.4324 -499.1354) (xy 208.1784 -499.3894) (xy 208.1784 -501.0658) (xy 208.7118 -501.5992)
				(xy 215.3158 -501.5992) (xy 215.5698 -501.3452) (xy 215.5698 -499.40083) (xy 215.30437 -499.1354)
			)
		)
		(polygon
			(pts
				(xy 214.6808 -500.0244) (xy 214.4776 -500.0244) (xy 214.4776 -500.2276) (xy 214.6808 -500.2276)
			)
		)
	)
	(zone
		(layer "F.Cu")
		(hatch none 0.5)
		(connect_pads
			(clearance 0)
		)
		(min_thickness 0.25)
		(keepout
			(tracks not_allowed)
			(vias allowed)
			(pads allowed)
			(copperpour not_allowed)
			(footprints allowed)
		)
		(placement
			(enabled no)
			(sheetname "")
		)
		(fill
			(thermal_gap 0.5)
			(thermal_bridge_width 0.5)
			(island_removal_mode 0)
		)
		(polygon
			(pts
				(arc
					(start 25.88514 -224.451164)
					(mid 25.273 -223.839024)
					(end 24.66086 -224.451164)
				)
				(xy 24.66086 -224.757234) (xy 24.825452 -224.757234)
				(arc
					(start 25.027382 -224.555304)
					(mid 25.461644 -224.26252)
					(end 25.16886 -224.696782)
				)
				(xy 24.908256 -224.957386) (xy 24.66086 -224.957386) (xy 24.66086 -225.062288) (xy 24.908002 -225.062288)
				(arc
					(start 25.16886 -225.323146)
					(mid 25.461644 -225.757408)
					(end 25.027382 -225.464624)
				)
				(xy 24.825198 -225.26244) (xy 24.66086 -225.26244)
				(arc
					(start 24.66086 -225.56851)
					(mid 25.272873 -226.180904)
					(end 25.88514 -225.568764)
				)
			)
		)
	)
	(zone
		(net "P12V")
		(layer "F.Cu")
		(hatch none 0.5)
		(connect_pads
			(clearance 0.5)
		)
		(min_thickness 0.25)
		(fill yes
			(thermal_gap 0.5)
			(thermal_bridge_width 0.5)
			(island_removal_mode 0)
		)
		(polygon
			(pts
				(xy 16.3576 -491.5154) (xy 16.256 -491.617) (xy 16.256 -491.998) (xy 16.383 -492.125) (xy 17.018 -492.125)
				(xy 17.2974 -492.4044) (xy 17.2974 -494.5634) (xy 18.306288 -495.572288) (xy 18.306288 -497.373402)
				(xy 18.518886 -497.586) (xy 20.5486 -497.586) (xy 21.169376 -496.965224) (xy 22.032976 -496.965224)
				(xy 22.5298 -496.4684) (xy 22.5298 -492.6838) (xy 21.7932 -491.9472) (xy 18.891758 -491.9472) (xy 18.459958 -491.5154)
			)
		)
		(polygon
			(pts
				(xy 17.9578 -493.0648) (xy 17.7546 -493.0648) (xy 17.7546 -493.268) (xy 17.9578 -493.268)
			)
		)
		(polygon
			(pts
				(xy 17.9578 -492.506) (xy 17.7546 -492.506) (xy 17.7546 -492.7092) (xy 17.9578 -492.7092)
			)
		)
		(polygon
			(pts
				(xy 18.0594 -492.0234) (xy 17.8562 -492.0234) (xy 17.8562 -492.2266) (xy 18.0594 -492.2266)
			)
		)
	)
	(zone
		(net "P12V")
		(layer "F.Cu")
		(hatch none 0.5)
		(connect_pads
			(clearance 0.5)
		)
		(min_thickness 0.25)
		(fill yes
			(thermal_gap 0.5)
			(thermal_bridge_width 0.5)
			(island_removal_mode 0)
		)
		(polygon
			(pts
				(xy 209.0166 -293.2684) (xy 208.915 -293.37) (xy 208.915 -293.878) (xy 209.042 -294.005) (xy 209.677 -294.005)
				(xy 209.9564 -294.2844) (xy 209.9564 -295.0464) (xy 210.312 -295.402) (xy 210.312 -296.799) (xy 211.2518 -297.7388)
				(xy 211.2518 -299.0342) (xy 212.598 -300.3804) (xy 213.91118 -300.3804) (xy 214.0458 -300.24578)
				(xy 214.0458 -299.602652) (xy 214.63 -299.018452) (xy 214.63 -294.1066) (xy 214.4014 -293.878) (xy 211.328 -293.878)
				(xy 210.7184 -293.2684)
			)
		)
		(polygon
			(pts
				(xy 213.7791 -299.7073) (xy 213.5759 -299.7073) (xy 213.5759 -299.9105) (xy 213.7791 -299.9105)
			)
		)
		(polygon
			(pts
				(xy 213.2203 -299.7073) (xy 213.0171 -299.7073) (xy 213.0171 -299.9105) (xy 213.2203 -299.9105)
			)
		)
		(polygon
			(pts
				(xy 210.6168 -294.8178) (xy 210.4136 -294.8178) (xy 210.4136 -295.021) (xy 210.6168 -295.021)
			)
		)
		(polygon
			(pts
				(xy 210.6168 -294.259) (xy 210.4136 -294.259) (xy 210.4136 -294.4622) (xy 210.6168 -294.4622)
			)
		)
		(polygon
			(pts
				(xy 210.7184 -293.7764) (xy 210.5152 -293.7764) (xy 210.5152 -293.9796) (xy 210.7184 -293.9796)
			)
		)
		(polygon
			(pts
				(xy 210.1088 -293.7764) (xy 209.9056 -293.7764) (xy 209.9056 -293.9796) (xy 210.1088 -293.9796)
			)
		)
	)
	(zone
		(layer "F.Cu")
		(hatch none 0.5)
		(connect_pads
			(clearance 0)
		)
		(min_thickness 0.25)
		(keepout
			(tracks allowed)
			(vias allowed)
			(pads allowed)
			(copperpour allowed)
			(footprints allowed)
		)
		(placement
			(enabled no)
			(sheetname "")
		)
		(fill
			(thermal_gap 0.5)
			(thermal_bridge_width 0.5)
			(island_removal_mode 0)
		)
		(polygon
			(pts
				(xy 92.075 -438.404) (xy 91.694 -438.785) (xy 91.694 -440.309) (xy 86.233 -440.309) (xy 86.233 -439.547)
				(xy 87.63 -438.15) (xy 88.9 -438.15) (xy 90.043 -437.007) (xy 90.043 -435.864) (xy 96.393 -435.864)
				(xy 96.393 -438.404)
			)
		)
	)
	(zone
		(layer "F.Cu")
		(hatch none 0.5)
		(connect_pads
			(clearance 0)
		)
		(min_thickness 0.25)
		(keepout
			(tracks not_allowed)
			(vias allowed)
			(pads allowed)
			(copperpour not_allowed)
			(footprints allowed)
		)
		(placement
			(enabled no)
			(sheetname "")
		)
		(fill
			(thermal_gap 0.5)
			(thermal_bridge_width 0.5)
			(island_removal_mode 0)
		)
		(polygon
			(pts
				(arc
					(start 37.33927 -275.631402)
					(mid 36.727257 -275.019008)
					(end 36.11499 -275.631148)
				)
				(arc
					(start 36.11499 -276.748748)
					(mid 36.72713 -277.360888)
					(end 37.33927 -276.748748)
				)
				(xy 37.33927 -276.442678) (xy 37.174678 -276.442678)
				(arc
					(start 36.972748 -276.644608)
					(mid 36.538486 -276.937392)
					(end 36.83127 -276.50313)
				)
				(xy 37.091874 -276.242526) (xy 37.33927 -276.242526) (xy 37.33927 -276.137624) (xy 37.092128 -276.137624)
				(arc
					(start 36.83127 -275.876766)
					(mid 36.538486 -275.442504)
					(end 36.972748 -275.735288)
				)
				(xy 37.174932 -275.937472) (xy 37.33927 -275.937472)
			)
		)
	)
	(zone
		(layer "F.Cu")
		(hatch none 0.5)
		(connect_pads
			(clearance 0)
		)
		(min_thickness 0.25)
		(keepout
			(tracks not_allowed)
			(vias allowed)
			(pads allowed)
			(copperpour not_allowed)
			(footprints allowed)
		)
		(placement
			(enabled no)
			(sheetname "")
		)
		(fill
			(thermal_gap 0.5)
			(thermal_bridge_width 0.5)
			(island_removal_mode 0)
		)
		(polygon
			(pts
				(arc
					(start 7.502906 -405.535638)
					(mid 6.992366 -405.025098)
					(end 6.481826 -405.535638)
				)
				(xy 6.481826 -405.689308) (xy 6.697218 -405.689308)
				(arc
					(start 6.746748 -405.639778)
					(mid 7.18101 -405.346994)
					(end 6.888226 -405.781256)
				)
				(xy 6.780022 -405.88946) (xy 6.481826 -405.88946) (xy 6.481826 -405.994362) (xy 6.779768 -405.994362)
				(arc
					(start 6.888226 -406.10282)
					(mid 7.18101 -406.537082)
					(end 6.746748 -406.244298)
				)
				(xy 6.696964 -406.194514) (xy 6.481826 -406.194514)
				(arc
					(start 6.481826 -406.348184)
					(mid 6.992239 -406.858978)
					(end 7.502906 -406.348438)
				)
			)
		)
	)
	(zone
		(net "P12V_SSD12")
		(layer "F.Cu")
		(hatch none 0.5)
		(connect_pads
			(clearance 0.5)
		)
		(min_thickness 0.25)
		(fill yes
			(thermal_gap 0.5)
			(thermal_bridge_width 0.5)
			(island_removal_mode 0)
		)
		(polygon
			(pts
				(xy 19.7358 -203.6826) (xy 19.433032 -203.985368) (xy 19.433032 -209.171032) (xy 20.193 -209.931)
				(xy 20.193 -210.82) (xy 18.542 -212.471) (xy 18.542 -218.22537) (xy 18.656808 -218.340178) (xy 21.100288 -218.340178)
				(xy 21.209 -218.231466) (xy 21.209 -216.281) (xy 21.463 -216.027) (xy 22.1996 -216.027) (xy 24.2824 -213.9442)
				(xy 30.1752 -213.9442) (xy 30.6578 -213.4616) (xy 30.6578 -208.7118) (xy 30.48 -208.534) (xy 24.003 -208.534)
				(xy 23.749 -208.28) (xy 23.749 -203.962) (xy 23.4696 -203.6826)
			)
		)
		(polygon
			(pts
				(xy 25.4 -213.233) (xy 25.1968 -213.233) (xy 25.1968 -213.4362) (xy 25.4 -213.4362)
			)
		)
		(polygon
			(pts
				(xy 24.7904 -213.233) (xy 24.5872 -213.233) (xy 24.5872 -213.4362) (xy 24.7904 -213.4362)
			)
		)
		(polygon
			(pts
				(xy 28.1432 -209.3976) (xy 27.94 -209.3976) (xy 27.94 -209.6008) (xy 28.1432 -209.6008)
			)
		)
		(polygon
			(pts
				(xy 27.2796 -209.3976) (xy 27.0764 -209.3976) (xy 27.0764 -209.6008) (xy 27.2796 -209.6008)
			)
		)
		(polygon
			(pts
				(xy 23.1902 -207.8482) (xy 22.987 -207.8482) (xy 22.987 -208.0514) (xy 23.1902 -208.0514)
			)
		)
		(polygon
			(pts
				(xy 22.0472 -207.8482) (xy 21.844 -207.8482) (xy 21.844 -208.0514) (xy 22.0472 -208.0514)
			)
		)
		(polygon
			(pts
				(xy 23.1902 -205.0542) (xy 22.987 -205.0542) (xy 22.987 -205.2574) (xy 23.1902 -205.2574)
			)
		)
		(polygon
			(pts
				(xy 22.0472 -205.0542) (xy 21.844 -205.0542) (xy 21.844 -205.2574) (xy 22.0472 -205.2574)
			)
		)
	)
	(zone
		(layer "F.Cu")
		(hatch none 0.5)
		(connect_pads
			(clearance 0)
		)
		(min_thickness 0.25)
		(keepout
			(tracks not_allowed)
			(vias allowed)
			(pads allowed)
			(copperpour not_allowed)
			(footprints allowed)
		)
		(placement
			(enabled no)
			(sheetname "")
		)
		(fill
			(thermal_gap 0.5)
			(thermal_bridge_width 0.5)
			(island_removal_mode 0)
		)
		(polygon
			(pts
				(arc
					(start 37.33927 -262.83158)
					(mid 36.727257 -262.219186)
					(end 36.11499 -262.831326)
				)
				(arc
					(start 36.11499 -263.948926)
					(mid 36.72713 -264.561066)
					(end 37.33927 -263.948926)
				)
				(xy 37.33927 -263.642602) (xy 37.174932 -263.642602)
				(arc
					(start 36.972748 -263.844786)
					(mid 36.538486 -264.13757)
					(end 36.83127 -263.703308)
				)
				(xy 37.092128 -263.44245) (xy 37.33927 -263.44245) (xy 37.33927 -263.337548) (xy 37.091874 -263.337548)
				(arc
					(start 36.83127 -263.076944)
					(mid 36.538486 -262.642682)
					(end 36.972748 -262.935466)
				)
				(xy 37.174678 -263.137396) (xy 37.33927 -263.137396)
			)
		)
	)
	(zone
		(net "P12V_SSD2")
		(layer "F.Cu")
		(hatch none 0.5)
		(connect_pads
			(clearance 0.5)
		)
		(min_thickness 0.25)
		(fill yes
			(thermal_gap 0.5)
			(thermal_bridge_width 0.5)
			(island_removal_mode 0)
		)
		(polygon
			(pts
				(xy 225.918776 -287.71469) (xy 225.806 -287.827466) (xy 225.806 -289.687) (xy 225.5266 -289.9664)
				(xy 224.8916 -289.9664) (xy 222.7326 -292.1254) (xy 218.6686 -292.1254) (xy 218.4019 -292.3921)
				(xy 216.5477 -292.3921) (xy 216.1286 -292.8112) (xy 216.1286 -297.1292) (xy 216.4334 -297.434) (xy 223.012 -297.434)
				(xy 223.266 -297.688) (xy 223.266 -301.2948) (xy 223.4946 -301.5234) (xy 227.7872 -301.5234) (xy 228.219 -301.0916)
				(xy 228.219 -297.434) (xy 226.822 -296.037) (xy 226.822 -295.148) (xy 228.473 -293.497) (xy 228.473 -287.815274)
				(xy 228.372416 -287.71469)
			)
		)
		(polygon
			(pts
				(xy 227.6348 -301.1678) (xy 227.4316 -301.1678) (xy 227.4316 -301.371) (xy 227.6348 -301.371)
			)
		)
		(polygon
			(pts
				(xy 226.4918 -301.1678) (xy 226.2886 -301.1678) (xy 226.2886 -301.371) (xy 226.4918 -301.371)
			)
		)
		(polygon
			(pts
				(xy 227.6348 -298.3738) (xy 227.4316 -298.3738) (xy 227.4316 -298.577) (xy 227.6348 -298.577)
			)
		)
		(polygon
			(pts
				(xy 226.4918 -298.3738) (xy 226.2886 -298.3738) (xy 226.2886 -298.577) (xy 226.4918 -298.577)
			)
		)
		(polygon
			(pts
				(xy 222.6564 -296.4434) (xy 222.4532 -296.4434) (xy 222.4532 -296.6466) (xy 222.6564 -296.6466)
			)
		)
		(polygon
			(pts
				(xy 221.7928 -296.4434) (xy 221.5896 -296.4434) (xy 221.5896 -296.6466) (xy 221.7928 -296.6466)
			)
		)
		(polygon
			(pts
				(xy 222.4278 -292.6334) (xy 222.2246 -292.6334) (xy 222.2246 -292.8366) (xy 222.4278 -292.8366)
			)
		)
		(polygon
			(pts
				(xy 221.8182 -292.6334) (xy 221.615 -292.6334) (xy 221.615 -292.8366) (xy 221.8182 -292.8366)
			)
		)
	)
	(zone
		(layer "F.Cu")
		(hatch none 0.5)
		(connect_pads
			(clearance 0)
		)
		(min_thickness 0.25)
		(keepout
			(tracks allowed)
			(vias allowed)
			(pads allowed)
			(copperpour allowed)
			(footprints allowed)
		)
		(placement
			(enabled no)
			(sheetname "")
		)
		(fill
			(thermal_gap 0.5)
			(thermal_bridge_width 0.5)
			(island_removal_mode 0)
		)
		(polygon
			(pts
				(xy 44.323 -60.198) (xy 44.323 -62.484) (xy 42.164 -62.484) (xy 42.164 -60.198)
			)
		)
	)
	(zone
		(net "P12V")
		(layer "F.Cu")
		(hatch none 0.5)
		(connect_pads
			(clearance 0.5)
		)
		(min_thickness 0.25)
		(fill yes
			(thermal_gap 0.5)
			(thermal_bridge_width 0.5)
			(island_removal_mode 0)
		)
		(polygon
			(pts
				(xy 209.0166 -87.2744) (xy 208.915 -87.376) (xy 208.915 -87.884) (xy 209.042 -88.011) (xy 209.677 -88.011)
				(xy 209.9564 -88.2904) (xy 209.9564 -89.0524) (xy 210.312 -89.408) (xy 210.312 -90.805) (xy 211.074 -91.567)
				(xy 211.074 -92.8878) (xy 212.5726 -94.3864) (xy 213.863936 -94.3864) (xy 214.0458 -94.204536) (xy 214.0458 -93.61551)
				(xy 214.7062 -92.95511) (xy 214.7062 -88.392) (xy 214.1982 -87.884) (xy 211.328 -87.884) (xy 210.7184 -87.2744)
			)
		)
		(polygon
			(pts
				(xy 213.7791 -93.7133) (xy 213.5759 -93.7133) (xy 213.5759 -93.9165) (xy 213.7791 -93.9165)
			)
		)
		(polygon
			(pts
				(xy 213.2203 -93.7133) (xy 213.0171 -93.7133) (xy 213.0171 -93.9165) (xy 213.2203 -93.9165)
			)
		)
		(polygon
			(pts
				(xy 210.6168 -88.8238) (xy 210.4136 -88.8238) (xy 210.4136 -89.027) (xy 210.6168 -89.027)
			)
		)
		(polygon
			(pts
				(xy 210.6168 -88.265) (xy 210.4136 -88.265) (xy 210.4136 -88.4682) (xy 210.6168 -88.4682)
			)
		)
		(polygon
			(pts
				(xy 210.7184 -87.7824) (xy 210.5152 -87.7824) (xy 210.5152 -87.9856) (xy 210.7184 -87.9856)
			)
		)
		(polygon
			(pts
				(xy 210.1088 -87.7824) (xy 209.9056 -87.7824) (xy 209.9056 -87.9856) (xy 210.1088 -87.9856)
			)
		)
	)
	(zone
		(layer "F.Cu")
		(hatch none 0.5)
		(connect_pads
			(clearance 0)
		)
		(min_thickness 0.25)
		(keepout
			(tracks not_allowed)
			(vias allowed)
			(pads allowed)
			(copperpour not_allowed)
			(footprints allowed)
		)
		(placement
			(enabled no)
			(sheetname "")
		)
		(fill
			(thermal_gap 0.5)
			(thermal_bridge_width 0.5)
			(island_removal_mode 0)
		)
		(polygon
			(pts
				(arc
					(start 7.502906 -281.98699)
					(mid 6.992493 -281.476196)
					(end 6.481826 -281.986736)
				)
				(xy 6.481826 -282.11907) (xy 6.718554 -282.11907)
				(arc
					(start 6.746748 -282.090876)
					(mid 7.18101 -281.798092)
					(end 6.888226 -282.232354)
				)
				(xy 6.801358 -282.319222) (xy 6.481826 -282.319222) (xy 6.481826 -282.424124) (xy 6.758432 -282.424124)
				(arc
					(start 6.888226 -282.553918)
					(mid 7.18101 -282.98818)
					(end 6.746748 -282.695396)
				)
				(xy 6.675628 -282.624276) (xy 6.481826 -282.624276)
				(arc
					(start 6.481826 -282.799536)
					(mid 6.992366 -283.310076)
					(end 7.502906 -282.799536)
				)
			)
		)
	)
	(zone
		(layer "F.Cu")
		(hatch none 0.5)
		(connect_pads
			(clearance 0)
		)
		(min_thickness 0.25)
		(keepout
			(tracks not_allowed)
			(vias allowed)
			(pads allowed)
			(copperpour not_allowed)
			(footprints allowed)
		)
		(placement
			(enabled no)
			(sheetname "")
		)
		(fill
			(thermal_gap 0.5)
			(thermal_bridge_width 0.5)
			(island_removal_mode 0)
		)
		(polygon
			(pts
				(arc
					(start 233.897424 -163.579302)
					(mid 233.386884 -163.068762)
					(end 232.876344 -163.579302)
				)
				(arc
					(start 232.876344 -164.391848)
					(mid 233.386757 -164.902642)
					(end 233.897424 -164.392102)
				)
				(xy 233.897424 -164.238178) (xy 233.682286 -164.238178)
				(arc
					(start 233.632502 -164.287962)
					(mid 233.19824 -164.580746)
					(end 233.491024 -164.146484)
				)
				(xy 233.599482 -164.038026) (xy 233.897424 -164.038026) (xy 233.897424 -163.933124) (xy 233.599228 -163.933124)
				(arc
					(start 233.491024 -163.82492)
					(mid 233.19824 -163.390658)
					(end 233.632502 -163.683442)
				)
				(xy 233.682032 -163.732972) (xy 233.897424 -163.732972)
			)
		)
	)
	(zone
		(layer "F.Cu")
		(hatch none 0.5)
		(connect_pads
			(clearance 0)
		)
		(min_thickness 0.25)
		(keepout
			(tracks allowed)
			(vias allowed)
			(pads allowed)
			(copperpour allowed)
			(footprints allowed)
		)
		(placement
			(enabled no)
			(sheetname "")
		)
		(fill
			(thermal_gap 0.5)
			(thermal_bridge_width 0.5)
			(island_removal_mode 0)
		)
		(polygon
			(pts
				(xy 44.323 -472.313) (xy 44.323 -474.599) (xy 42.164 -474.599) (xy 42.164 -472.313)
			)
		)
	)
	(zone
		(layer "F.Cu")
		(hatch none 0.5)
		(connect_pads
			(clearance 0)
		)
		(min_thickness 0.25)
		(keepout
			(tracks not_allowed)
			(vias allowed)
			(pads allowed)
			(copperpour not_allowed)
			(footprints allowed)
		)
		(placement
			(enabled no)
			(sheetname "")
		)
		(fill
			(thermal_gap 0.5)
			(thermal_bridge_width 0.5)
			(island_removal_mode 0)
		)
		(polygon
			(pts
				(xy 95.39478 -214.65921) (xy 95.48368 -214.65921) (xy 95.48368 -215.82761) (xy 95.39478 -215.82761)
			)
		)
	)
	(zone
		(layer "F.Cu")
		(hatch none 0.5)
		(connect_pads
			(clearance 0)
		)
		(min_thickness 0.25)
		(keepout
			(tracks not_allowed)
			(vias allowed)
			(pads allowed)
			(copperpour not_allowed)
			(footprints allowed)
		)
		(placement
			(enabled no)
			(sheetname "")
		)
		(fill
			(thermal_gap 0.5)
			(thermal_bridge_width 0.5)
			(island_removal_mode 0)
		)
		(polygon
			(pts
				(arc
					(start 7.502906 -168.787064)
					(mid 6.992493 -168.27627)
					(end 6.481826 -168.78681)
				)
				(xy 6.481826 -168.940226) (xy 6.697472 -168.940226)
				(arc
					(start 6.746748 -168.89095)
					(mid 7.18101 -168.598166)
					(end 6.888226 -169.032428)
				)
				(xy 6.780276 -169.140378) (xy 6.481826 -169.140378) (xy 6.481826 -169.24528) (xy 6.779514 -169.24528)
				(arc
					(start 6.888226 -169.353992)
					(mid 7.18101 -169.788254)
					(end 6.746748 -169.49547)
				)
				(xy 6.69671 -169.445432) (xy 6.481826 -169.445432)
				(arc
					(start 6.481826 -169.59961)
					(mid 6.992366 -170.11015)
					(end 7.502906 -169.59961)
				)
			)
		)
	)
	(zone
		(layer "F.Cu")
		(hatch none 0.5)
		(connect_pads
			(clearance 0)
		)
		(min_thickness 0.25)
		(keepout
			(tracks not_allowed)
			(vias allowed)
			(pads allowed)
			(copperpour not_allowed)
			(footprints allowed)
		)
		(placement
			(enabled no)
			(sheetname "")
		)
		(fill
			(thermal_gap 0.5)
			(thermal_bridge_width 0.5)
			(island_removal_mode 0)
		)
		(polygon
			(pts
				(arc
					(start 27.18054 -437.803798)
					(mid 26.670127 -437.293004)
					(end 26.15946 -437.803544)
				)
				(xy 26.15946 -437.982868) (xy 26.349198 -437.982868)
				(arc
					(start 26.424382 -437.907684)
					(mid 26.858644 -437.6149)
					(end 26.56586 -438.049162)
				)
				(xy 26.432002 -438.18302) (xy 26.15946 -438.18302) (xy 26.15946 -438.287922) (xy 26.483056 -438.287922)
				(arc
					(start 26.56586 -438.370726)
					(mid 26.858644 -438.804988)
					(end 26.424382 -438.512204)
				)
				(xy 26.400252 -438.488074) (xy 26.15946 -438.488074)
				(arc
					(start 26.15946 -438.616344)
					(mid 26.67 -439.126884)
					(end 27.18054 -438.616344)
				)
			)
		)
	)
	(zone
		(net "GND")
		(layer "F.Cu")
		(hatch none 0.5)
		(connect_pads
			(clearance 0.5)
		)
		(min_thickness 0.25)
		(fill yes
			(thermal_gap 0.5)
			(thermal_bridge_width 0.5)
			(island_removal_mode 0)
		)
		(polygon
			(pts
				(xy 93.1926 -312.9534) (xy 92.71 -313.436) (xy 92.71 -314.9346) (xy 93.0148 -315.2394) (xy 94.5134 -315.2394)
				(xy 94.869 -314.8838) (xy 94.869 -313.055) (xy 94.7674 -312.9534)
			)
		)
		(polygon
			(pts
				(xy 94.2848 -313.4614) (xy 93.8022 -313.4614) (xy 93.8022 -313.6646) (xy 94.2848 -313.6646)
			)
		)
		(polygon
			(pts
				(xy 93.3958 -313.4614) (xy 93.1926 -313.4614) (xy 93.1926 -313.6646) (xy 93.3958 -313.6646)
			)
		)
	)
	(zone
		(net "P12V_SSD8")
		(layer "F.Cu")
		(hatch none 0.5)
		(connect_pads
			(clearance 0.5)
		)
		(min_thickness 0.25)
		(fill yes
			(thermal_gap 0.5)
			(thermal_bridge_width 0.5)
			(island_removal_mode 0)
		)
		(polygon
			(pts
				(xy 40.871648 -184.726834) (xy 40.767 -184.831482) (xy 40.767 -186.69) (xy 40.513 -186.944) (xy 39.8272 -186.944)
				(xy 37.6174 -189.1538) (xy 31.8516 -189.1538) (xy 31.4198 -189.5856) (xy 31.4198 -194.1322) (xy 31.5468 -194.2592)
				(xy 37.7952 -194.2592) (xy 38.3286 -194.7926) (xy 38.3286 -199.2376) (xy 38.5064 -199.4154) (xy 42.799 -199.4154)
				(xy 43.18 -199.0344) (xy 43.18 -194.437) (xy 41.783 -193.04) (xy 41.783 -192.151) (xy 43.434 -190.5)
				(xy 43.434 -184.839356) (xy 43.321478 -184.726834)
			)
		)
		(polygon
			(pts
				(xy 41.4528 -198.247) (xy 41.2496 -198.247) (xy 41.2496 -198.4502) (xy 41.4528 -198.4502)
			)
		)
		(polygon
			(pts
				(xy 40.3098 -198.247) (xy 40.1066 -198.247) (xy 40.1066 -198.4502) (xy 40.3098 -198.4502)
			)
		)
		(polygon
			(pts
				(xy 41.4528 -195.453) (xy 41.2496 -195.453) (xy 41.2496 -195.6562) (xy 41.4528 -195.6562)
			)
		)
		(polygon
			(pts
				(xy 40.3098 -195.453) (xy 40.1066 -195.453) (xy 40.1066 -195.6562) (xy 40.3098 -195.6562)
			)
		)
		(polygon
			(pts
				(xy 37.7444 -193.0908) (xy 37.5412 -193.0908) (xy 37.5412 -193.294) (xy 37.7444 -193.294)
			)
		)
		(polygon
			(pts
				(xy 36.8808 -193.0908) (xy 36.6776 -193.0908) (xy 36.6776 -193.294) (xy 36.8808 -193.294)
			)
		)
		(polygon
			(pts
				(xy 37.4396 -189.6618) (xy 37.2364 -189.6618) (xy 37.2364 -189.865) (xy 37.4396 -189.865)
			)
		)
		(polygon
			(pts
				(xy 36.83 -189.6618) (xy 36.6268 -189.6618) (xy 36.6268 -189.865) (xy 36.83 -189.865)
			)
		)
	)
	(zone
		(layer "F.Cu")
		(hatch none 0.5)
		(connect_pads
			(clearance 0)
		)
		(min_thickness 0.25)
		(keepout
			(tracks not_allowed)
			(vias allowed)
			(pads allowed)
			(copperpour not_allowed)
			(footprints allowed)
		)
		(placement
			(enabled no)
			(sheetname "")
		)
		(fill
			(thermal_gap 0.5)
			(thermal_bridge_width 0.5)
			(island_removal_mode 0)
		)
		(polygon
			(pts
				(arc
					(start 220.840554 -479.384106)
					(mid 220.330141 -478.873312)
					(end 219.819474 -479.383852)
				)
				(arc
					(start 219.819474 -480.196652)
					(mid 220.330014 -480.707192)
					(end 220.840554 -480.196652)
				)
				(xy 220.840554 -480.042728) (xy 220.625416 -480.042728)
				(arc
					(start 220.575632 -480.092512)
					(mid 220.14137 -480.385296)
					(end 220.434154 -479.951034)
				)
				(xy 220.542612 -479.842576) (xy 220.840554 -479.842576) (xy 220.840554 -479.737674) (xy 220.542358 -479.737674)
				(arc
					(start 220.434154 -479.62947)
					(mid 220.14137 -479.195208)
					(end 220.575632 -479.487992)
				)
				(xy 220.625162 -479.537522) (xy 220.840554 -479.537522)
			)
		)
	)
	(zone
		(layer "F.Cu")
		(hatch none 0.5)
		(connect_pads
			(clearance 0)
		)
		(min_thickness 0.25)
		(keepout
			(tracks not_allowed)
			(vias allowed)
			(pads allowed)
			(copperpour not_allowed)
			(footprints allowed)
		)
		(placement
			(enabled no)
			(sheetname "")
		)
		(fill
			(thermal_gap 0.5)
			(thermal_bridge_width 0.5)
			(island_removal_mode 0)
		)
		(polygon
			(pts
				(arc
					(start 7.502906 -162.387026)
					(mid 6.992493 -161.876232)
					(end 6.481826 -162.386772)
				)
				(xy 6.481826 -162.540188) (xy 6.697472 -162.540188)
				(arc
					(start 6.746748 -162.490912)
					(mid 7.18101 -162.198128)
					(end 6.888226 -162.63239)
				)
				(xy 6.780276 -162.74034) (xy 6.481826 -162.74034) (xy 6.481826 -162.845242) (xy 6.779514 -162.845242)
				(arc
					(start 6.888226 -162.953954)
					(mid 7.18101 -163.388216)
					(end 6.746748 -163.095432)
				)
				(xy 6.69671 -163.045394) (xy 6.481826 -163.045394)
				(arc
					(start 6.481826 -163.199572)
					(mid 6.992366 -163.710112)
					(end 7.502906 -163.199572)
				)
			)
		)
	)
	(zone
		(layer "F.Cu")
		(hatch none 0.5)
		(connect_pads
			(clearance 0)
		)
		(min_thickness 0.25)
		(keepout
			(tracks not_allowed)
			(vias allowed)
			(pads allowed)
			(copperpour not_allowed)
			(footprints allowed)
		)
		(placement
			(enabled no)
			(sheetname "")
		)
		(fill
			(thermal_gap 0.5)
			(thermal_bridge_width 0.5)
			(island_removal_mode 0)
		)
		(polygon
			(pts
				(arc
					(start 7.502906 -220.685106)
					(mid 6.992366 -220.174566)
					(end 6.481826 -220.685106)
				)
				(xy 6.481826 -220.838522) (xy 6.697472 -220.838522)
				(arc
					(start 6.746748 -220.789246)
					(mid 7.18101 -220.496462)
					(end 6.888226 -220.930724)
				)
				(xy 6.780276 -221.038674) (xy 6.481826 -221.038674) (xy 6.481826 -221.143576) (xy 6.779514 -221.143576)
				(arc
					(start 6.888226 -221.252288)
					(mid 7.18101 -221.68655)
					(end 6.746748 -221.393766)
				)
				(xy 6.69671 -221.343728) (xy 6.481826 -221.343728)
				(arc
					(start 6.481826 -221.497652)
					(mid 6.992239 -222.008446)
					(end 7.502906 -221.497906)
				)
			)
		)
	)
	(zone
		(layer "F.Cu")
		(hatch none 0.5)
		(connect_pads
			(clearance 0)
		)
		(min_thickness 0.25)
		(keepout
			(tracks not_allowed)
			(vias allowed)
			(pads allowed)
			(copperpour not_allowed)
			(footprints allowed)
		)
		(placement
			(enabled no)
			(sheetname "")
		)
		(fill
			(thermal_gap 0.5)
			(thermal_bridge_width 0.5)
			(island_removal_mode 0)
		)
		(polygon
			(pts
				(xy 94.89567 -300.17339) (xy 95.06458 -300.17339) (xy 95.06458 -301.34179) (xy 94.89567 -301.34179)
			)
		)
	)
	(zone
		(layer "F.Cu")
		(hatch none 0.5)
		(connect_pads
			(clearance 0)
		)
		(min_thickness 0.25)
		(keepout
			(tracks not_allowed)
			(vias allowed)
			(pads allowed)
			(copperpour not_allowed)
			(footprints allowed)
		)
		(placement
			(enabled no)
			(sheetname "")
		)
		(fill
			(thermal_gap 0.5)
			(thermal_bridge_width 0.5)
			(island_removal_mode 0)
		)
		(polygon
			(pts
				(arc
					(start 7.502906 -297.935904)
					(mid 6.992366 -297.425364)
					(end 6.481826 -297.935904)
				)
				(xy 6.481826 -298.08932) (xy 6.697472 -298.08932)
				(arc
					(start 6.746748 -298.040044)
					(mid 7.18101 -297.74726)
					(end 6.888226 -298.181522)
				)
				(xy 6.780276 -298.289472) (xy 6.481826 -298.289472) (xy 6.481826 -298.394374) (xy 6.779514 -298.394374)
				(arc
					(start 6.888226 -298.503086)
					(mid 7.18101 -298.937348)
					(end 6.746748 -298.644564)
				)
				(xy 6.69671 -298.594526) (xy 6.481826 -298.594526)
				(arc
					(start 6.481826 -298.74845)
					(mid 6.992239 -299.259244)
					(end 7.502906 -298.748704)
				)
			)
		)
	)
	(zone
		(layer "F.Cu")
		(hatch none 0.5)
		(connect_pads
			(clearance 0)
		)
		(min_thickness 0.25)
		(keepout
			(tracks allowed)
			(vias allowed)
			(pads allowed)
			(copperpour allowed)
			(footprints allowed)
		)
		(placement
			(enabled no)
			(sheetname "")
		)
		(fill
			(thermal_gap 0.5)
			(thermal_bridge_width 0.5)
			(island_removal_mode 0)
		)
		(polygon
			(pts
				(xy 222.377 -58.928) (xy 222.377 -51.816) (xy 224.536 -51.816) (xy 224.536 -58.928)
			)
		)
	)
	(zone
		(layer "F.Cu")
		(hatch none 0.5)
		(connect_pads
			(clearance 0)
		)
		(min_thickness 0.25)
		(keepout
			(tracks not_allowed)
			(vias allowed)
			(pads allowed)
			(copperpour not_allowed)
			(footprints allowed)
		)
		(placement
			(enabled no)
			(sheetname "")
		)
		(fill
			(thermal_gap 0.5)
			(thermal_bridge_width 0.5)
			(island_removal_mode 0)
		)
		(polygon
			(pts
				(arc
					(start 220.840554 -175.1838)
					(mid 220.330141 -174.673006)
					(end 219.819474 -175.183546)
				)
				(arc
					(start 219.819474 -175.996346)
					(mid 220.330014 -176.506886)
					(end 220.840554 -175.996346)
				)
				(xy 220.840554 -175.842676) (xy 220.625162 -175.842676)
				(arc
					(start 220.575632 -175.892206)
					(mid 220.14137 -176.18499)
					(end 220.434154 -175.750728)
				)
				(xy 220.542358 -175.642524) (xy 220.840554 -175.642524) (xy 220.840554 -175.537622) (xy 220.542612 -175.537622)
				(arc
					(start 220.434154 -175.429164)
					(mid 220.14137 -174.994902)
					(end 220.575632 -175.287686)
				)
				(xy 220.625416 -175.33747) (xy 220.840554 -175.33747)
			)
		)
	)
	(zone
		(layer "F.Cu")
		(hatch none 0.5)
		(connect_pads
			(clearance 0)
		)
		(min_thickness 0.25)
		(keepout
			(tracks allowed)
			(vias allowed)
			(pads allowed)
			(copperpour allowed)
			(footprints allowed)
		)
		(placement
			(enabled no)
			(sheetname "")
		)
		(fill
			(thermal_gap 0.5)
			(thermal_bridge_width 0.5)
			(island_removal_mode 0)
		)
		(polygon
			(pts
				(xy 78.1558 -306.5018) (xy 78.1558 -305.0032) (xy 79.0702 -305.0032) (xy 79.0702 -306.5018)
			)
		)
	)
	(zone
		(net "GND")
		(layer "F.Cu")
		(hatch none 0.5)
		(connect_pads
			(clearance 0.5)
		)
		(min_thickness 0.25)
		(fill yes
			(thermal_gap 0.5)
			(thermal_bridge_width 0.5)
			(island_removal_mode 0)
		)
		(polygon
			(pts
				(xy 209.514948 -439.928) (xy 209.378804 -440.064144) (xy 209.378804 -442.071252) (xy 209.521552 -442.214)
				(xy 212.823552 -442.214) (xy 213.077552 -441.96) (xy 213.077552 -440.182) (xy 212.823552 -439.928)
			)
		)
	)
	(zone
		(net "GND")
		(layer "F.Cu")
		(hatch none 0.5)
		(connect_pads
			(clearance 0.5)
		)
		(min_thickness 0.25)
		(fill yes
			(thermal_gap 0.5)
			(thermal_bridge_width 0.5)
			(island_removal_mode 0)
		)
		(polygon
			(pts
				(xy 82.439256 -147.573238) (xy 82.307176 -147.705318) (xy 82.307176 -148.580856) (xy 82.516472 -148.790152)
				(xy 83.198208 -148.790152) (xy 83.334352 -148.926296) (xy 83.334352 -149.820376) (xy 83.43138 -149.917404)
				(xy 85.201252 -149.917404) (xy 85.372956 -150.089108) (xy 85.372956 -151.168608) (xy 85.301582 -151.239982)
				(xy 83.450684 -151.239982) (xy 83.340702 -151.349964) (xy 83.340702 -151.816816) (xy 83.4898 -151.965914)
				(xy 85.178392 -151.965914) (xy 85.372956 -152.160478) (xy 85.372956 -155.22321) (xy 85.278976 -155.31719)
				(xy 83.203034 -155.31719) (xy 83.105752 -155.414472) (xy 83.105752 -185.720736) (xy 83.28787 -185.902854)
				(xy 84.78774 -185.902854) (xy 87.206074 -183.48452) (xy 87.206074 -148.225002) (xy 86.55431 -147.573238)
			)
		)
		(polygon
			(pts
				(xy 83.9978 -149.225) (xy 83.7946 -149.225) (xy 83.7946 -149.4282) (xy 83.9978 -149.4282)
			)
		)
	)
	(zone
		(layer "F.Cu")
		(hatch none 0.5)
		(connect_pads
			(clearance 0)
		)
		(min_thickness 0.25)
		(keepout
			(tracks not_allowed)
			(vias allowed)
			(pads allowed)
			(copperpour not_allowed)
			(footprints allowed)
		)
		(placement
			(enabled no)
			(sheetname "")
		)
		(fill
			(thermal_gap 0.5)
			(thermal_bridge_width 0.5)
			(island_removal_mode 0)
		)
		(polygon
			(pts
				(arc
					(start 27.18054 -119.20347)
					(mid 26.67 -118.69293)
					(end 26.15946 -119.20347)
				)
				(xy 26.15946 -119.35714) (xy 26.374852 -119.35714)
				(arc
					(start 26.424382 -119.30761)
					(mid 26.858644 -119.014826)
					(end 26.56586 -119.449088)
				)
				(xy 26.457656 -119.557292) (xy 26.15946 -119.557292) (xy 26.15946 -119.662194) (xy 26.457402 -119.662194)
				(arc
					(start 26.56586 -119.770652)
					(mid 26.858644 -120.204914)
					(end 26.424382 -119.91213)
				)
				(xy 26.374598 -119.862346) (xy 26.15946 -119.862346)
				(arc
					(start 26.15946 -120.016016)
					(mid 26.669873 -120.52681)
					(end 27.18054 -120.01627)
				)
			)
		)
	)
	(zone
		(net "GND")
		(layer "F.Cu")
		(hatch none 0.5)
		(connect_pads
			(clearance 0.5)
		)
		(min_thickness 0.25)
		(fill yes
			(thermal_gap 0.5)
			(thermal_bridge_width 0.5)
			(island_removal_mode 0)
		)
		(polygon
			(pts
				(xy 218.2876 -393.0904) (xy 218.059 -393.319) (xy 218.059 -394.6398) (xy 218.4146 -394.9954) (xy 222.4278 -394.9954)
				(xy 222.5294 -394.8938) (xy 222.5294 -393.2936) (xy 222.3262 -393.0904)
			)
		)
		(polygon
			(pts
				(xy 221.8436 -394.2842) (xy 221.6404 -394.2842) (xy 221.6404 -394.4874) (xy 221.8436 -394.4874)
			)
		)
	)
	(zone
		(layer "F.Cu")
		(hatch none 0.5)
		(connect_pads
			(clearance 0)
		)
		(min_thickness 0.25)
		(keepout
			(tracks allowed)
			(vias allowed)
			(pads allowed)
			(copperpour allowed)
			(footprints allowed)
		)
		(placement
			(enabled no)
			(sheetname "")
		)
		(fill
			(thermal_gap 0.5)
			(thermal_bridge_width 0.5)
			(island_removal_mode 0)
		)
		(polygon
			(pts
				(xy 17.78 -342.773) (xy 17.78 -340.487) (xy 19.939 -340.487) (xy 19.939 -342.773)
			)
		)
	)
	(zone
		(layer "F.Cu")
		(hatch none 0.5)
		(connect_pads
			(clearance 0)
		)
		(min_thickness 0.25)
		(keepout
			(tracks not_allowed)
			(vias allowed)
			(pads allowed)
			(copperpour not_allowed)
			(footprints allowed)
		)
		(placement
			(enabled no)
			(sheetname "")
		)
		(fill
			(thermal_gap 0.5)
			(thermal_bridge_width 0.5)
			(island_removal_mode 0)
		)
		(polygon
			(pts
				(arc
					(start 35.84067 -363.583982)
					(mid 35.330257 -363.073188)
					(end 34.81959 -363.583728)
				)
				(arc
					(start 34.81959 -364.396528)
					(mid 35.33013 -364.907068)
					(end 35.84067 -364.396528)
				)
				(xy 35.84067 -364.242858) (xy 35.625278 -364.242858)
				(arc
					(start 35.575748 -364.292388)
					(mid 35.141486 -364.585172)
					(end 35.43427 -364.15091)
				)
				(xy 35.542474 -364.042706) (xy 35.84067 -364.042706) (xy 35.84067 -363.937804) (xy 35.542728 -363.937804)
				(arc
					(start 35.43427 -363.829346)
					(mid 35.141486 -363.395084)
					(end 35.575748 -363.687868)
				)
				(xy 35.625532 -363.737652) (xy 35.84067 -363.737652)
			)
		)
	)
	(zone
		(layer "F.Cu")
		(hatch none 0.5)
		(connect_pads
			(clearance 0)
		)
		(min_thickness 0.25)
		(keepout
			(tracks not_allowed)
			(vias allowed)
			(pads allowed)
			(copperpour not_allowed)
			(footprints allowed)
		)
		(placement
			(enabled no)
			(sheetname "")
		)
		(fill
			(thermal_gap 0.5)
			(thermal_bridge_width 0.5)
			(island_removal_mode 0)
		)
		(polygon
			(pts
				(arc
					(start 27.18054 -227.00361)
					(mid 26.67 -226.49307)
					(end 26.15946 -227.00361)
				)
				(xy 26.15946 -227.15728) (xy 26.374852 -227.15728)
				(arc
					(start 26.424382 -227.10775)
					(mid 26.858644 -226.814966)
					(end 26.56586 -227.249228)
				)
				(xy 26.457656 -227.357432) (xy 26.15946 -227.357432) (xy 26.15946 -227.462334) (xy 26.457402 -227.462334)
				(arc
					(start 26.56586 -227.570792)
					(mid 26.858644 -228.005054)
					(end 26.424382 -227.71227)
				)
				(xy 26.374598 -227.662486) (xy 26.15946 -227.662486)
				(arc
					(start 26.15946 -227.816156)
					(mid 26.669873 -228.32695)
					(end 27.18054 -227.81641)
				)
			)
		)
	)
	(zone
		(layer "F.Cu")
		(hatch none 0.5)
		(connect_pads
			(clearance 0)
		)
		(min_thickness 0.25)
		(keepout
			(tracks not_allowed)
			(vias allowed)
			(pads allowed)
			(copperpour not_allowed)
			(footprints allowed)
		)
		(placement
			(enabled no)
			(sheetname "")
		)
		(fill
			(thermal_gap 0.5)
			(thermal_bridge_width 0.5)
			(island_removal_mode 0)
		)
		(polygon
			(pts
				(arc
					(start 74.269854 -429.61306)
					(mid 73.75906 -430.123473)
					(end 74.2696 -430.63414)
				)
				(xy 74.43597 -430.63414) (xy 74.43597 -430.431448)
				(arc
					(start 74.37374 -430.369218)
					(mid 74.080956 -429.934956)
					(end 74.515218 -430.22774)
				)
				(xy 74.636122 -430.348644) (xy 74.636122 -430.63414) (xy 74.741024 -430.63414) (xy 74.741024 -430.323498)
				(arc
					(start 74.836782 -430.22774)
					(mid 75.271044 -429.934956)
					(end 74.97826 -430.369218)
				)
				(xy 74.941176 -430.406302) (xy 74.941176 -430.63414)
				(arc
					(start 75.0824 -430.63414)
					(mid 75.59294 -430.1236)
					(end 75.0824 -429.61306)
				)
			)
		)
	)
	(zone
		(net "GND")
		(layer "F.Cu")
		(hatch none 0.5)
		(connect_pads
			(clearance 0.5)
		)
		(min_thickness 0.25)
		(fill yes
			(thermal_gap 0.5)
			(thermal_bridge_width 0.5)
			(island_removal_mode 0)
		)
		(polygon
			(pts
				(xy 218.3511 -84.0867) (xy 218.1352 -84.3026) (xy 218.1352 -85.6996) (xy 218.2622 -85.8266) (xy 222.5294 -85.8266)
				(xy 222.7326 -85.6234) (xy 222.7326 -84.2772) (xy 222.5421 -84.0867)
			)
		)
		(polygon
			(pts
				(xy 222.4532 -85.1154) (xy 222.25 -85.1154) (xy 222.25 -85.3186) (xy 222.4532 -85.3186)
			)
		)
		(polygon
			(pts
				(xy 221.8436 -85.1154) (xy 221.6404 -85.1154) (xy 221.6404 -85.3186) (xy 221.8436 -85.3186)
			)
		)
	)
	(zone
		(net "P3V3")
		(layer "F.Cu")
		(hatch none 0.5)
		(connect_pads
			(clearance 0.5)
		)
		(min_thickness 0.25)
		(fill yes
			(thermal_gap 0.5)
			(thermal_bridge_width 0.5)
			(island_removal_mode 0)
		)
		(polygon
			(pts
				(xy 24.511 -256.6416) (xy 24.1554 -256.9972) (xy 24.1554 -260.9342) (xy 24.3586 -261.1374) (xy 25.5524 -261.1374)
				(xy 26.0604 -260.6294) (xy 26.0604 -257.175) (xy 25.527 -256.6416)
			)
		)
		(polygon
			(pts
				(xy 24.8158 -260.651752) (xy 24.6126 -260.651752) (xy 24.6126 -260.854952) (xy 24.8158 -260.854952)
			)
		)
		(polygon
			(pts
				(xy 24.8158 -260.092952) (xy 24.6126 -260.092952) (xy 24.6126 -260.296152) (xy 24.8158 -260.296152)
			)
		)
		(polygon
			(pts
				(xy 24.8158 -259.5118) (xy 24.6126 -259.5118) (xy 24.6126 -259.715) (xy 24.8158 -259.715)
			)
		)
		(polygon
			(pts
				(xy 24.8158 -258.953) (xy 24.6126 -258.953) (xy 24.6126 -259.1562) (xy 24.8158 -259.1562)
			)
		)
		(polygon
			(pts
				(xy 24.8158 -258.3688) (xy 24.6126 -258.3688) (xy 24.6126 -258.572) (xy 24.8158 -258.572)
			)
		)
		(polygon
			(pts
				(xy 24.8158 -257.81) (xy 24.6126 -257.81) (xy 24.6126 -258.0132) (xy 24.8158 -258.0132)
			)
		)
	)
	(zone
		(net "GND")
		(layer "F.Cu")
		(hatch none 0.5)
		(connect_pads
			(clearance 0.5)
		)
		(min_thickness 0.25)
		(fill yes
			(thermal_gap 0.5)
			(thermal_bridge_width 0.5)
			(island_removal_mode 0)
		)
		(polygon
			(pts
				(xy 105.918 -167.259) (xy 100.584 -172.593) (xy 100.584 -200.787) (xy 102.108 -202.311) (xy 108.331 -202.311)
				(xy 109.474 -201.168) (xy 109.474 -168.402) (xy 108.331 -167.259)
			)
		)
	)
	(zone
		(net "GND")
		(layer "F.Cu")
		(hatch none 0.5)
		(connect_pads
			(clearance 0.5)
		)
		(min_thickness 0.25)
		(fill yes
			(thermal_gap 0.5)
			(thermal_bridge_width 0.5)
			(island_removal_mode 0)
		)
		(polygon
			(pts
				(xy 24.5618 -411.8102) (xy 24.13 -412.242) (xy 24.13 -414.02) (xy 24.257 -414.147) (xy 27.8638 -414.147)
				(xy 28.1178 -413.893) (xy 28.1178 -412.2928) (xy 27.6352 -411.8102)
			)
		)
		(polygon
			(pts
				(xy 27.2542 -413.0294) (xy 27.051 -413.0294) (xy 27.051 -413.2326) (xy 27.2542 -413.2326)
			)
		)
	)
	(zone
		(layer "F.Cu")
		(hatch none 0.5)
		(connect_pads
			(clearance 0)
		)
		(min_thickness 0.25)
		(keepout
			(tracks not_allowed)
			(vias allowed)
			(pads allowed)
			(copperpour not_allowed)
			(footprints allowed)
		)
		(placement
			(enabled no)
			(sheetname "")
		)
		(fill
			(thermal_gap 0.5)
			(thermal_bridge_width 0.5)
			(island_removal_mode 0)
		)
		(polygon
			(pts
				(arc
					(start 42.92854 -238.58474)
					(mid 42.418127 -238.073946)
					(end 41.90746 -238.584486)
				)
				(arc
					(start 41.90746 -239.397286)
					(mid 42.418 -239.907826)
					(end 42.92854 -239.397286)
				)
				(xy 42.92854 -239.243108) (xy 42.713656 -239.243108)
				(arc
					(start 42.663618 -239.293146)
					(mid 42.229356 -239.58593)
					(end 42.52214 -239.151668)
				)
				(xy 42.630852 -239.042956) (xy 42.92854 -239.042956) (xy 42.92854 -238.938054) (xy 42.63009 -238.938054)
				(arc
					(start 42.52214 -238.830104)
					(mid 42.229356 -238.395842)
					(end 42.663618 -238.688626)
				)
				(xy 42.712894 -238.737902) (xy 42.92854 -238.737902)
			)
		)
	)
	(zone
		(layer "F.Cu")
		(hatch none 0.5)
		(connect_pads
			(clearance 0)
		)
		(min_thickness 0.25)
		(keepout
			(tracks not_allowed)
			(vias allowed)
			(pads allowed)
			(copperpour not_allowed)
			(footprints allowed)
		)
		(placement
			(enabled no)
			(sheetname "")
		)
		(fill
			(thermal_gap 0.5)
			(thermal_bridge_width 0.5)
			(island_removal_mode 0)
		)
		(polygon
			(pts
				(arc
					(start 25.88514 -448.051428)
					(mid 25.273127 -447.439034)
					(end 24.66086 -448.051174)
				)
				(xy 24.66086 -448.382898) (xy 24.799798 -448.382898)
				(arc
					(start 25.027382 -448.155314)
					(mid 25.461644 -447.86253)
					(end 25.16886 -448.296792)
				)
				(xy 24.882602 -448.58305) (xy 24.66086 -448.58305) (xy 24.66086 -448.687952) (xy 24.933656 -448.687952)
				(arc
					(start 25.16886 -448.923156)
					(mid 25.461644 -449.357418)
					(end 25.027382 -449.064634)
				)
				(xy 24.850852 -448.888104) (xy 24.66086 -448.888104)
				(arc
					(start 24.66086 -449.168774)
					(mid 25.273 -449.780914)
					(end 25.88514 -449.168774)
				)
			)
		)
	)
	(zone
		(layer "F.Cu")
		(hatch none 0.5)
		(connect_pads
			(clearance 0)
		)
		(min_thickness 0.25)
		(keepout
			(tracks allowed)
			(vias allowed)
			(pads allowed)
			(copperpour allowed)
			(footprints allowed)
		)
		(placement
			(enabled no)
			(sheetname "")
		)
		(fill
			(thermal_gap 0.5)
			(thermal_bridge_width 0.5)
			(island_removal_mode 0)
		)
		(polygon
			(pts
				(xy 226.9744 -240.157) (xy 226.9744 -241.0206) (xy 225.7806 -241.0206) (xy 225.7806 -240.157)
			)
		)
	)
	(zone
		(layer "F.Cu")
		(hatch none 0.5)
		(connect_pads
			(clearance 0)
		)
		(min_thickness 0.25)
		(keepout
			(tracks not_allowed)
			(vias allowed)
			(pads allowed)
			(copperpour not_allowed)
			(footprints allowed)
		)
		(placement
			(enabled no)
			(sheetname "")
		)
		(fill
			(thermal_gap 0.5)
			(thermal_bridge_width 0.5)
			(island_removal_mode 0)
		)
		(polygon
			(pts
				(arc
					(start 35.84067 -381.183896)
					(mid 35.330257 -380.673102)
					(end 34.81959 -381.183642)
				)
				(arc
					(start 34.81959 -381.996442)
					(mid 35.33013 -382.506982)
					(end 35.84067 -381.996442)
				)
				(xy 35.84067 -381.842772) (xy 35.625278 -381.842772)
				(arc
					(start 35.575748 -381.892302)
					(mid 35.141486 -382.185086)
					(end 35.43427 -381.750824)
				)
				(xy 35.542474 -381.64262) (xy 35.84067 -381.64262) (xy 35.84067 -381.537718) (xy 35.542728 -381.537718)
				(arc
					(start 35.43427 -381.42926)
					(mid 35.141486 -380.994998)
					(end 35.575748 -381.287782)
				)
				(xy 35.625532 -381.337566) (xy 35.84067 -381.337566)
			)
		)
	)
	(zone
		(layer "F.Cu")
		(hatch none 0.5)
		(connect_pads
			(clearance 0)
		)
		(min_thickness 0.25)
		(keepout
			(tracks allowed)
			(vias allowed)
			(pads allowed)
			(copperpour allowed)
			(footprints allowed)
		)
		(placement
			(enabled no)
			(sheetname "")
		)
		(fill
			(thermal_gap 0.5)
			(thermal_bridge_width 0.5)
			(island_removal_mode 0)
		)
		(polygon
			(pts
				(xy 24.638 -114.046) (xy 24.638 -130.683) (xy 22.479 -130.683) (xy 22.479 -114.046)
			)
		)
	)
	(zone
		(layer "F.Cu")
		(hatch none 0.5)
		(connect_pads
			(clearance 0)
		)
		(min_thickness 0.25)
		(keepout
			(tracks not_allowed)
			(vias allowed)
			(pads allowed)
			(copperpour not_allowed)
			(footprints allowed)
		)
		(placement
			(enabled no)
			(sheetname "")
		)
		(fill
			(thermal_gap 0.5)
			(thermal_bridge_width 0.5)
			(island_removal_mode 0)
		)
		(polygon
			(pts
				(arc
					(start 7.502906 -343.58707)
					(mid 6.992493 -343.076276)
					(end 6.481826 -343.586816)
				)
				(xy 6.481826 -343.740232) (xy 6.697472 -343.740232)
				(arc
					(start 6.746748 -343.690956)
					(mid 7.18101 -343.398172)
					(end 6.888226 -343.832434)
				)
				(xy 6.780276 -343.940384) (xy 6.481826 -343.940384) (xy 6.481826 -344.045286) (xy 6.779514 -344.045286)
				(arc
					(start 6.888226 -344.153998)
					(mid 7.18101 -344.58826)
					(end 6.746748 -344.295476)
				)
				(xy 6.69671 -344.245438) (xy 6.481826 -344.245438)
				(arc
					(start 6.481826 -344.399616)
					(mid 6.992366 -344.910156)
					(end 7.502906 -344.399616)
				)
			)
		)
	)
	(zone
		(layer "F.Cu")
		(hatch none 0.5)
		(connect_pads
			(clearance 0)
		)
		(min_thickness 0.25)
		(keepout
			(tracks not_allowed)
			(vias allowed)
			(pads allowed)
			(copperpour not_allowed)
			(footprints allowed)
		)
		(placement
			(enabled no)
			(sheetname "")
		)
		(fill
			(thermal_gap 0.5)
			(thermal_bridge_width 0.5)
			(island_removal_mode 0)
		)
		(polygon
			(pts
				(arc
					(start 222.339154 -378.63145)
					(mid 221.727141 -378.019056)
					(end 221.114874 -378.631196)
				)
				(arc
					(start 221.114874 -379.748796)
					(mid 221.727014 -380.360936)
					(end 222.339154 -379.748796)
				)
				(xy 222.339154 -379.442726) (xy 222.174562 -379.442726)
				(arc
					(start 221.972632 -379.644656)
					(mid 221.53837 -379.93744)
					(end 221.831154 -379.503178)
				)
				(xy 222.091758 -379.242574) (xy 222.339154 -379.242574) (xy 222.339154 -379.137672) (xy 222.092012 -379.137672)
				(arc
					(start 221.831154 -378.876814)
					(mid 221.53837 -378.442552)
					(end 221.972632 -378.735336)
				)
				(xy 222.174816 -378.93752) (xy 222.339154 -378.93752)
			)
		)
	)
	(zone
		(layer "F.Cu")
		(hatch none 0.5)
		(connect_pads
			(clearance 0)
		)
		(min_thickness 0.25)
		(keepout
			(tracks not_allowed)
			(vias allowed)
			(pads allowed)
			(copperpour not_allowed)
			(footprints allowed)
		)
		(placement
			(enabled no)
			(sheetname "")
		)
		(fill
			(thermal_gap 0.5)
			(thermal_bridge_width 0.5)
			(island_removal_mode 0)
		)
		(polygon
			(pts
				(xy 97.81921 -308.59603) (xy 97.81921 -308.684676) (xy 97.819464 -308.68493) (xy 98.98761 -308.68493)
				(xy 98.98761 -308.59603)
			)
		)
	)
	(zone
		(layer "F.Cu")
		(hatch none 0.5)
		(connect_pads
			(clearance 0)
		)
		(min_thickness 0.25)
		(keepout
			(tracks not_allowed)
			(vias allowed)
			(pads allowed)
			(copperpour not_allowed)
			(footprints allowed)
		)
		(placement
			(enabled no)
			(sheetname "")
		)
		(fill
			(thermal_gap 0.5)
			(thermal_bridge_width 0.5)
			(island_removal_mode 0)
		)
		(polygon
			(pts
				(arc
					(start 7.502906 -390.336024)
					(mid 6.992493 -389.82523)
					(end 6.481826 -390.33577)
				)
				(xy 6.481826 -390.489186) (xy 6.697472 -390.489186)
				(arc
					(start 6.746748 -390.43991)
					(mid 7.18101 -390.147126)
					(end 6.888226 -390.581388)
				)
				(xy 6.780276 -390.689338) (xy 6.481826 -390.689338) (xy 6.481826 -390.79424) (xy 6.779514 -390.79424)
				(arc
					(start 6.888226 -390.902952)
					(mid 7.18101 -391.337214)
					(end 6.746748 -391.04443)
				)
				(xy 6.69671 -390.994392) (xy 6.481826 -390.994392)
				(arc
					(start 6.481826 -391.14857)
					(mid 6.992366 -391.65911)
					(end 7.502906 -391.14857)
				)
			)
		)
	)
	(zone
		(layer "F.Cu")
		(hatch none 0.5)
		(connect_pads
			(clearance 0)
		)
		(min_thickness 0.25)
		(keepout
			(tracks allowed)
			(vias allowed)
			(pads allowed)
			(copperpour allowed)
			(footprints allowed)
		)
		(placement
			(enabled no)
			(sheetname "")
		)
		(fill
			(thermal_gap 0.5)
			(thermal_bridge_width 0.5)
			(island_removal_mode 0)
		)
		(polygon
			(pts
				(xy 24.638 -344.043) (xy 24.638 -351.155) (xy 22.479 -351.155) (xy 22.479 -344.043)
			)
		)
	)
	(zone
		(layer "F.Cu")
		(hatch none 0.5)
		(connect_pads
			(clearance 0)
		)
		(min_thickness 0.25)
		(keepout
			(tracks not_allowed)
			(vias allowed)
			(pads allowed)
			(copperpour not_allowed)
			(footprints allowed)
		)
		(placement
			(enabled no)
			(sheetname "")
		)
		(fill
			(thermal_gap 0.5)
			(thermal_bridge_width 0.5)
			(island_removal_mode 0)
		)
		(polygon
			(pts
				(arc
					(start 6.477254 -448.957192)
					(mid 5.96646 -449.467605)
					(end 6.477 -449.978272)
				)
				(arc
					(start 7.2898 -449.978272)
					(mid 7.80034 -449.467732)
					(end 7.2898 -448.957192)
				)
				(xy 7.135876 -448.957192) (xy 7.135876 -449.17233)
				(arc
					(start 7.18566 -449.222114)
					(mid 7.478444 -449.656376)
					(end 7.044182 -449.363592)
				)
				(xy 6.935724 -449.255134) (xy 6.935724 -448.957192) (xy 6.830822 -448.957192) (xy 6.830822 -449.255388)
				(arc
					(start 6.722618 -449.363592)
					(mid 6.288356 -449.656376)
					(end 6.58114 -449.222114)
				)
				(xy 6.63067 -449.172584) (xy 6.63067 -448.957192)
			)
		)
	)
	(zone
		(layer "F.Cu")
		(hatch none 0.5)
		(connect_pads
			(clearance 0)
		)
		(min_thickness 0.25)
		(keepout
			(tracks allowed)
			(vias allowed)
			(pads allowed)
			(copperpour allowed)
			(footprints allowed)
		)
		(placement
			(enabled no)
			(sheetname "")
		)
		(fill
			(thermal_gap 0.5)
			(thermal_bridge_width 0.5)
			(island_removal_mode 0)
		)
		(polygon
			(pts
				(xy 24.638 -217.043) (xy 24.638 -233.68) (xy 22.479 -233.68) (xy 22.479 -217.043)
			)
		)
	)
	(zone
		(layer "F.Cu")
		(hatch none 0.5)
		(connect_pads
			(clearance 0)
		)
		(min_thickness 0.25)
		(keepout
			(tracks not_allowed)
			(vias allowed)
			(pads allowed)
			(copperpour not_allowed)
			(footprints allowed)
		)
		(placement
			(enabled no)
			(sheetname "")
		)
		(fill
			(thermal_gap 0.5)
			(thermal_bridge_width 0.5)
			(island_removal_mode 0)
		)
		(polygon
			(pts
				(arc
					(start 220.840554 -484.183944)
					(mid 220.330141 -483.67315)
					(end 219.819474 -484.18369)
				)
				(arc
					(start 219.819474 -484.99649)
					(mid 220.330014 -485.50703)
					(end 220.840554 -484.99649)
				)
				(xy 220.840554 -484.84282) (xy 220.625162 -484.84282)
				(arc
					(start 220.575632 -484.89235)
					(mid 220.14137 -485.185134)
					(end 220.434154 -484.750872)
				)
				(xy 220.542358 -484.642668) (xy 220.840554 -484.642668) (xy 220.840554 -484.537766) (xy 220.542612 -484.537766)
				(arc
					(start 220.434154 -484.429308)
					(mid 220.14137 -483.995046)
					(end 220.575632 -484.28783)
				)
				(xy 220.625416 -484.337614) (xy 220.840554 -484.337614)
			)
		)
	)
	(zone
		(layer "F.Cu")
		(hatch none 0.5)
		(connect_pads
			(clearance 0)
		)
		(min_thickness 0.25)
		(keepout
			(tracks not_allowed)
			(vias allowed)
			(pads allowed)
			(copperpour not_allowed)
			(footprints allowed)
		)
		(placement
			(enabled no)
			(sheetname "")
		)
		(fill
			(thermal_gap 0.5)
			(thermal_bridge_width 0.5)
			(island_removal_mode 0)
		)
		(polygon
			(pts
				(arc
					(start 7.502906 -152.786842)
					(mid 6.992493 -152.276048)
					(end 6.481826 -152.786588)
				)
				(xy 6.481826 -152.940258) (xy 6.697218 -152.940258)
				(arc
					(start 6.746748 -152.890728)
					(mid 7.18101 -152.597944)
					(end 6.888226 -153.032206)
				)
				(xy 6.780022 -153.14041) (xy 6.481826 -153.14041) (xy 6.481826 -153.245312) (xy 6.779768 -153.245312)
				(arc
					(start 6.888226 -153.35377)
					(mid 7.18101 -153.788032)
					(end 6.746748 -153.495248)
				)
				(xy 6.696964 -153.445464) (xy 6.481826 -153.445464)
				(arc
					(start 6.481826 -153.599388)
					(mid 6.992366 -154.109928)
					(end 7.502906 -153.599388)
				)
			)
		)
	)
	(zone
		(layer "F.Cu")
		(hatch none 0.5)
		(connect_pads
			(clearance 0)
		)
		(min_thickness 0.25)
		(keepout
			(tracks not_allowed)
			(vias allowed)
			(pads allowed)
			(copperpour not_allowed)
			(footprints allowed)
		)
		(placement
			(enabled no)
			(sheetname "")
		)
		(fill
			(thermal_gap 0.5)
			(thermal_bridge_width 0.5)
			(island_removal_mode 0)
		)
		(polygon
			(pts
				(arc
					(start 7.502906 -195.936108)
					(mid 6.992493 -195.425314)
					(end 6.481826 -195.935854)
				)
				(xy 6.481826 -196.08927) (xy 6.697472 -196.08927)
				(arc
					(start 6.746748 -196.039994)
					(mid 7.18101 -195.74721)
					(end 6.888226 -196.181472)
				)
				(xy 6.780276 -196.289422) (xy 6.481826 -196.289422) (xy 6.481826 -196.394324) (xy 6.779514 -196.394324)
				(arc
					(start 6.888226 -196.503036)
					(mid 7.18101 -196.937298)
					(end 6.746748 -196.644514)
				)
				(xy 6.69671 -196.594476) (xy 6.481826 -196.594476)
				(arc
					(start 6.481826 -196.748654)
					(mid 6.992366 -197.259194)
					(end 7.502906 -196.748654)
				)
			)
		)
	)
	(zone
		(layer "F.Cu")
		(hatch none 0.5)
		(connect_pads
			(clearance 0)
		)
		(min_thickness 0.25)
		(keepout
			(tracks not_allowed)
			(vias allowed)
			(pads allowed)
			(copperpour not_allowed)
			(footprints allowed)
		)
		(placement
			(enabled no)
			(sheetname "")
		)
		(fill
			(thermal_gap 0.5)
			(thermal_bridge_width 0.5)
			(island_removal_mode 0)
		)
		(polygon
			(pts
				(xy 92.89542 -214.65921) (xy 92.98432 -214.65921) (xy 92.98432 -215.82761) (xy 92.89542 -215.82761)
			)
		)
	)
	(zone
		(layer "F.Cu")
		(hatch none 0.5)
		(connect_pads
			(clearance 0)
		)
		(min_thickness 0.25)
		(keepout
			(tracks not_allowed)
			(vias allowed)
			(pads allowed)
			(copperpour not_allowed)
			(footprints allowed)
		)
		(placement
			(enabled no)
			(sheetname "")
		)
		(fill
			(thermal_gap 0.5)
			(thermal_bridge_width 0.5)
			(island_removal_mode 0)
		)
		(polygon
			(pts
				(xy 97.39503 -214.65921) (xy 97.48393 -214.65921) (xy 97.48393 -215.82761) (xy 97.39503 -215.82761)
			)
		)
	)
	(zone
		(layer "F.Cu")
		(hatch none 0.5)
		(connect_pads
			(clearance 0)
		)
		(min_thickness 0.25)
		(keepout
			(tracks not_allowed)
			(vias allowed)
			(pads allowed)
			(copperpour not_allowed)
			(footprints allowed)
		)
		(placement
			(enabled no)
			(sheetname "")
		)
		(fill
			(thermal_gap 0.5)
			(thermal_bridge_width 0.5)
			(island_removal_mode 0)
		)
		(polygon
			(pts
				(xy 92.89542 -309.02021) (xy 92.98432 -309.02021) (xy 92.98432 -310.18861) (xy 92.89542 -310.18861)
			)
		)
	)
	(zone
		(layer "F.Cu")
		(hatch none 0.5)
		(connect_pads
			(clearance 0)
		)
		(min_thickness 0.25)
		(keepout
			(tracks not_allowed)
			(vias allowed)
			(pads allowed)
			(copperpour not_allowed)
			(footprints allowed)
		)
		(placement
			(enabled no)
			(sheetname "")
		)
		(fill
			(thermal_gap 0.5)
			(thermal_bridge_width 0.5)
			(island_removal_mode 0)
		)
		(polygon
			(pts
				(arc
					(start 27.18054 -222.203518)
					(mid 26.67 -221.692978)
					(end 26.15946 -222.203518)
				)
				(xy 26.15946 -222.357188) (xy 26.374852 -222.357188)
				(arc
					(start 26.424382 -222.307658)
					(mid 26.858644 -222.014874)
					(end 26.56586 -222.449136)
				)
				(xy 26.457656 -222.55734) (xy 26.15946 -222.55734) (xy 26.15946 -222.662242) (xy 26.457402 -222.662242)
				(arc
					(start 26.56586 -222.7707)
					(mid 26.858644 -223.204962)
					(end 26.424382 -222.912178)
				)
				(xy 26.374598 -222.862394) (xy 26.15946 -222.862394)
				(arc
					(start 26.15946 -223.016064)
					(mid 26.669873 -223.526858)
					(end 27.18054 -223.016318)
				)
			)
		)
	)
	(zone
		(net "P12V")
		(layer "F.Cu")
		(hatch none 0.5)
		(connect_pads
			(clearance 0.5)
		)
		(min_thickness 0.25)
		(fill yes
			(thermal_gap 0.5)
			(thermal_bridge_width 0.5)
			(island_removal_mode 0)
		)
		(polygon
			(pts
				(xy 252.349 -360.6546) (xy 252.1712 -360.8324) (xy 251.1298 -360.8324) (xy 250.6472 -361.315) (xy 237.363 -361.315)
				(xy 236.728 -361.95) (xy 236.728 -383.413) (xy 236.9058 -383.5908) (xy 249.174 -383.5908) (xy 249.3772 -383.794)
				(xy 258.953 -383.794) (xy 259.08 -383.667) (xy 259.08 -364.236) (xy 256.3114 -361.4674) (xy 253.7206 -361.4674)
				(xy 252.9078 -360.6546)
			)
		)
		(polygon
			(pts
				(xy 252.1204 -361.5944) (xy 251.9172 -361.5944) (xy 251.9172 -361.7976) (xy 252.1204 -361.7976)
			)
		)
		(polygon
			(pts
				(xy 251.2568 -361.5944) (xy 251.0536 -361.5944) (xy 251.0536 -361.7976) (xy 251.2568 -361.7976)
			)
		)
		(polygon
			(pts
				(xy 253.0348 -361.1626) (xy 252.8316 -361.1626) (xy 252.8316 -361.3658) (xy 253.0348 -361.3658)
			)
		)
		(polygon
			(pts
				(xy 252.4252 -361.1626) (xy 252.222 -361.1626) (xy 252.222 -361.3658) (xy 252.4252 -361.3658)
			)
		)
	)
	(zone
		(layer "F.Cu")
		(hatch none 0.5)
		(connect_pads
			(clearance 0)
		)
		(min_thickness 0.25)
		(keepout
			(tracks allowed)
			(vias allowed)
			(pads allowed)
			(copperpour allowed)
			(footprints allowed)
		)
		(placement
			(enabled no)
			(sheetname "")
		)
		(fill
			(thermal_gap 0.5)
			(thermal_bridge_width 0.5)
			(island_removal_mode 0)
		)
		(polygon
			(pts
				(xy 24.638 -320.04) (xy 24.638 -336.677) (xy 22.479 -336.677) (xy 22.479 -320.04)
			)
		)
	)
	(zone
		(layer "F.Cu")
		(hatch none 0.5)
		(connect_pads
			(clearance 0)
		)
		(min_thickness 0.25)
		(keepout
			(tracks allowed)
			(vias allowed)
			(pads allowed)
			(copperpour allowed)
			(footprints allowed)
		)
		(placement
			(enabled no)
			(sheetname "")
		)
		(fill
			(thermal_gap 0.5)
			(thermal_bridge_width 0.5)
			(island_removal_mode 0)
		)
		(polygon
			(pts
				(xy 77.043788 -101.007418) (xy 77.043788 -99.508818) (xy 77.958188 -99.508818) (xy 77.958188 -101.007418)
			)
		)
	)
	(zone
		(net "GND")
		(layer "F.Cu")
		(hatch none 0.5)
		(connect_pads
			(clearance 0.5)
		)
		(min_thickness 0.25)
		(fill yes
			(thermal_gap 0.5)
			(thermal_bridge_width 0.5)
			(island_removal_mode 0)
		)
		(polygon
			(pts
				(xy 34.2138 -297.7642) (xy 34.036 -297.942) (xy 34.036 -299.72) (xy 34.417 -300.101) (xy 37.8968 -300.101)
				(xy 38.2524 -299.7454) (xy 38.2524 -297.8658) (xy 38.1508 -297.7642)
			)
		)
		(polygon
			(pts
				(xy 37.3888 -298.6024) (xy 37.1856 -298.6024) (xy 37.1856 -298.8056) (xy 37.3888 -298.8056)
			)
		)
	)
	(zone
		(layer "F.Cu")
		(hatch none 0.5)
		(connect_pads
			(clearance 0)
		)
		(min_thickness 0.25)
		(keepout
			(tracks not_allowed)
			(vias allowed)
			(pads allowed)
			(copperpour not_allowed)
			(footprints allowed)
		)
		(placement
			(enabled no)
			(sheetname "")
		)
		(fill
			(thermal_gap 0.5)
			(thermal_bridge_width 0.5)
			(island_removal_mode 0)
		)
		(polygon
			(pts
				(arc
					(start 25.88514 -121.451116)
					(mid 25.273 -120.838976)
					(end 24.66086 -121.451116)
				)
				(xy 24.66086 -121.757186) (xy 24.825452 -121.757186)
				(arc
					(start 25.027382 -121.555256)
					(mid 25.461644 -121.262472)
					(end 25.16886 -121.696734)
				)
				(xy 24.908256 -121.957338) (xy 24.66086 -121.957338) (xy 24.66086 -122.06224) (xy 24.908002 -122.06224)
				(arc
					(start 25.16886 -122.323098)
					(mid 25.461644 -122.75736)
					(end 25.027382 -122.464576)
				)
				(xy 24.825198 -122.262392) (xy 24.66086 -122.262392)
				(arc
					(start 24.66086 -122.568462)
					(mid 25.272873 -123.180856)
					(end 25.88514 -122.568716)
				)
			)
		)
	)
	(zone
		(layer "F.Cu")
		(hatch none 0.5)
		(connect_pads
			(clearance 0)
		)
		(min_thickness 0.25)
		(keepout
			(tracks not_allowed)
			(vias allowed)
			(pads allowed)
			(copperpour not_allowed)
			(footprints allowed)
		)
		(placement
			(enabled no)
			(sheetname "")
		)
		(fill
			(thermal_gap 0.5)
			(thermal_bridge_width 0.5)
			(island_removal_mode 0)
		)
		(polygon
			(pts
				(arc
					(start 7.502906 -402.335746)
					(mid 6.992366 -401.825206)
					(end 6.481826 -402.335746)
				)
				(xy 6.481826 -402.489162) (xy 6.697472 -402.489162)
				(arc
					(start 6.746748 -402.439886)
					(mid 7.18101 -402.147102)
					(end 6.888226 -402.581364)
				)
				(xy 6.780276 -402.689314) (xy 6.481826 -402.689314) (xy 6.481826 -402.794216) (xy 6.779514 -402.794216)
				(arc
					(start 6.888226 -402.902928)
					(mid 7.18101 -403.33719)
					(end 6.746748 -403.044406)
				)
				(xy 6.69671 -402.994368) (xy 6.481826 -402.994368)
				(arc
					(start 6.481826 -403.148292)
					(mid 6.992239 -403.659086)
					(end 7.502906 -403.148546)
				)
			)
		)
	)
	(zone
		(layer "F.Cu")
		(hatch none 0.5)
		(connect_pads
			(clearance 0)
		)
		(min_thickness 0.25)
		(keepout
			(tracks not_allowed)
			(vias allowed)
			(pads allowed)
			(copperpour not_allowed)
			(footprints allowed)
		)
		(placement
			(enabled no)
			(sheetname "")
		)
		(fill
			(thermal_gap 0.5)
			(thermal_bridge_width 0.5)
			(island_removal_mode 0)
		)
		(polygon
			(pts
				(arc
					(start 7.502906 -424.78452)
					(mid 6.992493 -424.273726)
					(end 6.481826 -424.784266)
				)
				(xy 6.481826 -424.91787) (xy 6.717284 -424.91787)
				(arc
					(start 6.746748 -424.888406)
					(mid 7.18101 -424.595622)
					(end 6.888226 -425.029884)
				)
				(xy 6.800088 -425.118022) (xy 6.481826 -425.118022) (xy 6.481826 -425.222924) (xy 6.759702 -425.222924)
				(arc
					(start 6.888226 -425.351448)
					(mid 7.18101 -425.78571)
					(end 6.746748 -425.492926)
				)
				(xy 6.676898 -425.423076) (xy 6.481826 -425.423076)
				(arc
					(start 6.481826 -425.597066)
					(mid 6.992366 -426.107606)
					(end 7.502906 -425.597066)
				)
			)
		)
	)
	(zone
		(layer "F.Cu")
		(hatch none 0.5)
		(connect_pads
			(clearance 0)
		)
		(min_thickness 0.25)
		(keepout
			(tracks allowed)
			(vias allowed)
			(pads allowed)
			(copperpour allowed)
			(footprints allowed)
		)
		(placement
			(enabled no)
			(sheetname "")
		)
		(fill
			(thermal_gap 0.5)
			(thermal_bridge_width 0.5)
			(island_removal_mode 0)
		)
		(polygon
			(pts
				(xy 222.377 -82.931) (xy 222.377 -66.294) (xy 224.536 -66.294) (xy 224.536 -82.931)
			)
		)
	)
	(zone
		(layer "F.Cu")
		(hatch none 0.5)
		(connect_pads
			(clearance 0)
		)
		(min_thickness 0.25)
		(keepout
			(tracks not_allowed)
			(vias allowed)
			(pads allowed)
			(copperpour not_allowed)
			(footprints allowed)
		)
		(placement
			(enabled no)
			(sheetname "")
		)
		(fill
			(thermal_gap 0.5)
			(thermal_bridge_width 0.5)
			(island_removal_mode 0)
		)
		(polygon
			(pts
				(arc
					(start 7.502906 -439.984134)
					(mid 6.992366 -439.473594)
					(end 6.481826 -439.984134)
				)
				(xy 6.481826 -440.137804) (xy 6.697218 -440.137804)
				(arc
					(start 6.746748 -440.088274)
					(mid 7.18101 -439.79549)
					(end 6.888226 -440.229752)
				)
				(xy 6.780022 -440.337956) (xy 6.481826 -440.337956) (xy 6.481826 -440.442858) (xy 6.779768 -440.442858)
				(arc
					(start 6.888226 -440.551316)
					(mid 7.18101 -440.985578)
					(end 6.746748 -440.692794)
				)
				(xy 6.696964 -440.64301) (xy 6.481826 -440.64301)
				(arc
					(start 6.481826 -440.79668)
					(mid 6.992239 -441.307474)
					(end 7.502906 -440.796934)
				)
			)
		)
	)
	(zone
		(layer "F.Cu")
		(hatch none 0.5)
		(connect_pads
			(clearance 0)
		)
		(min_thickness 0.25)
		(keepout
			(tracks allowed)
			(vias allowed)
			(pads allowed)
			(copperpour allowed)
			(footprints allowed)
		)
		(placement
			(enabled no)
			(sheetname "")
		)
		(fill
			(thermal_gap 0.5)
			(thermal_bridge_width 0.5)
			(island_removal_mode 0)
		)
		(polygon
			(pts
				(xy 7.239 -312.674) (xy 1.905 -312.674) (xy 1.905 -277.622) (xy 7.239 -277.622)
			)
		)
	)
	(zone
		(net "P12V")
		(layer "F.Cu")
		(hatch none 0.5)
		(connect_pads
			(clearance 0.5)
		)
		(min_thickness 0.25)
		(fill yes
			(thermal_gap 0.5)
			(thermal_bridge_width 0.5)
			(island_removal_mode 0)
		)
		(polygon
			(pts
				(xy 209.0166 -396.2654) (xy 208.915 -396.367) (xy 208.915 -396.875) (xy 209.042 -397.002) (xy 209.677 -397.002)
				(xy 209.9564 -397.2814) (xy 209.9564 -398.0434) (xy 210.312 -398.399) (xy 210.312 -399.796) (xy 211.074 -400.558)
				(xy 211.074 -401.955) (xy 212.386926 -403.267926) (xy 213.783926 -403.267926) (xy 213.924388 -403.127464)
				(xy 213.924388 -402.734018) (xy 215.011 -401.647406) (xy 215.011 -397.129) (xy 214.757 -396.875)
				(xy 211.328 -396.875) (xy 210.7184 -396.2654)
			)
		)
		(polygon
			(pts
				(xy 213.7791 -402.7043) (xy 213.5759 -402.7043) (xy 213.5759 -402.9075) (xy 213.7791 -402.9075)
			)
		)
		(polygon
			(pts
				(xy 213.2203 -402.7043) (xy 213.0171 -402.7043) (xy 213.0171 -402.9075) (xy 213.2203 -402.9075)
			)
		)
		(polygon
			(pts
				(xy 210.6168 -397.8148) (xy 210.4136 -397.8148) (xy 210.4136 -398.018) (xy 210.6168 -398.018)
			)
		)
		(polygon
			(pts
				(xy 210.6168 -397.256) (xy 210.4136 -397.256) (xy 210.4136 -397.4592) (xy 210.6168 -397.4592)
			)
		)
		(polygon
			(pts
				(xy 210.7184 -396.7734) (xy 210.5152 -396.7734) (xy 210.5152 -396.9766) (xy 210.7184 -396.9766)
			)
		)
		(polygon
			(pts
				(xy 210.1088 -396.7734) (xy 209.9056 -396.7734) (xy 209.9056 -396.9766) (xy 210.1088 -396.9766)
			)
		)
	)
	(zone
		(layer "F.Cu")
		(hatch none 0.5)
		(connect_pads
			(clearance 0)
		)
		(min_thickness 0.25)
		(keepout
			(tracks not_allowed)
			(vias allowed)
			(pads allowed)
			(copperpour not_allowed)
			(footprints allowed)
		)
		(placement
			(enabled no)
			(sheetname "")
		)
		(fill
			(thermal_gap 0.5)
			(thermal_bridge_width 0.5)
			(island_removal_mode 0)
		)
		(polygon
			(pts
				(arc
					(start 7.502906 -310.73598)
					(mid 6.992366 -310.22544)
					(end 6.481826 -310.73598)
				)
				(xy 6.481826 -310.889396) (xy 6.697472 -310.889396)
				(arc
					(start 6.746748 -310.84012)
					(mid 7.18101 -310.547336)
					(end 6.888226 -310.981598)
				)
				(xy 6.780276 -311.089548) (xy 6.481826 -311.089548) (xy 6.481826 -311.19445) (xy 6.779514 -311.19445)
				(arc
					(start 6.888226 -311.303162)
					(mid 7.18101 -311.737424)
					(end 6.746748 -311.44464)
				)
				(xy 6.69671 -311.394602) (xy 6.481826 -311.394602)
				(arc
					(start 6.481826 -311.548526)
					(mid 6.992239 -312.05932)
					(end 7.502906 -311.54878)
				)
			)
		)
	)
	(zone
		(layer "F.Cu")
		(hatch none 0.5)
		(connect_pads
			(clearance 0)
		)
		(min_thickness 0.25)
		(keepout
			(tracks not_allowed)
			(vias allowed)
			(pads allowed)
			(copperpour not_allowed)
			(footprints allowed)
		)
		(placement
			(enabled no)
			(sheetname "")
		)
		(fill
			(thermal_gap 0.5)
			(thermal_bridge_width 0.5)
			(island_removal_mode 0)
		)
		(polygon
			(pts
				(arc
					(start 7.502906 -288.336228)
					(mid 6.992493 -287.825434)
					(end 6.481826 -288.335974)
				)
				(xy 6.481826 -288.48939) (xy 6.697472 -288.48939)
				(arc
					(start 6.746748 -288.440114)
					(mid 7.18101 -288.14733)
					(end 6.888226 -288.581592)
				)
				(xy 6.780276 -288.689542) (xy 6.481826 -288.689542) (xy 6.481826 -288.794444) (xy 6.779514 -288.794444)
				(arc
					(start 6.888226 -288.903156)
					(mid 7.18101 -289.337418)
					(end 6.746748 -289.044634)
				)
				(xy 6.69671 -288.994596) (xy 6.481826 -288.994596)
				(arc
					(start 6.481826 -289.148774)
					(mid 6.992366 -289.659314)
					(end 7.502906 -289.148774)
				)
			)
		)
	)
	(zone
		(layer "F.Cu")
		(hatch none 0.5)
		(connect_pads
			(clearance 0)
		)
		(min_thickness 0.25)
		(keepout
			(tracks not_allowed)
			(vias allowed)
			(pads allowed)
			(copperpour not_allowed)
			(footprints allowed)
		)
		(placement
			(enabled no)
			(sheetname "")
		)
		(fill
			(thermal_gap 0.5)
			(thermal_bridge_width 0.5)
			(island_removal_mode 0)
		)
		(polygon
			(pts
				(arc
					(start 222.339154 -262.83158)
					(mid 221.727141 -262.219186)
					(end 221.114874 -262.831326)
				)
				(arc
					(start 221.114874 -263.948926)
					(mid 221.727014 -264.561066)
					(end 222.339154 -263.948926)
				)
				(xy 222.339154 -263.642602) (xy 222.174816 -263.642602)
				(arc
					(start 221.972632 -263.844786)
					(mid 221.53837 -264.13757)
					(end 221.831154 -263.703308)
				)
				(xy 222.092012 -263.44245) (xy 222.339154 -263.44245) (xy 222.339154 -263.337548) (xy 222.091758 -263.337548)
				(arc
					(start 221.831154 -263.076944)
					(mid 221.53837 -262.642682)
					(end 221.972632 -262.935466)
				)
				(xy 222.174562 -263.137396) (xy 222.339154 -263.137396)
			)
		)
	)
	(zone
		(layer "F.Cu")
		(hatch none 0.5)
		(connect_pads
			(clearance 0)
		)
		(min_thickness 0.25)
		(keepout
			(tracks not_allowed)
			(vias allowed)
			(pads allowed)
			(copperpour not_allowed)
			(footprints allowed)
		)
		(placement
			(enabled no)
			(sheetname "")
		)
		(fill
			(thermal_gap 0.5)
			(thermal_bridge_width 0.5)
			(island_removal_mode 0)
		)
		(polygon
			(pts
				(arc
					(start 7.502906 -230.33609)
					(mid 6.992493 -229.825296)
					(end 6.481826 -230.335836)
				)
				(xy 6.481826 -230.489252) (xy 6.697472 -230.489252)
				(arc
					(start 6.746748 -230.439976)
					(mid 7.18101 -230.147192)
					(end 6.888226 -230.581454)
				)
				(xy 6.780276 -230.689404) (xy 6.481826 -230.689404) (xy 6.481826 -230.794306) (xy 6.779514 -230.794306)
				(arc
					(start 6.888226 -230.903018)
					(mid 7.18101 -231.33728)
					(end 6.746748 -231.044496)
				)
				(xy 6.69671 -230.994458) (xy 6.481826 -230.994458)
				(arc
					(start 6.481826 -231.148636)
					(mid 6.992366 -231.659176)
					(end 7.502906 -231.148636)
				)
			)
		)
	)
	(zone
		(net "P12V")
		(layer "F.Cu")
		(hatch none 0.5)
		(connect_pads
			(clearance 0.5)
		)
		(min_thickness 0.25)
		(fill yes
			(thermal_gap 0.5)
			(thermal_bridge_width 0.5)
			(island_removal_mode 0)
		)
		(polygon
			(pts
				(xy 222.242126 -418.806122) (xy 222.029528 -419.01872) (xy 222.029528 -422.531794) (xy 222.242888 -422.745154)
				(xy 224.05467 -422.745154) (xy 224.371662 -422.428162) (xy 224.371662 -419.041326) (xy 224.136458 -418.806122)
			)
		)
	)
	(zone
		(net "GND")
		(layer "F.Cu")
		(hatch none 0.5)
		(connect_pads
			(clearance 0.5)
		)
		(min_thickness 0.25)
		(fill yes
			(thermal_gap 0.5)
			(thermal_bridge_width 0.5)
			(island_removal_mode 0)
		)
		(polygon
			(pts
				(xy 36.0426 -289.4584) (xy 35.3822 -290.1188) (xy 33.2232 -290.1188) (xy 33.02 -290.322) (xy 33.02 -291.3126)
				(xy 33.2994 -291.592) (xy 37.592 -291.592) (xy 37.846 -291.338) (xy 37.846 -289.6616) (xy 37.6428 -289.4584)
			)
		)
		(polygon
			(pts
				(xy 37.4396 -290.8808) (xy 37.2364 -290.8808) (xy 37.2364 -291.084) (xy 37.4396 -291.084)
			)
		)
		(polygon
			(pts
				(xy 36.83 -290.8808) (xy 36.6268 -290.8808) (xy 36.6268 -291.084) (xy 36.83 -291.084)
			)
		)
	)
	(zone
		(layer "F.Cu")
		(hatch none 0.5)
		(connect_pads
			(clearance 0)
		)
		(min_thickness 0.25)
		(keepout
			(tracks allowed)
			(vias allowed)
			(pads allowed)
			(copperpour allowed)
			(footprints allowed)
		)
		(placement
			(enabled no)
			(sheetname "")
		)
		(fill
			(thermal_gap 0.5)
			(thermal_bridge_width 0.5)
			(island_removal_mode 0)
		)
		(polygon
			(pts
				(xy 77.597 -150.241) (xy 77.597 -147.193) (xy 79.121 -147.193) (xy 79.121 -150.241)
			)
		)
	)
	(zone
		(net "GND")
		(layer "F.Cu")
		(hatch none 0.5)
		(connect_pads
			(clearance 0.5)
		)
		(min_thickness 0.25)
		(fill yes
			(thermal_gap 0.5)
			(thermal_bridge_width 0.5)
			(island_removal_mode 0)
		)
		(polygon
			(pts
				(xy 34.0614 -91.694) (xy 33.8328 -91.9226) (xy 33.8328 -94.107) (xy 34.0106 -94.2848) (xy 37.6936 -94.2848)
				(xy 37.846 -94.1324) (xy 37.846 -91.948) (xy 37.592 -91.694)
			)
		)
		(polygon
			(pts
				(xy 36.9062 -92.5576) (xy 36.703 -92.5576) (xy 36.703 -92.7608) (xy 36.9062 -92.7608)
			)
		)
	)
	(zone
		(layer "F.Cu")
		(hatch none 0.5)
		(connect_pads
			(clearance 0)
		)
		(min_thickness 0.25)
		(keepout
			(tracks not_allowed)
			(vias allowed)
			(pads allowed)
			(copperpour not_allowed)
			(footprints allowed)
		)
		(placement
			(enabled no)
			(sheetname "")
		)
		(fill
			(thermal_gap 0.5)
			(thermal_bridge_width 0.5)
			(island_removal_mode 0)
		)
		(polygon
			(pts
				(arc
					(start 7.502906 -171.986956)
					(mid 6.992493 -171.476162)
					(end 6.481826 -171.986702)
				)
				(xy 6.481826 -172.140118) (xy 6.697472 -172.140118)
				(arc
					(start 6.746748 -172.090842)
					(mid 7.18101 -171.798058)
					(end 6.888226 -172.23232)
				)
				(xy 6.780276 -172.34027) (xy 6.481826 -172.34027) (xy 6.481826 -172.445172) (xy 6.779514 -172.445172)
				(arc
					(start 6.888226 -172.553884)
					(mid 7.18101 -172.988146)
					(end 6.746748 -172.695362)
				)
				(xy 6.69671 -172.645324) (xy 6.481826 -172.645324)
				(arc
					(start 6.481826 -172.799502)
					(mid 6.992366 -173.310042)
					(end 7.502906 -172.799502)
				)
			)
		)
	)
	(zone
		(layer "F.Cu")
		(hatch none 0.5)
		(connect_pads
			(clearance 0)
		)
		(min_thickness 0.25)
		(keepout
			(tracks not_allowed)
			(vias allowed)
			(pads allowed)
			(copperpour not_allowed)
			(footprints allowed)
		)
		(placement
			(enabled no)
			(sheetname "")
		)
		(fill
			(thermal_gap 0.5)
			(thermal_bridge_width 0.5)
			(island_removal_mode 0)
		)
		(polygon
			(pts
				(xy 97.81921 -208.23555) (xy 97.81921 -208.324196) (xy 97.819464 -208.32445) (xy 98.98761 -208.32445)
				(xy 98.98761 -208.23555)
			)
		)
	)
	(zone
		(layer "F.Cu")
		(hatch none 0.5)
		(connect_pads
			(clearance 0)
		)
		(min_thickness 0.25)
		(keepout
			(tracks not_allowed)
			(vias allowed)
			(pads allowed)
			(copperpour not_allowed)
			(footprints allowed)
		)
		(placement
			(enabled no)
			(sheetname "")
		)
		(fill
			(thermal_gap 0.5)
			(thermal_bridge_width 0.5)
			(island_removal_mode 0)
		)
		(polygon
			(pts
				(arc
					(start 222.339154 -481.631498)
					(mid 221.727141 -481.019104)
					(end 221.114874 -481.631244)
				)
				(arc
					(start 221.114874 -482.748844)
					(mid 221.727014 -483.360984)
					(end 222.339154 -482.748844)
				)
				(xy 222.339154 -482.442774) (xy 222.174562 -482.442774)
				(arc
					(start 221.972632 -482.644704)
					(mid 221.53837 -482.937488)
					(end 221.831154 -482.503226)
				)
				(xy 222.091758 -482.242622) (xy 222.339154 -482.242622) (xy 222.339154 -482.13772) (xy 222.092012 -482.13772)
				(arc
					(start 221.831154 -481.876862)
					(mid 221.53837 -481.4426)
					(end 221.972632 -481.735384)
				)
				(xy 222.174816 -481.937568) (xy 222.339154 -481.937568)
			)
		)
	)
	(zone
		(layer "F.Cu")
		(hatch none 0.5)
		(connect_pads
			(clearance 0)
		)
		(min_thickness 0.25)
		(keepout
			(tracks not_allowed)
			(vias allowed)
			(pads allowed)
			(copperpour not_allowed)
			(footprints allowed)
		)
		(placement
			(enabled no)
			(sheetname "")
		)
		(fill
			(thermal_gap 0.5)
			(thermal_bridge_width 0.5)
			(island_removal_mode 0)
		)
		(polygon
			(pts
				(arc
					(start 37.33927 -383.431542)
					(mid 36.727257 -382.819148)
					(end 36.11499 -383.431288)
				)
				(arc
					(start 36.11499 -384.548888)
					(mid 36.72713 -385.161028)
					(end 37.33927 -384.548888)
				)
				(xy 37.33927 -384.242818) (xy 37.174678 -384.242818)
				(arc
					(start 36.972748 -384.444748)
					(mid 36.538486 -384.737532)
					(end 36.83127 -384.30327)
				)
				(xy 37.091874 -384.042666) (xy 37.33927 -384.042666) (xy 37.33927 -383.937764) (xy 37.092128 -383.937764)
				(arc
					(start 36.83127 -383.676906)
					(mid 36.538486 -383.242644)
					(end 36.972748 -383.535428)
				)
				(xy 37.174932 -383.737612) (xy 37.33927 -383.737612)
			)
		)
	)
	(zone
		(net "GND")
		(layer "F.Cu")
		(hatch none 0.5)
		(connect_pads
			(clearance 0.5)
		)
		(min_thickness 0.25)
		(fill yes
			(thermal_gap 0.5)
			(thermal_bridge_width 0.5)
			(island_removal_mode 0)
		)
		(polygon
			(pts
				(xy 29.69895 -66.675) (xy 17.145 -79.22895) (xy 17.145 -85.962998) (xy 17.413478 -86.231476) (xy 19.214592 -86.231476)
				(xy 24.547068 -80.899) (xy 33.771586 -80.899) (xy 34.48812 -80.182466) (xy 34.48812 -66.95313) (xy 34.20999 -66.675)
			)
		)
	)
	(zone
		(layer "F.Cu")
		(hatch none 0.5)
		(connect_pads
			(clearance 0)
		)
		(min_thickness 0.25)
		(keepout
			(tracks not_allowed)
			(vias allowed)
			(pads allowed)
			(copperpour not_allowed)
			(footprints allowed)
		)
		(placement
			(enabled no)
			(sheetname "")
		)
		(fill
			(thermal_gap 0.5)
			(thermal_bridge_width 0.5)
			(island_removal_mode 0)
		)
		(polygon
			(pts
				(arc
					(start 7.502906 -301.135796)
					(mid 6.992366 -300.625256)
					(end 6.481826 -301.135796)
				)
				(xy 6.481826 -301.289212) (xy 6.697472 -301.289212)
				(arc
					(start 6.746748 -301.239936)
					(mid 7.18101 -300.947152)
					(end 6.888226 -301.381414)
				)
				(xy 6.780276 -301.489364) (xy 6.481826 -301.489364) (xy 6.481826 -301.594266) (xy 6.779514 -301.594266)
				(arc
					(start 6.888226 -301.702978)
					(mid 7.18101 -302.13724)
					(end 6.746748 -301.844456)
				)
				(xy 6.69671 -301.794418) (xy 6.481826 -301.794418)
				(arc
					(start 6.481826 -301.948342)
					(mid 6.992239 -302.459136)
					(end 7.502906 -301.948596)
				)
			)
		)
	)
	(zone
		(layer "F.Cu")
		(hatch none 0.5)
		(connect_pads
			(clearance 0)
		)
		(min_thickness 0.25)
		(keepout
			(tracks not_allowed)
			(vias allowed)
			(pads allowed)
			(copperpour not_allowed)
			(footprints allowed)
		)
		(placement
			(enabled no)
			(sheetname "")
		)
		(fill
			(thermal_gap 0.5)
			(thermal_bridge_width 0.5)
			(island_removal_mode 0)
		)
		(polygon
			(pts
				(arc
					(start 7.502906 -159.18688)
					(mid 6.992493 -158.676086)
					(end 6.481826 -159.186626)
				)
				(xy 6.481826 -159.340296) (xy 6.697218 -159.340296)
				(arc
					(start 6.746748 -159.290766)
					(mid 7.18101 -158.997982)
					(end 6.888226 -159.432244)
				)
				(xy 6.780022 -159.540448) (xy 6.481826 -159.540448) (xy 6.481826 -159.64535) (xy 6.779768 -159.64535)
				(arc
					(start 6.888226 -159.753808)
					(mid 7.18101 -160.18807)
					(end 6.746748 -159.895286)
				)
				(xy 6.696964 -159.845502) (xy 6.481826 -159.845502)
				(arc
					(start 6.481826 -159.999426)
					(mid 6.992366 -160.509966)
					(end 7.502906 -159.999426)
				)
			)
		)
	)
	(zone
		(layer "F.Cu")
		(hatch none 0.5)
		(connect_pads
			(clearance 0)
		)
		(min_thickness 0.25)
		(keepout
			(tracks allowed)
			(vias allowed)
			(pads allowed)
			(copperpour allowed)
			(footprints allowed)
		)
		(placement
			(enabled no)
			(sheetname "")
		)
		(fill
			(thermal_gap 0.5)
			(thermal_bridge_width 0.5)
			(island_removal_mode 0)
		)
		(polygon
			(pts
				(xy 222.377 -367.919) (xy 222.377 -360.807) (xy 224.536 -360.807) (xy 224.536 -367.919)
			)
		)
	)
	(zone
		(net "GND")
		(layer "F.Cu")
		(hatch none 0.5)
		(connect_pads
			(clearance 0.5)
		)
		(min_thickness 0.25)
		(fill yes
			(thermal_gap 0.5)
			(thermal_bridge_width 0.5)
			(island_removal_mode 0)
		)
		(polygon
			(pts
				(xy 31.833312 -343.040462) (xy 31.242 -343.631774) (xy 31.242 -351.028) (xy 28.575 -353.695) (xy 24.6634 -353.695)
				(xy 23.622 -354.7364) (xy 23.622 -358.0384) (xy 23.8506 -358.267) (xy 25.196546 -358.267) (xy 26.4922 -359.562654)
				(xy 26.4922 -364.198916) (xy 26.739088 -364.445804) (xy 26.739088 -365.306356) (xy 26.411428 -365.634016)
				(xy 25.78989 -365.634016) (xy 25.221946 -366.20196) (xy 25.221946 -367.318036) (xy 25.83307 -367.92916)
				(xy 25.83307 -371.503448) (xy 25.744932 -371.591586) (xy 24.283416 -371.591586) (xy 24.226774 -371.648228)
				(xy 24.226774 -372.870222) (xy 24.330914 -372.974362) (xy 26.58745 -372.974362) (xy 28.287472 -371.27434)
				(xy 31.82366 -371.27434) (xy 33.655 -369.443) (xy 33.655 -360.807) (xy 39.878 -354.584) (xy 39.878 -351.730056)
				(xy 39.601394 -351.45345) (xy 35.099244 -351.45345) (xy 33.94329 -350.297496) (xy 33.94329 -345.88958)
				(xy 35.542728 -344.290142) (xy 35.542728 -343.564718) (xy 35.018472 -343.040462)
			)
		)
	)
	(zone
		(net "GND")
		(layer "F.Cu")
		(hatch none 0.5)
		(connect_pads
			(clearance 0.5)
		)
		(min_thickness 0.25)
		(fill yes
			(thermal_gap 0.5)
			(thermal_bridge_width 0.5)
			(island_removal_mode 0)
		)
		(polygon
			(pts
				(xy 1.143 -457.327) (xy 1.016 -457.454) (xy 1.016 -461.645) (xy 1.143 -461.772) (xy 6.604 -461.772)
				(xy 7.493 -460.883) (xy 10.16 -460.883) (xy 10.6426 -460.4004) (xy 10.6426 -458.343) (xy 10.2616 -457.962)
				(xy 6.477 -457.962) (xy 5.842 -457.327)
			)
		)
	)
	(zone
		(net "P3V3")
		(layer "F.Cu")
		(hatch none 0.5)
		(connect_pads
			(clearance 0.5)
		)
		(min_thickness 0.25)
		(fill yes
			(thermal_gap 0.5)
			(thermal_bridge_width 0.5)
			(island_removal_mode 0)
		)
		(polygon
			(pts
				(xy 24.384 -51.689) (xy 24.16683 -51.90617) (xy 24.16683 -54.90083) (xy 24.3586 -55.0926) (xy 25.3492 -55.0926)
				(xy 26.1366 -54.3052) (xy 26.1366 -51.9176) (xy 25.908 -51.689)
			)
		)
		(polygon
			(pts
				(xy 24.8158 -54.65191) (xy 24.6126 -54.65191) (xy 24.6126 -54.85511) (xy 24.8158 -54.85511)
			)
		)
		(polygon
			(pts
				(xy 24.8158 -54.09311) (xy 24.6126 -54.09311) (xy 24.6126 -54.29631) (xy 24.8158 -54.29631)
			)
		)
		(polygon
			(pts
				(xy 24.8158 -53.5178) (xy 24.6126 -53.5178) (xy 24.6126 -53.721) (xy 24.8158 -53.721)
			)
		)
		(polygon
			(pts
				(xy 24.8158 -52.959) (xy 24.6126 -52.959) (xy 24.6126 -53.1622) (xy 24.8158 -53.1622)
			)
		)
		(polygon
			(pts
				(xy 24.8158 -52.3748) (xy 24.6126 -52.3748) (xy 24.6126 -52.578) (xy 24.8158 -52.578)
			)
		)
		(polygon
			(pts
				(xy 24.8158 -51.816) (xy 24.6126 -51.816) (xy 24.6126 -52.0192) (xy 24.8158 -52.0192)
			)
		)
	)
	(zone
		(net "P12V")
		(layer "F.Cu")
		(hatch none 0.5)
		(connect_pads
			(clearance 0.5)
		)
		(min_thickness 0.25)
		(fill yes
			(thermal_gap 0.5)
			(thermal_bridge_width 0.5)
			(island_removal_mode 0)
		)
		(polygon
			(pts
				(xy 32.6136 -102.5144) (xy 32.4358 -102.6922) (xy 32.4358 -103.2764) (xy 31.9278 -103.7844) (xy 31.9278 -108.9152)
				(xy 32.1564 -109.1438) (xy 35.7378 -109.1438) (xy 36.322 -109.728) (xy 38.0746 -109.728) (xy 38.1508 -109.6518)
				(xy 38.1508 -109.1438) (xy 38.0238 -109.0168) (xy 37.338 -109.0168) (xy 37.0332 -108.712) (xy 37.0332 -107.8992)
				(xy 36.7538 -107.6198) (xy 36.7538 -106.2228) (xy 35.0774 -104.5464) (xy 35.0774 -103.7844) (xy 33.8074 -102.5144)
			)
		)
		(polygon
			(pts
				(xy 37.084 -109.0168) (xy 36.8808 -109.0168) (xy 36.8808 -109.22) (xy 37.084 -109.22)
			)
		)
		(polygon
			(pts
				(xy 36.4744 -109.0168) (xy 36.2712 -109.0168) (xy 36.2712 -109.22) (xy 36.4744 -109.22)
			)
		)
		(polygon
			(pts
				(xy 36.576 -108.5342) (xy 36.3728 -108.5342) (xy 36.3728 -108.7374) (xy 36.576 -108.7374)
			)
		)
		(polygon
			(pts
				(xy 36.576 -107.9754) (xy 36.3728 -107.9754) (xy 36.3728 -108.1786) (xy 36.576 -108.1786)
			)
		)
		(polygon
			(pts
				(xy 33.39465 -102.96525) (xy 33.19145 -102.96525) (xy 33.19145 -103.16845) (xy 33.39465 -103.16845)
			)
		)
		(polygon
			(pts
				(xy 32.83585 -102.96525) (xy 32.63265 -102.96525) (xy 32.63265 -103.16845) (xy 32.83585 -103.16845)
			)
		)
	)
	(zone
		(layer "F.Cu")
		(hatch none 0.5)
		(connect_pads
			(clearance 0)
		)
		(min_thickness 0.25)
		(keepout
			(tracks not_allowed)
			(vias allowed)
			(pads allowed)
			(copperpour not_allowed)
			(footprints allowed)
		)
		(placement
			(enabled no)
			(sheetname "")
		)
		(fill
			(thermal_gap 0.5)
			(thermal_bridge_width 0.5)
			(island_removal_mode 0)
		)
		(polygon
			(pts
				(arc
					(start 25.88514 -242.051078)
					(mid 25.273 -241.438938)
					(end 24.66086 -242.051078)
				)
				(xy 24.66086 -242.357402) (xy 24.825198 -242.357402)
				(arc
					(start 25.027382 -242.155218)
					(mid 25.461644 -241.862434)
					(end 25.16886 -242.296696)
				)
				(xy 24.908002 -242.557554) (xy 24.66086 -242.557554) (xy 24.66086 -242.662456) (xy 24.908256 -242.662456)
				(arc
					(start 25.16886 -242.92306)
					(mid 25.461644 -243.357322)
					(end 25.027382 -243.064538)
				)
				(xy 24.825452 -242.862608) (xy 24.66086 -242.862608)
				(arc
					(start 24.66086 -243.168424)
					(mid 25.272873 -243.780818)
					(end 25.88514 -243.168678)
				)
			)
		)
	)
	(zone
		(net "P12V_SSD6")
		(layer "F.Cu")
		(hatch none 0.5)
		(connect_pads
			(clearance 0.5)
		)
		(min_thickness 0.25)
		(fill yes
			(thermal_gap 0.5)
			(thermal_bridge_width 0.5)
			(island_removal_mode 0)
		)
		(polygon
			(pts
				(xy 40.794178 -390.689592) (xy 40.6654 -390.81837) (xy 40.6654 -392.7856) (xy 40.1574 -393.2936)
				(xy 38.608 -393.2936) (xy 37.465 -394.4366) (xy 36.7792 -394.4366) (xy 36.3982 -394.8176) (xy 36.3982 -394.9446)
				(xy 36.2966 -395.0462) (xy 33.655 -395.0462) (xy 32.8422 -394.2334) (xy 31.369 -394.2334) (xy 31.115 -394.4874)
				(xy 31.115 -399.415) (xy 32.131 -400.431) (xy 37.973 -400.431) (xy 38.4302 -400.8882) (xy 38.4302 -404.241)
				(xy 38.6588 -404.4696) (xy 42.9514 -404.4696) (xy 43.18 -404.241) (xy 43.18 -400.431) (xy 41.783 -399.034)
				(xy 41.783 -398.145) (xy 43.434 -396.494) (xy 43.434 -390.81837) (xy 43.305222 -390.689592)
			)
		)
		(polygon
			(pts
				(xy 41.6052 -404.0632) (xy 41.402 -404.0632) (xy 41.402 -404.2664) (xy 41.6052 -404.2664)
			)
		)
		(polygon
			(pts
				(xy 40.4622 -404.0632) (xy 40.259 -404.0632) (xy 40.259 -404.2664) (xy 40.4622 -404.2664)
			)
		)
		(polygon
			(pts
				(xy 41.6052 -401.2692) (xy 41.402 -401.2692) (xy 41.402 -401.4724) (xy 41.6052 -401.4724)
			)
		)
		(polygon
			(pts
				(xy 40.4622 -401.2692) (xy 40.259 -401.2692) (xy 40.259 -401.4724) (xy 40.4622 -401.4724)
			)
		)
		(polygon
			(pts
				(xy 35.2552 -399.3134) (xy 35.052 -399.3134) (xy 35.052 -399.5166) (xy 35.2552 -399.5166)
			)
		)
		(polygon
			(pts
				(xy 34.3916 -399.3134) (xy 34.1884 -399.3134) (xy 34.1884 -399.5166) (xy 34.3916 -399.5166)
			)
		)
		(polygon
			(pts
				(xy 37.4396 -394.9446) (xy 37.2364 -394.9446) (xy 37.2364 -395.1478) (xy 37.4396 -395.1478)
			)
		)
		(polygon
			(pts
				(xy 36.83 -394.9446) (xy 36.6268 -394.9446) (xy 36.6268 -395.1478) (xy 36.83 -395.1478)
			)
		)
	)
	(zone
		(layer "F.Cu")
		(hatch none 0.5)
		(connect_pads
			(clearance 0)
		)
		(min_thickness 0.25)
		(keepout
			(tracks not_allowed)
			(vias allowed)
			(pads allowed)
			(copperpour not_allowed)
			(footprints allowed)
		)
		(placement
			(enabled no)
			(sheetname "")
		)
		(fill
			(thermal_gap 0.5)
			(thermal_bridge_width 0.5)
			(island_removal_mode 0)
		)
		(polygon
			(pts
				(arc
					(start 35.84067 -278.183848)
					(mid 35.330257 -277.673054)
					(end 34.81959 -278.183594)
				)
				(arc
					(start 34.81959 -278.996394)
					(mid 35.33013 -279.506934)
					(end 35.84067 -278.996394)
				)
				(xy 35.84067 -278.842724) (xy 35.625278 -278.842724)
				(arc
					(start 35.575748 -278.892254)
					(mid 35.141486 -279.185038)
					(end 35.43427 -278.750776)
				)
				(xy 35.542474 -278.642572) (xy 35.84067 -278.642572) (xy 35.84067 -278.53767) (xy 35.542728 -278.53767)
				(arc
					(start 35.43427 -278.429212)
					(mid 35.141486 -277.99495)
					(end 35.575748 -278.287734)
				)
				(xy 35.625532 -278.337518) (xy 35.84067 -278.337518)
			)
		)
	)
	(zone
		(layer "F.Cu")
		(hatch none 0.5)
		(connect_pads
			(clearance 0)
		)
		(min_thickness 0.25)
		(keepout
			(tracks allowed)
			(vias allowed)
			(pads allowed)
			(copperpour allowed)
			(footprints allowed)
		)
		(placement
			(enabled no)
			(sheetname "")
		)
		(fill
			(thermal_gap 0.5)
			(thermal_bridge_width 0.5)
			(island_removal_mode 0)
		)
		(polygon
			(pts
				(xy 24.638 -35.052) (xy 24.638 -42.164) (xy 22.479 -42.164) (xy 22.479 -35.052)
			)
		)
	)
	(zone
		(layer "F.Cu")
		(hatch none 0.5)
		(connect_pads
			(clearance 0)
		)
		(min_thickness 0.25)
		(keepout
			(tracks not_allowed)
			(vias allowed)
			(pads allowed)
			(copperpour not_allowed)
			(footprints allowed)
		)
		(placement
			(enabled no)
			(sheetname "")
		)
		(fill
			(thermal_gap 0.5)
			(thermal_bridge_width 0.5)
			(island_removal_mode 0)
		)
		(polygon
			(pts
				(arc
					(start 37.33927 -172.631354)
					(mid 36.727257 -172.01896)
					(end 36.11499 -172.6311)
				)
				(arc
					(start 36.11499 -173.7487)
					(mid 36.72713 -174.36084)
					(end 37.33927 -173.7487)
				)
				(xy 37.33927 -173.44263) (xy 37.174678 -173.44263)
				(arc
					(start 36.972748 -173.64456)
					(mid 36.538486 -173.937344)
					(end 36.83127 -173.503082)
				)
				(xy 37.091874 -173.242478) (xy 37.33927 -173.242478) (xy 37.33927 -173.137576) (xy 37.092128 -173.137576)
				(arc
					(start 36.83127 -172.876718)
					(mid 36.538486 -172.442456)
					(end 36.972748 -172.73524)
				)
				(xy 37.174932 -172.937424) (xy 37.33927 -172.937424)
			)
		)
	)
	(zone
		(layer "F.Cu")
		(hatch none 0.5)
		(connect_pads
			(clearance 0)
		)
		(min_thickness 0.25)
		(keepout
			(tracks not_allowed)
			(vias allowed)
			(pads allowed)
			(copperpour not_allowed)
			(footprints allowed)
		)
		(placement
			(enabled no)
			(sheetname "")
		)
		(fill
			(thermal_gap 0.5)
			(thermal_bridge_width 0.5)
			(island_removal_mode 0)
		)
		(polygon
			(pts
				(arc
					(start 220.840554 -381.183896)
					(mid 220.330141 -380.673102)
					(end 219.819474 -381.183642)
				)
				(arc
					(start 219.819474 -381.996442)
					(mid 220.330014 -382.506982)
					(end 220.840554 -381.996442)
				)
				(xy 220.840554 -381.842772) (xy 220.625162 -381.842772)
				(arc
					(start 220.575632 -381.892302)
					(mid 220.14137 -382.185086)
					(end 220.434154 -381.750824)
				)
				(xy 220.542358 -381.64262) (xy 220.840554 -381.64262) (xy 220.840554 -381.537718) (xy 220.542612 -381.537718)
				(arc
					(start 220.434154 -381.42926)
					(mid 220.14137 -380.994998)
					(end 220.575632 -381.287782)
				)
				(xy 220.625416 -381.337566) (xy 220.840554 -381.337566)
			)
		)
	)
	(zone
		(layer "F.Cu")
		(hatch none 0.5)
		(connect_pads
			(clearance 0)
		)
		(min_thickness 0.25)
		(keepout
			(tracks not_allowed)
			(vias allowed)
			(pads allowed)
			(copperpour not_allowed)
			(footprints allowed)
		)
		(placement
			(enabled no)
			(sheetname "")
		)
		(fill
			(thermal_gap 0.5)
			(thermal_bridge_width 0.5)
			(island_removal_mode 0)
		)
		(polygon
			(pts
				(arc
					(start 233.897424 -369.579398)
					(mid 233.386884 -369.068858)
					(end 232.876344 -369.579398)
				)
				(arc
					(start 232.876344 -370.391944)
					(mid 233.386757 -370.902738)
					(end 233.897424 -370.392198)
				)
				(xy 233.897424 -370.238274) (xy 233.682286 -370.238274)
				(arc
					(start 233.632502 -370.288058)
					(mid 233.19824 -370.580842)
					(end 233.491024 -370.14658)
				)
				(xy 233.599482 -370.038122) (xy 233.897424 -370.038122) (xy 233.897424 -369.93322) (xy 233.599228 -369.93322)
				(arc
					(start 233.491024 -369.825016)
					(mid 233.19824 -369.390754)
					(end 233.632502 -369.683538)
				)
				(xy 233.682032 -369.733068) (xy 233.897424 -369.733068)
			)
		)
	)
	(zone
		(net "GND")
		(layer "F.Cu")
		(hatch none 0.5)
		(connect_pads
			(clearance 0.5)
		)
		(min_thickness 0.25)
		(fill yes
			(thermal_gap 0.5)
			(thermal_bridge_width 0.5)
			(island_removal_mode 0)
		)
		(polygon
			(pts
				(xy 167.824404 -339.404452) (xy 167.10787 -340.120986) (xy 167.10787 -342.472518) (xy 179.825396 -355.190044)
				(xy 219.23883 -355.190044) (xy 220.218 -354.210874) (xy 220.218 -348.7166) (xy 219.5322 -348.0308)
				(xy 217.6526 -348.0308) (xy 216.1032 -346.4814) (xy 216.1032 -341.36584) (xy 214.141812 -339.404452)
			)
		)
	)
	(zone
		(layer "F.Cu")
		(hatch none 0.5)
		(connect_pads
			(clearance 0)
		)
		(min_thickness 0.25)
		(keepout
			(tracks not_allowed)
			(vias allowed)
			(pads allowed)
			(copperpour not_allowed)
			(footprints allowed)
		)
		(placement
			(enabled no)
			(sheetname "")
		)
		(fill
			(thermal_gap 0.5)
			(thermal_bridge_width 0.5)
			(island_removal_mode 0)
		)
		(polygon
			(pts
				(arc
					(start 25.88514 -126.251208)
					(mid 25.273 -125.639068)
					(end 24.66086 -126.251208)
				)
				(xy 24.66086 -126.557278) (xy 24.825452 -126.557278)
				(arc
					(start 25.027382 -126.355348)
					(mid 25.461644 -126.062564)
					(end 25.16886 -126.496826)
				)
				(xy 24.908256 -126.75743) (xy 24.66086 -126.75743) (xy 24.66086 -126.862332) (xy 24.908002 -126.862332)
				(arc
					(start 25.16886 -127.12319)
					(mid 25.461644 -127.557452)
					(end 25.027382 -127.264668)
				)
				(xy 24.825198 -127.062484) (xy 24.66086 -127.062484)
				(arc
					(start 24.66086 -127.368554)
					(mid 25.272873 -127.980948)
					(end 25.88514 -127.368808)
				)
			)
		)
	)
	(zone
		(layer "F.Cu")
		(hatch none 0.5)
		(connect_pads
			(clearance 0)
		)
		(min_thickness 0.25)
		(keepout
			(tracks not_allowed)
			(vias allowed)
			(pads allowed)
			(copperpour not_allowed)
			(footprints allowed)
		)
		(placement
			(enabled no)
			(sheetname "")
		)
		(fill
			(thermal_gap 0.5)
			(thermal_bridge_width 0.5)
			(island_removal_mode 0)
		)
		(polygon
			(pts
				(arc
					(start 37.33927 -468.831422)
					(mid 36.72713 -468.219282)
					(end 36.11499 -468.831422)
				)
				(arc
					(start 36.11499 -469.948768)
					(mid 36.727003 -470.561162)
					(end 37.33927 -469.949022)
				)
				(xy 37.33927 -469.642698) (xy 37.174932 -469.642698)
				(arc
					(start 36.972748 -469.844882)
					(mid 36.538486 -470.137666)
					(end 36.83127 -469.703404)
				)
				(xy 37.092128 -469.442546) (xy 37.33927 -469.442546) (xy 37.33927 -469.337644) (xy 37.091874 -469.337644)
				(arc
					(start 36.83127 -469.07704)
					(mid 36.538486 -468.642778)
					(end 36.972748 -468.935562)
				)
				(xy 37.174678 -469.137492) (xy 37.33927 -469.137492)
			)
		)
	)
	(zone
		(layer "F.Cu")
		(hatch none 0.5)
		(connect_pads
			(clearance 0)
		)
		(min_thickness 0.25)
		(keepout
			(tracks allowed)
			(vias allowed)
			(pads allowed)
			(copperpour allowed)
			(footprints allowed)
		)
		(placement
			(enabled no)
			(sheetname "")
		)
		(fill
			(thermal_gap 0.5)
			(thermal_bridge_width 0.5)
			(island_removal_mode 0)
		)
		(polygon
			(pts
				(xy 73.279 -150.241) (xy 73.279 -147.193) (xy 74.803 -147.193) (xy 74.803 -150.241)
			)
		)
	)
	(zone
		(net "GND")
		(layer "F.Cu")
		(hatch none 0.5)
		(connect_pads
			(clearance 0.5)
		)
		(min_thickness 0.25)
		(fill yes
			(thermal_gap 0.5)
			(thermal_bridge_width 0.5)
			(island_removal_mode 0)
		)
		(polygon
			(pts
				(xy 24.638 -214.249) (xy 24.13 -214.757) (xy 24.13 -216.3318) (xy 24.3586 -216.5604) (xy 25.5524 -216.5604)
				(xy 26.2382 -215.8746) (xy 28.8036 -215.8746) (xy 28.956 -215.7222) (xy 28.956 -214.4522) (xy 28.7528 -214.249)
			)
		)
		(polygon
			(pts
				(xy 25.4 -214.757) (xy 25.1968 -214.757) (xy 25.1968 -214.9602) (xy 25.4 -214.9602)
			)
		)
		(polygon
			(pts
				(xy 24.7904 -214.757) (xy 24.5872 -214.757) (xy 24.5872 -214.9602) (xy 24.7904 -214.9602)
			)
		)
	)
	(zone
		(layer "F.Cu")
		(hatch none 0.5)
		(connect_pads
			(clearance 0)
		)
		(min_thickness 0.25)
		(keepout
			(tracks not_allowed)
			(vias allowed)
			(pads allowed)
			(copperpour not_allowed)
			(footprints allowed)
		)
		(placement
			(enabled no)
			(sheetname "")
		)
		(fill
			(thermal_gap 0.5)
			(thermal_bridge_width 0.5)
			(island_removal_mode 0)
		)
		(polygon
			(pts
				(arc
					(start 7.502906 -353.1362)
					(mid 6.992493 -352.625406)
					(end 6.481826 -353.135946)
				)
				(xy 6.481826 -353.289362) (xy 6.697472 -353.289362)
				(arc
					(start 6.746748 -353.240086)
					(mid 7.18101 -352.947302)
					(end 6.888226 -353.381564)
				)
				(xy 6.780276 -353.489514) (xy 6.481826 -353.489514) (xy 6.481826 -353.594416) (xy 6.779514 -353.594416)
				(arc
					(start 6.888226 -353.703128)
					(mid 7.18101 -354.13739)
					(end 6.746748 -353.844606)
				)
				(xy 6.69671 -353.794568) (xy 6.481826 -353.794568)
				(arc
					(start 6.481826 -353.948746)
					(mid 6.992366 -354.459286)
					(end 7.502906 -353.948746)
				)
			)
		)
	)
	(zone
		(layer "F.Cu")
		(hatch none 0.5)
		(connect_pads
			(clearance 0)
		)
		(min_thickness 0.25)
		(keepout
			(tracks not_allowed)
			(vias allowed)
			(pads allowed)
			(copperpour not_allowed)
			(footprints allowed)
		)
		(placement
			(enabled no)
			(sheetname "")
		)
		(fill
			(thermal_gap 0.5)
			(thermal_bridge_width 0.5)
			(island_removal_mode 0)
		)
		(polygon
			(pts
				(arc
					(start 7.502906 -408.735784)
					(mid 6.992366 -408.225244)
					(end 6.481826 -408.735784)
				)
				(xy 6.481826 -408.8892) (xy 6.697472 -408.8892)
				(arc
					(start 6.746748 -408.839924)
					(mid 7.18101 -408.54714)
					(end 6.888226 -408.981402)
				)
				(xy 6.780276 -409.089352) (xy 6.481826 -409.089352) (xy 6.481826 -409.194254) (xy 6.779514 -409.194254)
				(arc
					(start 6.888226 -409.302966)
					(mid 7.18101 -409.737228)
					(end 6.746748 -409.444444)
				)
				(xy 6.69671 -409.394406) (xy 6.481826 -409.394406)
				(arc
					(start 6.481826 -409.54833)
					(mid 6.992239 -410.059124)
					(end 7.502906 -409.548584)
				)
			)
		)
	)
	(zone
		(layer "F.Cu")
		(hatch none 0.5)
		(connect_pads
			(clearance 0)
		)
		(min_thickness 0.25)
		(keepout
			(tracks not_allowed)
			(vias allowed)
			(pads allowed)
			(copperpour not_allowed)
			(footprints allowed)
		)
		(placement
			(enabled no)
			(sheetname "")
		)
		(fill
			(thermal_gap 0.5)
			(thermal_bridge_width 0.5)
			(island_removal_mode 0)
		)
		(polygon
			(pts
				(arc
					(start 72.90054 -431.139854)
					(mid 72.390127 -430.62906)
					(end 71.87946 -431.1396)
				)
				(xy 71.87946 -431.30089) (xy 72.087232 -431.30089)
				(arc
					(start 72.144382 -431.24374)
					(mid 72.578644 -430.950956)
					(end 72.28586 -431.385218)
				)
				(xy 72.170036 -431.501042) (xy 71.87946 -431.501042) (xy 71.87946 -431.605944) (xy 72.185022 -431.605944)
				(arc
					(start 72.28586 -431.706782)
					(mid 72.578644 -432.141044)
					(end 72.144382 -431.84826)
				)
				(xy 72.102218 -431.806096) (xy 71.87946 -431.806096)
				(arc
					(start 71.87946 -431.9524)
					(mid 72.39 -432.46294)
					(end 72.90054 -431.9524)
				)
			)
		)
	)
	(zone
		(net "GND")
		(layer "F.Cu")
		(hatch none 0.5)
		(connect_pads
			(clearance 0.5)
		)
		(min_thickness 0.25)
		(fill yes
			(thermal_gap 0.5)
			(thermal_bridge_width 0.5)
			(island_removal_mode 0)
		)
		(polygon
			(pts
				(xy 51.423062 -439.863738) (xy 48.186848 -443.099952) (xy 48.186848 -443.537848) (xy 48.50384 -443.85484)
				(xy 59.074558 -443.85484) (xy 64.549528 -449.32981) (xy 64.549528 -450.112638) (xy 63.761366 -450.9008)
				(xy 56.1086 -450.9008) (xy 50.9016 -456.1078) (xy 46.0502 -456.1078) (xy 45.466 -456.692) (xy 45.466 -459.105)
				(xy 47.244 -460.883) (xy 76.581 -460.883) (xy 84.709 -452.755) (xy 84.709 -445.2874) (xy 79.8068 -440.3852)
				(xy 78.1558 -440.3852) (xy 77.724 -440.817) (xy 77.724 -454.533) (xy 74.803 -457.454) (xy 68.834 -457.454)
				(xy 67.757802 -456.377802) (xy 67.757802 -453.145652) (xy 69.547486 -451.355968) (xy 69.547486 -447.118486)
				(xy 65.278 -442.849) (xy 59.069986 -442.849) (xy 56.084724 -439.863738)
			)
		)
	)
	(zone
		(layer "F.Cu")
		(hatch none 0.5)
		(connect_pads
			(clearance 0)
		)
		(min_thickness 0.25)
		(keepout
			(tracks not_allowed)
			(vias allowed)
			(pads allowed)
			(copperpour not_allowed)
			(footprints allowed)
		)
		(placement
			(enabled no)
			(sheetname "")
		)
		(fill
			(thermal_gap 0.5)
			(thermal_bridge_width 0.5)
			(island_removal_mode 0)
		)
		(polygon
			(pts
				(arc
					(start 35.84067 -260.583934)
					(mid 35.330257 -260.07314)
					(end 34.81959 -260.58368)
				)
				(arc
					(start 34.81959 -261.39648)
					(mid 35.33013 -261.90702)
					(end 35.84067 -261.39648)
				)
				(xy 35.84067 -261.24281) (xy 35.625278 -261.24281)
				(arc
					(start 35.575748 -261.29234)
					(mid 35.141486 -261.585124)
					(end 35.43427 -261.150862)
				)
				(xy 35.542474 -261.042658) (xy 35.84067 -261.042658) (xy 35.84067 -260.937756) (xy 35.542728 -260.937756)
				(arc
					(start 35.43427 -260.829298)
					(mid 35.141486 -260.395036)
					(end 35.575748 -260.68782)
				)
				(xy 35.625532 -260.737604) (xy 35.84067 -260.737604)
			)
		)
	)
	(zone
		(layer "F.Cu")
		(hatch none 0.5)
		(connect_pads
			(clearance 0)
		)
		(min_thickness 0.25)
		(keepout
			(tracks not_allowed)
			(vias allowed)
			(pads allowed)
			(copperpour not_allowed)
			(footprints allowed)
		)
		(placement
			(enabled no)
			(sheetname "")
		)
		(fill
			(thermal_gap 0.5)
			(thermal_bridge_width 0.5)
			(island_removal_mode 0)
		)
		(polygon
			(pts
				(arc
					(start 7.502906 -291.535866)
					(mid 6.992366 -291.025326)
					(end 6.481826 -291.535866)
				)
				(xy 6.481826 -291.689282) (xy 6.697472 -291.689282)
				(arc
					(start 6.746748 -291.640006)
					(mid 7.18101 -291.347222)
					(end 6.888226 -291.781484)
				)
				(xy 6.780276 -291.889434) (xy 6.481826 -291.889434) (xy 6.481826 -291.994336) (xy 6.779514 -291.994336)
				(arc
					(start 6.888226 -292.103048)
					(mid 7.18101 -292.53731)
					(end 6.746748 -292.244526)
				)
				(xy 6.69671 -292.194488) (xy 6.481826 -292.194488)
				(arc
					(start 6.481826 -292.348412)
					(mid 6.992239 -292.859206)
					(end 7.502906 -292.348666)
				)
			)
		)
	)
	(zone
		(layer "F.Cu")
		(hatch none 0.5)
		(connect_pads
			(clearance 0)
		)
		(min_thickness 0.25)
		(keepout
			(tracks not_allowed)
			(vias allowed)
			(pads allowed)
			(copperpour not_allowed)
			(footprints allowed)
		)
		(placement
			(enabled no)
			(sheetname "")
		)
		(fill
			(thermal_gap 0.5)
			(thermal_bridge_width 0.5)
			(island_removal_mode 0)
		)
		(polygon
			(pts
				(arc
					(start 17.78254 -238.603282)
					(mid 17.272 -238.092742)
					(end 16.76146 -238.603282)
				)
				(arc
					(start 16.76146 -239.415828)
					(mid 17.271873 -239.926622)
					(end 17.78254 -239.416082)
				)
				(xy 17.78254 -239.262158) (xy 17.567402 -239.262158)
				(arc
					(start 17.517618 -239.311942)
					(mid 17.083356 -239.604726)
					(end 17.37614 -239.170464)
				)
				(xy 17.484598 -239.062006) (xy 17.78254 -239.062006) (xy 17.78254 -238.957104) (xy 17.484344 -238.957104)
				(arc
					(start 17.37614 -238.8489)
					(mid 17.083356 -238.414638)
					(end 17.517618 -238.707422)
				)
				(xy 17.567148 -238.756952) (xy 17.78254 -238.756952)
			)
		)
	)
	(zone
		(layer "F.Cu")
		(hatch none 0.5)
		(connect_pads
			(clearance 0)
		)
		(min_thickness 0.25)
		(keepout
			(tracks allowed)
			(vias allowed)
			(pads allowed)
			(copperpour allowed)
			(footprints allowed)
		)
		(placement
			(enabled no)
			(sheetname "")
		)
		(fill
			(thermal_gap 0.5)
			(thermal_bridge_width 0.5)
			(island_removal_mode 0)
		)
		(polygon
			(pts
				(xy 222.377 -288.925) (xy 222.377 -272.288) (xy 224.536 -272.288) (xy 224.536 -288.925)
			)
		)
	)
	(zone
		(layer "F.Cu")
		(hatch none 0.5)
		(connect_pads
			(clearance 0)
		)
		(min_thickness 0.25)
		(keepout
			(tracks not_allowed)
			(vias allowed)
			(pads allowed)
			(copperpour not_allowed)
			(footprints allowed)
		)
		(placement
			(enabled no)
			(sheetname "")
		)
		(fill
			(thermal_gap 0.5)
			(thermal_bridge_width 0.5)
			(island_removal_mode 0)
		)
		(polygon
			(pts
				(arc
					(start 222.339154 -468.831676)
					(mid 221.727141 -468.219282)
					(end 221.114874 -468.831422)
				)
				(arc
					(start 221.114874 -469.949022)
					(mid 221.727014 -470.561162)
					(end 222.339154 -469.949022)
				)
				(xy 222.339154 -469.642698) (xy 222.174816 -469.642698)
				(arc
					(start 221.972632 -469.844882)
					(mid 221.53837 -470.137666)
					(end 221.831154 -469.703404)
				)
				(xy 222.092012 -469.442546) (xy 222.339154 -469.442546) (xy 222.339154 -469.337644) (xy 222.091758 -469.337644)
				(arc
					(start 221.831154 -469.07704)
					(mid 221.53837 -468.642778)
					(end 221.972632 -468.935562)
				)
				(xy 222.174562 -469.137492) (xy 222.339154 -469.137492)
			)
		)
	)
	(zone
		(layer "F.Cu")
		(hatch none 0.5)
		(connect_pads
			(clearance 0)
		)
		(min_thickness 0.25)
		(keepout
			(tracks not_allowed)
			(vias allowed)
			(pads allowed)
			(copperpour not_allowed)
			(footprints allowed)
		)
		(placement
			(enabled no)
			(sheetname "")
		)
		(fill
			(thermal_gap 0.5)
			(thermal_bridge_width 0.5)
			(island_removal_mode 0)
		)
		(polygon
			(pts
				(xy 1.022096 -457.795884) (xy 3.758184 -457.795884) (xy 3.81 -457.8477) (xy 3.81 -458.039216) (xy 3.761232 -458.087984)
				(xy 1.025398 -458.087984) (xy 1.014984 -458.098398) (xy 1.010158 -458.098398) (xy 1.005332 -458.093572)
				(xy 1.005332 -457.791058) (xy 1.007872 -457.788518) (xy 1.01473 -457.788518)
			)
		)
	)
	(zone
		(net "GND")
		(layer "F.Cu")
		(hatch none 0.5)
		(connect_pads
			(clearance 0.5)
		)
		(min_thickness 0.25)
		(fill yes
			(thermal_gap 0.5)
			(thermal_bridge_width 0.5)
			(island_removal_mode 0)
		)
		(polygon
			(pts
				(xy 24.6888 -111.252) (xy 24.13 -111.8108) (xy 24.13 -113.2586) (xy 24.3586 -113.4872) (xy 25.8572 -113.4872)
				(xy 26.4414 -112.903) (xy 28.4988 -112.903) (xy 28.956 -112.4458) (xy 28.956 -111.4552) (xy 28.7528 -111.252)
			)
		)
		(polygon
			(pts
				(xy 25.4 -111.76) (xy 25.1968 -111.76) (xy 25.1968 -111.9632) (xy 25.4 -111.9632)
			)
		)
		(polygon
			(pts
				(xy 24.7904 -111.76) (xy 24.5872 -111.76) (xy 24.5872 -111.9632) (xy 24.7904 -111.9632)
			)
		)
	)
	(zone
		(net "GND")
		(layer "F.Cu")
		(hatch none 0.5)
		(connect_pads
			(clearance 0.5)
		)
		(min_thickness 0.25)
		(fill yes
			(thermal_gap 0.5)
			(thermal_bridge_width 0.5)
			(island_removal_mode 0)
		)
		(polygon
			(pts
				(xy 46.101 -463.423) (xy 45.212 -464.312) (xy 45.212 -469.1761) (xy 46.345856 -470.309956) (xy 70.314566 -470.309956)
				(xy 74.271886 -466.352636) (xy 74.271886 -463.98561) (xy 73.709276 -463.423)
			)
		)
	)
	(zone
		(layer "F.Cu")
		(hatch none 0.5)
		(connect_pads
			(clearance 0)
		)
		(min_thickness 0.25)
		(keepout
			(tracks allowed)
			(vias allowed)
			(pads allowed)
			(copperpour allowed)
			(footprints allowed)
		)
		(placement
			(enabled no)
			(sheetname "")
		)
		(fill
			(thermal_gap 0.5)
			(thermal_bridge_width 0.5)
			(island_removal_mode 0)
		)
		(polygon
			(pts
				(xy 229.235 -163.195) (xy 229.235 -165.481) (xy 227.076 -165.481) (xy 227.076 -163.195)
			)
		)
	)
	(zone
		(layer "F.Cu")
		(hatch none 0.5)
		(connect_pads
			(clearance 0)
		)
		(min_thickness 0.25)
		(keepout
			(tracks not_allowed)
			(vias allowed)
			(pads allowed)
			(copperpour not_allowed)
			(footprints allowed)
		)
		(placement
			(enabled no)
			(sheetname "")
		)
		(fill
			(thermal_gap 0.5)
			(thermal_bridge_width 0.5)
			(island_removal_mode 0)
		)
		(polygon
			(pts
				(arc
					(start 222.339154 -172.631354)
					(mid 221.727141 -172.01896)
					(end 221.114874 -172.6311)
				)
				(arc
					(start 221.114874 -173.7487)
					(mid 221.727014 -174.36084)
					(end 222.339154 -173.7487)
				)
				(xy 222.339154 -173.44263) (xy 222.174562 -173.44263)
				(arc
					(start 221.972632 -173.64456)
					(mid 221.53837 -173.937344)
					(end 221.831154 -173.503082)
				)
				(xy 222.091758 -173.242478) (xy 222.339154 -173.242478) (xy 222.339154 -173.137576) (xy 222.092012 -173.137576)
				(arc
					(start 221.831154 -172.876718)
					(mid 221.53837 -172.442456)
					(end 221.972632 -172.73524)
				)
				(xy 222.174816 -172.937424) (xy 222.339154 -172.937424)
			)
		)
	)
	(zone
		(net "P12V")
		(layer "F.Cu")
		(hatch none 0.5)
		(connect_pads
			(clearance 0.5)
		)
		(min_thickness 0.25)
		(fill yes
			(thermal_gap 0.5)
			(thermal_bridge_width 0.5)
			(island_removal_mode 0)
		)
		(polygon
			(pts
				(xy 209.0166 -190.2714) (xy 208.915 -190.373) (xy 208.915 -190.881) (xy 209.042 -191.008) (xy 209.677 -191.008)
				(xy 209.9564 -191.2874) (xy 209.9564 -192.0494) (xy 210.312 -192.405) (xy 210.312 -193.802) (xy 211.074 -194.564)
				(xy 211.074 -195.9356) (xy 212.391244 -197.252844) (xy 213.900512 -197.252844) (xy 214.0712 -197.082156)
				(xy 214.0712 -196.585586) (xy 215.011 -195.645786) (xy 215.011 -191.135) (xy 214.757 -190.881) (xy 211.328 -190.881)
				(xy 210.7184 -190.2714)
			)
		)
		(polygon
			(pts
				(xy 213.7791 -196.7103) (xy 213.5759 -196.7103) (xy 213.5759 -196.9135) (xy 213.7791 -196.9135)
			)
		)
		(polygon
			(pts
				(xy 213.2203 -196.7103) (xy 213.0171 -196.7103) (xy 213.0171 -196.9135) (xy 213.2203 -196.9135)
			)
		)
		(polygon
			(pts
				(xy 210.6168 -191.8208) (xy 210.4136 -191.8208) (xy 210.4136 -192.024) (xy 210.6168 -192.024)
			)
		)
		(polygon
			(pts
				(xy 210.6168 -191.262) (xy 210.4136 -191.262) (xy 210.4136 -191.4652) (xy 210.6168 -191.4652)
			)
		)
		(polygon
			(pts
				(xy 210.7184 -190.7794) (xy 210.5152 -190.7794) (xy 210.5152 -190.9826) (xy 210.7184 -190.9826)
			)
		)
		(polygon
			(pts
				(xy 210.1088 -190.7794) (xy 209.9056 -190.7794) (xy 209.9056 -190.9826) (xy 210.1088 -190.9826)
			)
		)
	)
	(zone
		(layer "F.Cu")
		(hatch none 0.5)
		(connect_pads
			(clearance 0)
		)
		(min_thickness 0.25)
		(keepout
			(tracks not_allowed)
			(vias allowed)
			(pads allowed)
			(copperpour not_allowed)
			(footprints allowed)
		)
		(placement
			(enabled no)
			(sheetname "")
		)
		(fill
			(thermal_gap 0.5)
			(thermal_bridge_width 0.5)
			(island_removal_mode 0)
		)
		(polygon
			(pts
				(arc
					(start 25.88514 -435.251606)
					(mid 25.273127 -434.639212)
					(end 24.66086 -435.251352)
				)
				(xy 24.66086 -435.557422) (xy 24.825452 -435.557422)
				(arc
					(start 25.027382 -435.355492)
					(mid 25.461644 -435.062708)
					(end 25.16886 -435.49697)
				)
				(xy 24.908256 -435.757574) (xy 24.66086 -435.757574) (xy 24.66086 -435.862476) (xy 24.908002 -435.862476)
				(arc
					(start 25.16886 -436.123334)
					(mid 25.461644 -436.557596)
					(end 25.027382 -436.264812)
				)
				(xy 24.825198 -436.062628) (xy 24.66086 -436.062628)
				(arc
					(start 24.66086 -436.368952)
					(mid 25.273 -436.981092)
					(end 25.88514 -436.368952)
				)
			)
		)
	)
	(zone
		(layer "F.Cu")
		(hatch none 0.5)
		(connect_pads
			(clearance 0)
		)
		(min_thickness 0.25)
		(keepout
			(tracks allowed)
			(vias allowed)
			(pads allowed)
			(copperpour allowed)
			(footprints allowed)
		)
		(placement
			(enabled no)
			(sheetname "")
		)
		(fill
			(thermal_gap 0.5)
			(thermal_bridge_width 0.5)
			(island_removal_mode 0)
		)
		(polygon
			(pts
				(xy 79.121 -359.41) (xy 79.121 -362.458) (xy 77.597 -362.458) (xy 77.597 -359.41)
			)
		)
	)
	(zone
		(layer "F.Cu")
		(hatch none 0.5)
		(connect_pads
			(clearance 0)
		)
		(min_thickness 0.25)
		(keepout
			(tracks not_allowed)
			(vias allowed)
			(pads allowed)
			(copperpour not_allowed)
			(footprints allowed)
		)
		(placement
			(enabled no)
			(sheetname "")
		)
		(fill
			(thermal_gap 0.5)
			(thermal_bridge_width 0.5)
			(island_removal_mode 0)
		)
		(polygon
			(pts
				(arc
					(start 25.88514 -36.050982)
					(mid 25.273 -35.438842)
					(end 24.66086 -36.050982)
				)
				(xy 24.66086 -36.357306) (xy 24.825198 -36.357306)
				(arc
					(start 25.027382 -36.155122)
					(mid 25.461644 -35.862338)
					(end 25.16886 -36.2966)
				)
				(xy 24.908002 -36.557458) (xy 24.66086 -36.557458) (xy 24.66086 -36.66236) (xy 24.908256 -36.66236)
				(arc
					(start 25.16886 -36.922964)
					(mid 25.461644 -37.357226)
					(end 25.027382 -37.064442)
				)
				(xy 24.825452 -36.862512) (xy 24.66086 -36.862512)
				(arc
					(start 24.66086 -37.168328)
					(mid 25.272873 -37.780722)
					(end 25.88514 -37.168582)
				)
			)
		)
	)
	(zone
		(layer "F.Cu")
		(hatch none 0.5)
		(connect_pads
			(clearance 0)
		)
		(min_thickness 0.25)
		(keepout
			(tracks not_allowed)
			(vias allowed)
			(pads allowed)
			(copperpour not_allowed)
			(footprints allowed)
		)
		(placement
			(enabled no)
			(sheetname "")
		)
		(fill
			(thermal_gap 0.5)
			(thermal_bridge_width 0.5)
			(island_removal_mode 0)
		)
		(polygon
			(pts
				(arc
					(start 32.26054 -444.58509)
					(mid 31.750127 -444.074296)
					(end 31.23946 -444.584836)
				)
				(arc
					(start 31.23946 -445.397636)
					(mid 31.75 -445.908176)
					(end 32.26054 -445.397636)
				)
				(xy 32.26054 -445.243204) (xy 32.04591 -445.243204)
				(arc
					(start 31.995618 -445.293496)
					(mid 31.561356 -445.58628)
					(end 31.85414 -445.152018)
				)
				(xy 31.963106 -445.043052) (xy 32.26054 -445.043052) (xy 32.26054 -444.93815) (xy 31.961836 -444.93815)
				(arc
					(start 31.85414 -444.830454)
					(mid 31.561356 -444.396192)
					(end 31.995618 -444.688976)
				)
				(xy 32.04464 -444.737998) (xy 32.26054 -444.737998)
			)
		)
	)
	(zone
		(layer "F.Cu")
		(hatch none 0.5)
		(connect_pads
			(clearance 0)
		)
		(min_thickness 0.25)
		(keepout
			(tracks not_allowed)
			(vias allowed)
			(pads allowed)
			(copperpour not_allowed)
			(footprints allowed)
		)
		(placement
			(enabled no)
			(sheetname "")
		)
		(fill
			(thermal_gap 0.5)
			(thermal_bridge_width 0.5)
			(island_removal_mode 0)
		)
		(polygon
			(pts
				(arc
					(start 222.339154 -383.431542)
					(mid 221.727141 -382.819148)
					(end 221.114874 -383.431288)
				)
				(arc
					(start 221.114874 -384.548888)
					(mid 221.727014 -385.161028)
					(end 222.339154 -384.548888)
				)
				(xy 222.339154 -384.242818) (xy 222.174562 -384.242818)
				(arc
					(start 221.972632 -384.444748)
					(mid 221.53837 -384.737532)
					(end 221.831154 -384.30327)
				)
				(xy 222.091758 -384.042666) (xy 222.339154 -384.042666) (xy 222.339154 -383.937764) (xy 222.092012 -383.937764)
				(arc
					(start 221.831154 -383.676906)
					(mid 221.53837 -383.242644)
					(end 221.972632 -383.535428)
				)
				(xy 222.174816 -383.737612) (xy 222.339154 -383.737612)
			)
		)
	)
	(zone
		(layer "F.Cu")
		(hatch none 0.5)
		(connect_pads
			(clearance 0)
		)
		(min_thickness 0.25)
		(keepout
			(tracks not_allowed)
			(vias allowed)
			(pads allowed)
			(copperpour not_allowed)
			(footprints allowed)
		)
		(placement
			(enabled no)
			(sheetname "")
		)
		(fill
			(thermal_gap 0.5)
			(thermal_bridge_width 0.5)
			(island_removal_mode 0)
		)
		(polygon
			(pts
				(arc
					(start 7.502906 -333.986886)
					(mid 6.992493 -333.476092)
					(end 6.481826 -333.986632)
				)
				(xy 6.481826 -334.140302) (xy 6.697218 -334.140302)
				(arc
					(start 6.746748 -334.090772)
					(mid 7.18101 -333.797988)
					(end 6.888226 -334.23225)
				)
				(xy 6.780022 -334.340454) (xy 6.481826 -334.340454) (xy 6.481826 -334.445356) (xy 6.779768 -334.445356)
				(arc
					(start 6.888226 -334.553814)
					(mid 7.18101 -334.988076)
					(end 6.746748 -334.695292)
				)
				(xy 6.696964 -334.645508) (xy 6.481826 -334.645508)
				(arc
					(start 6.481826 -334.799432)
					(mid 6.992366 -335.309972)
					(end 7.502906 -334.799432)
				)
			)
		)
	)
	(zone
		(layer "F.Cu")
		(hatch none 0.5)
		(connect_pads
			(clearance 0)
		)
		(min_thickness 0.25)
		(keepout
			(tracks allowed)
			(vias allowed)
			(pads allowed)
			(copperpour allowed)
			(footprints allowed)
		)
		(placement
			(enabled no)
			(sheetname "")
		)
		(fill
			(thermal_gap 0.5)
			(thermal_bridge_width 0.5)
			(island_removal_mode 0)
		)
		(polygon
			(pts
				(xy 24.638 -11.049) (xy 24.638 -27.686) (xy 22.479 -27.686) (xy 22.479 -11.049)
			)
		)
	)
	(zone
		(layer "F.Cu")
		(hatch none 0.5)
		(connect_pads
			(clearance 0)
		)
		(min_thickness 0.25)
		(keepout
			(tracks allowed)
			(vias allowed)
			(pads allowed)
			(copperpour allowed)
			(footprints allowed)
		)
		(placement
			(enabled no)
			(sheetname "")
		)
		(fill
			(thermal_gap 0.5)
			(thermal_bridge_width 0.5)
			(island_removal_mode 0)
		)
		(polygon
			(pts
				(xy 229.235 -266.192) (xy 229.235 -268.478) (xy 227.076 -268.478) (xy 227.076 -266.192)
			)
		)
	)
	(zone
		(layer "F.Cu")
		(hatch none 0.5)
		(connect_pads
			(clearance 0)
		)
		(min_thickness 0.25)
		(keepout
			(tracks not_allowed)
			(vias allowed)
			(pads allowed)
			(copperpour not_allowed)
			(footprints allowed)
		)
		(placement
			(enabled no)
			(sheetname "")
		)
		(fill
			(thermal_gap 0.5)
			(thermal_bridge_width 0.5)
			(island_removal_mode 0)
		)
		(polygon
			(pts
				(arc
					(start 7.502906 -396.736062)
					(mid 6.992493 -396.225268)
					(end 6.481826 -396.735808)
				)
				(xy 6.481826 -396.889224) (xy 6.697472 -396.889224)
				(arc
					(start 6.746748 -396.839948)
					(mid 7.18101 -396.547164)
					(end 6.888226 -396.981426)
				)
				(xy 6.780276 -397.089376) (xy 6.481826 -397.089376) (xy 6.481826 -397.194278) (xy 6.779514 -397.194278)
				(arc
					(start 6.888226 -397.30299)
					(mid 7.18101 -397.737252)
					(end 6.746748 -397.444468)
				)
				(xy 6.69671 -397.39443) (xy 6.481826 -397.39443)
				(arc
					(start 6.481826 -397.548608)
					(mid 6.992366 -398.059148)
					(end 7.502906 -397.548608)
				)
			)
		)
	)
	(zone
		(layer "F.Cu")
		(hatch none 0.5)
		(connect_pads
			(clearance 0)
		)
		(min_thickness 0.25)
		(keepout
			(tracks not_allowed)
			(vias allowed)
			(pads allowed)
			(copperpour not_allowed)
			(footprints allowed)
		)
		(placement
			(enabled no)
			(sheetname "")
		)
		(fill
			(thermal_gap 0.5)
			(thermal_bridge_width 0.5)
			(island_removal_mode 0)
		)
		(polygon
			(pts
				(arc
					(start 35.84067 -466.583776)
					(mid 35.33013 -466.073236)
					(end 34.81959 -466.583776)
				)
				(arc
					(start 34.81959 -467.396322)
					(mid 35.330003 -467.907116)
					(end 35.84067 -467.396576)
				)
				(xy 35.84067 -467.242906) (xy 35.625278 -467.242906)
				(arc
					(start 35.575748 -467.292436)
					(mid 35.141486 -467.58522)
					(end 35.43427 -467.150958)
				)
				(xy 35.542474 -467.042754) (xy 35.84067 -467.042754) (xy 35.84067 -466.937852) (xy 35.542728 -466.937852)
				(arc
					(start 35.43427 -466.829394)
					(mid 35.141486 -466.395132)
					(end 35.575748 -466.687916)
				)
				(xy 35.625532 -466.7377) (xy 35.84067 -466.7377)
			)
		)
	)
	(zone
		(layer "F.Cu")
		(hatch none 0.5)
		(connect_pads
			(clearance 0)
		)
		(min_thickness 0.25)
		(keepout
			(tracks not_allowed)
			(vias allowed)
			(pads allowed)
			(copperpour not_allowed)
			(footprints allowed)
		)
		(placement
			(enabled no)
			(sheetname "")
		)
		(fill
			(thermal_gap 0.5)
			(thermal_bridge_width 0.5)
			(island_removal_mode 0)
		)
		(polygon
			(pts
				(xy 1.022096 -464.195922) (xy 3.758184 -464.195922) (xy 3.81 -464.247738) (xy 3.81 -464.439254)
				(xy 3.761232 -464.488022) (xy 1.025398 -464.488022) (xy 1.014984 -464.498436) (xy 1.010158 -464.498436)
				(xy 1.005332 -464.49361) (xy 1.005332 -464.191096) (xy 1.007872 -464.188556) (xy 1.01473 -464.188556)
			)
		)
	)
	(zone
		(net "P12V_SSD10")
		(layer "F.Cu")
		(hatch none 0.5)
		(connect_pads
			(clearance 0.5)
		)
		(min_thickness 0.25)
		(fill yes
			(thermal_gap 0.5)
			(thermal_bridge_width 0.5)
			(island_removal_mode 0)
		)
		(polygon
			(pts
				(xy 19.304 -409.702) (xy 18.796 -410.21) (xy 18.796 -414.528) (xy 20.193 -415.925) (xy 20.193 -416.814)
				(xy 18.542 -418.465) (xy 18.542 -424.071542) (xy 18.670778 -424.20032) (xy 21.204682 -424.20032)
				(xy 21.3106 -424.094402) (xy 21.3106 -422.1734) (xy 21.463 -422.021) (xy 22.606 -422.021) (xy 24.5872 -420.0398)
				(xy 28.9052 -420.0398) (xy 29.2354 -419.7096) (xy 30.7086 -419.7096) (xy 30.9372 -419.481) (xy 30.9372 -414.6804)
				(xy 30.7848 -414.528) (xy 24.003 -414.528) (xy 23.749 -414.274) (xy 23.749 -410.591) (xy 22.86 -409.702)
			)
		)
		(polygon
			(pts
				(xy 25.527 -419.3286) (xy 25.3238 -419.3286) (xy 25.3238 -419.5318) (xy 25.527 -419.5318)
			)
		)
		(polygon
			(pts
				(xy 24.9174 -419.3286) (xy 24.7142 -419.3286) (xy 24.7142 -419.5318) (xy 24.9174 -419.5318)
			)
		)
		(polygon
			(pts
				(xy 28.1178 -415.3154) (xy 27.9146 -415.3154) (xy 27.9146 -415.5186) (xy 28.1178 -415.5186)
			)
		)
		(polygon
			(pts
				(xy 27.2542 -415.3154) (xy 27.051 -415.3154) (xy 27.051 -415.5186) (xy 27.2542 -415.5186)
			)
		)
		(polygon
			(pts
				(xy 22.2504 -413.7914) (xy 22.0472 -413.7914) (xy 22.0472 -413.9946) (xy 22.2504 -413.9946)
			)
		)
		(polygon
			(pts
				(xy 21.1074 -413.7914) (xy 20.9042 -413.7914) (xy 20.9042 -413.9946) (xy 21.1074 -413.9946)
			)
		)
		(polygon
			(pts
				(xy 22.2504 -410.9974) (xy 22.0472 -410.9974) (xy 22.0472 -411.2006) (xy 22.2504 -411.2006)
			)
		)
		(polygon
			(pts
				(xy 21.1074 -410.9974) (xy 20.9042 -410.9974) (xy 20.9042 -411.2006) (xy 21.1074 -411.2006)
			)
		)
	)
	(zone
		(layer "F.Cu")
		(hatch none 0.5)
		(connect_pads
			(clearance 0)
		)
		(min_thickness 0.25)
		(keepout
			(tracks not_allowed)
			(vias allowed)
			(pads allowed)
			(copperpour not_allowed)
			(footprints allowed)
		)
		(placement
			(enabled no)
			(sheetname "")
		)
		(fill
			(thermal_gap 0.5)
			(thermal_bridge_width 0.5)
			(island_removal_mode 0)
		)
		(polygon
			(pts
				(arc
					(start 220.840554 -76.983844)
					(mid 220.330141 -76.47305)
					(end 219.819474 -76.98359)
				)
				(arc
					(start 219.819474 -77.79639)
					(mid 220.330014 -78.30693)
					(end 220.840554 -77.79639)
				)
				(xy 220.840554 -77.64272) (xy 220.625162 -77.64272)
				(arc
					(start 220.575632 -77.69225)
					(mid 220.14137 -77.985034)
					(end 220.434154 -77.550772)
				)
				(xy 220.542358 -77.442568) (xy 220.840554 -77.442568) (xy 220.840554 -77.337666) (xy 220.542612 -77.337666)
				(arc
					(start 220.434154 -77.229208)
					(mid 220.14137 -76.794946)
					(end 220.575632 -77.08773)
				)
				(xy 220.625416 -77.137514) (xy 220.840554 -77.137514)
			)
		)
	)
	(zone
		(layer "F.Cu")
		(hatch none 0.5)
		(connect_pads
			(clearance 0)
		)
		(min_thickness 0.25)
		(keepout
			(tracks not_allowed)
			(vias allowed)
			(pads allowed)
			(copperpour not_allowed)
			(footprints allowed)
		)
		(placement
			(enabled no)
			(sheetname "")
		)
		(fill
			(thermal_gap 0.5)
			(thermal_bridge_width 0.5)
			(island_removal_mode 0)
		)
		(polygon
			(pts
				(arc
					(start 7.502906 -207.936084)
					(mid 6.992493 -207.42529)
					(end 6.481826 -207.93583)
				)
				(xy 6.481826 -208.089246) (xy 6.697472 -208.089246)
				(arc
					(start 6.746748 -208.03997)
					(mid 7.18101 -207.747186)
					(end 6.888226 -208.181448)
				)
				(xy 6.780276 -208.289398) (xy 6.481826 -208.289398) (xy 6.481826 -208.3943) (xy 6.779514 -208.3943)
				(arc
					(start 6.888226 -208.503012)
					(mid 7.18101 -208.937274)
					(end 6.746748 -208.64449)
				)
				(xy 6.69671 -208.594452) (xy 6.481826 -208.594452)
				(arc
					(start 6.481826 -208.74863)
					(mid 6.992366 -209.25917)
					(end 7.502906 -208.74863)
				)
			)
		)
	)
	(zone
		(net "GND")
		(layer "F.Cu")
		(hatch none 0.5)
		(connect_pads
			(clearance 0.5)
		)
		(min_thickness 0.25)
		(fill yes
			(thermal_gap 0.5)
			(thermal_bridge_width 0.5)
			(island_removal_mode 0)
		)
		(polygon
			(pts
				(xy 209.521552 -430.022) (xy 209.267552 -430.276) (xy 209.267552 -432.308) (xy 209.521552 -432.562)
				(xy 212.823552 -432.562) (xy 213.077552 -432.308) (xy 213.077552 -431.927) (xy 213.229952 -431.7746)
				(xy 214.122 -431.7746) (xy 214.2744 -431.6222) (xy 214.2744 -430.276) (xy 214.0204 -430.022)
			)
		)
		(polygon
			(pts
				(xy 214.1474 -431.0634) (xy 213.9442 -431.0634) (xy 213.9442 -431.2666) (xy 214.1474 -431.2666)
			)
		)
		(polygon
			(pts
				(xy 213.5378 -431.0634) (xy 213.3346 -431.0634) (xy 213.3346 -431.2666) (xy 213.5378 -431.2666)
			)
		)
	)
	(zone
		(layer "F.Cu")
		(hatch none 0.5)
		(connect_pads
			(clearance 0)
		)
		(min_thickness 0.25)
		(keepout
			(tracks not_allowed)
			(vias allowed)
			(pads allowed)
			(copperpour not_allowed)
			(footprints allowed)
		)
		(placement
			(enabled no)
			(sheetname "")
		)
		(fill
			(thermal_gap 0.5)
			(thermal_bridge_width 0.5)
			(island_removal_mode 0)
		)
		(polygon
			(pts
				(arc
					(start 222.339154 -285.231586)
					(mid 221.727141 -284.619192)
					(end 221.114874 -285.231332)
				)
				(arc
					(start 221.114874 -286.348932)
					(mid 221.727014 -286.961072)
					(end 222.339154 -286.348932)
				)
				(xy 222.339154 -286.042608) (xy 222.174816 -286.042608)
				(arc
					(start 221.972632 -286.244792)
					(mid 221.53837 -286.537576)
					(end 221.831154 -286.103314)
				)
				(xy 222.092012 -285.842456) (xy 222.339154 -285.842456) (xy 222.339154 -285.737554) (xy 222.091758 -285.737554)
				(arc
					(start 221.831154 -285.47695)
					(mid 221.53837 -285.042688)
					(end 221.972632 -285.335472)
				)
				(xy 222.174562 -285.537402) (xy 222.339154 -285.537402)
			)
		)
	)
	(zone
		(layer "F.Cu")
		(hatch none 0.5)
		(connect_pads
			(clearance 0)
		)
		(min_thickness 0.25)
		(keepout
			(tracks not_allowed)
			(vias allowed)
			(pads allowed)
			(copperpour not_allowed)
			(footprints allowed)
		)
		(placement
			(enabled no)
			(sheetname "")
		)
		(fill
			(thermal_gap 0.5)
			(thermal_bridge_width 0.5)
			(island_removal_mode 0)
		)
		(polygon
			(pts
				(arc
					(start 35.84067 -54.583838)
					(mid 35.330257 -54.073044)
					(end 34.81959 -54.583584)
				)
				(arc
					(start 34.81959 -55.396384)
					(mid 35.33013 -55.906924)
					(end 35.84067 -55.396384)
				)
				(xy 35.84067 -55.242714) (xy 35.625278 -55.242714)
				(arc
					(start 35.575748 -55.292244)
					(mid 35.141486 -55.585028)
					(end 35.43427 -55.150766)
				)
				(xy 35.542474 -55.042562) (xy 35.84067 -55.042562) (xy 35.84067 -54.93766) (xy 35.542728 -54.93766)
				(arc
					(start 35.43427 -54.829202)
					(mid 35.141486 -54.39494)
					(end 35.575748 -54.687724)
				)
				(xy 35.625532 -54.737508) (xy 35.84067 -54.737508)
			)
		)
	)
	(zone
		(layer "F.Cu")
		(hatch none 0.5)
		(connect_pads
			(clearance 0)
		)
		(min_thickness 0.25)
		(keepout
			(tracks not_allowed)
			(vias allowed)
			(pads allowed)
			(copperpour not_allowed)
			(footprints allowed)
		)
		(placement
			(enabled no)
			(sheetname "")
		)
		(fill
			(thermal_gap 0.5)
			(thermal_bridge_width 0.5)
			(island_removal_mode 0)
		)
		(polygon
			(pts
				(arc
					(start 220.840554 -170.383962)
					(mid 220.330141 -169.873168)
					(end 219.819474 -170.383708)
				)
				(arc
					(start 219.819474 -171.196508)
					(mid 220.330014 -171.707048)
					(end 220.840554 -171.196508)
				)
				(xy 220.840554 -171.042584) (xy 220.625416 -171.042584)
				(arc
					(start 220.575632 -171.092368)
					(mid 220.14137 -171.385152)
					(end 220.434154 -170.95089)
				)
				(xy 220.542612 -170.842432) (xy 220.840554 -170.842432) (xy 220.840554 -170.73753) (xy 220.542358 -170.73753)
				(arc
					(start 220.434154 -170.629326)
					(mid 220.14137 -170.195064)
					(end 220.575632 -170.487848)
				)
				(xy 220.625162 -170.537378) (xy 220.840554 -170.537378)
			)
		)
	)
	(zone
		(net "GND")
		(layer "F.Cu")
		(hatch none 0.5)
		(connect_pads
			(clearance 0.5)
		)
		(min_thickness 0.25)
		(fill yes
			(thermal_gap 0.5)
			(thermal_bridge_width 0.5)
			(island_removal_mode 0)
		)
		(polygon
			(pts
				(xy 218.313 -187.1472) (xy 218.059 -187.4012) (xy 218.059 -188.8236) (xy 218.313 -189.0776) (xy 222.504 -189.0776)
				(xy 222.758 -188.8236) (xy 222.758 -187.325) (xy 222.5802 -187.1472)
			)
		)
		(polygon
			(pts
				(xy 222.4278 -188.3664) (xy 222.2246 -188.3664) (xy 222.2246 -188.5696) (xy 222.4278 -188.5696)
			)
		)
		(polygon
			(pts
				(xy 221.8182 -188.3664) (xy 221.615 -188.3664) (xy 221.615 -188.5696) (xy 221.8182 -188.5696)
			)
		)
	)
	(zone
		(layer "F.Cu")
		(hatch none 0.5)
		(connect_pads
			(clearance 0)
		)
		(min_thickness 0.25)
		(keepout
			(tracks not_allowed)
			(vias allowed)
			(pads allowed)
			(copperpour not_allowed)
			(footprints allowed)
		)
		(placement
			(enabled no)
			(sheetname "")
		)
		(fill
			(thermal_gap 0.5)
			(thermal_bridge_width 0.5)
			(island_removal_mode 0)
		)
		(polygon
			(pts
				(arc
					(start 37.33927 -69.631306)
					(mid 36.727257 -69.018912)
					(end 36.11499 -69.631052)
				)
				(arc
					(start 36.11499 -70.748652)
					(mid 36.72713 -71.360792)
					(end 37.33927 -70.748652)
				)
				(xy 37.33927 -70.442582) (xy 37.174678 -70.442582)
				(arc
					(start 36.972748 -70.644512)
					(mid 36.538486 -70.937296)
					(end 36.83127 -70.503034)
				)
				(xy 37.091874 -70.24243) (xy 37.33927 -70.24243) (xy 37.33927 -70.137528) (xy 37.092128 -70.137528)
				(arc
					(start 36.83127 -69.87667)
					(mid 36.538486 -69.442408)
					(end 36.972748 -69.735192)
				)
				(xy 37.174932 -69.937376) (xy 37.33927 -69.937376)
			)
		)
	)
	(zone
		(layer "F.Cu")
		(hatch none 0.5)
		(connect_pads
			(clearance 0)
		)
		(min_thickness 0.25)
		(keepout
			(tracks allowed)
			(vias allowed)
			(pads allowed)
			(copperpour allowed)
			(footprints allowed)
		)
		(placement
			(enabled no)
			(sheetname "")
		)
		(fill
			(thermal_gap 0.5)
			(thermal_bridge_width 0.5)
			(island_removal_mode 0)
		)
		(polygon
			(pts
				(xy 222.377 -161.925) (xy 222.377 -154.813) (xy 224.536 -154.813) (xy 224.536 -161.925)
			)
		)
	)
	(zone
		(layer "F.Cu")
		(hatch none 0.5)
		(connect_pads
			(clearance 0)
		)
		(min_thickness 0.25)
		(keepout
			(tracks allowed)
			(vias allowed)
			(pads allowed)
			(copperpour allowed)
			(footprints allowed)
		)
		(placement
			(enabled no)
			(sheetname "")
		)
		(fill
			(thermal_gap 0.5)
			(thermal_bridge_width 0.5)
			(island_removal_mode 0)
		)
		(polygon
			(pts
				(xy 24.638 -423.037) (xy 24.638 -439.674) (xy 22.479 -439.674) (xy 22.479 -423.037)
			)
		)
	)
	(zone
		(layer "F.Cu")
		(hatch none 0.5)
		(connect_pads
			(clearance 0)
		)
		(min_thickness 0.25)
		(keepout
			(tracks not_allowed)
			(vias allowed)
			(pads allowed)
			(copperpour not_allowed)
			(footprints allowed)
		)
		(placement
			(enabled no)
			(sheetname "")
		)
		(fill
			(thermal_gap 0.5)
			(thermal_bridge_width 0.5)
			(island_removal_mode 0)
		)
		(polygon
			(pts
				(arc
					(start 27.18054 -231.803448)
					(mid 26.67 -231.292908)
					(end 26.15946 -231.803448)
				)
				(xy 26.15946 -231.957372) (xy 26.374598 -231.957372)
				(arc
					(start 26.424382 -231.907588)
					(mid 26.858644 -231.614804)
					(end 26.56586 -232.049066)
				)
				(xy 26.457402 -232.157524) (xy 26.15946 -232.157524) (xy 26.15946 -232.262426) (xy 26.457656 -232.262426)
				(arc
					(start 26.56586 -232.37063)
					(mid 26.858644 -232.804892)
					(end 26.424382 -232.512108)
				)
				(xy 26.374852 -232.462578) (xy 26.15946 -232.462578)
				(arc
					(start 26.15946 -232.615994)
					(mid 26.669873 -233.126788)
					(end 27.18054 -232.616248)
				)
			)
		)
	)
	(zone
		(layer "F.Cu")
		(hatch none 0.5)
		(connect_pads
			(clearance 0)
		)
		(min_thickness 0.25)
		(keepout
			(tracks allowed)
			(vias allowed)
			(pads allowed)
			(copperpour allowed)
			(footprints allowed)
		)
		(placement
			(enabled no)
			(sheetname "")
		)
		(fill
			(thermal_gap 0.5)
			(thermal_bridge_width 0.5)
			(island_removal_mode 0)
		)
		(polygon
			(pts
				(xy 229.235 -369.189) (xy 229.235 -371.475) (xy 227.076 -371.475) (xy 227.076 -369.189)
			)
		)
	)
	(zone
		(net "GND")
		(layer "F.Cu")
		(hatch none 0.5)
		(connect_pads
			(clearance 0.5)
		)
		(min_thickness 0.25)
		(fill yes
			(thermal_gap 0.5)
			(thermal_bridge_width 0.5)
			(island_removal_mode 0)
		)
		(polygon
			(pts
				(xy 15.39748 -147.419822) (xy 15.047976 -147.769326) (xy 15.047976 -153.324052) (xy 15.425674 -153.70175)
				(xy 16.308832 -153.70175) (xy 16.774414 -154.167332) (xy 19.374104 -154.167332) (xy 20.638516 -152.90292)
				(xy 28.99791 -152.90292) (xy 29.66974 -152.23109) (xy 29.66974 -147.742402) (xy 29.34716 -147.419822)
			)
		)
	)
	(zone
		(net "P12V")
		(layer "F.Cu")
		(hatch none 0.5)
		(connect_pads
			(clearance 0.5)
		)
		(min_thickness 0.25)
		(fill yes
			(thermal_gap 0.5)
			(thermal_bridge_width 0.5)
			(island_removal_mode 0)
		)
		(polygon
			(pts
				(xy 24.0538 -293.37) (xy 23.9776 -293.4462) (xy 23.9776 -293.9034) (xy 24.0792 -294.005) (xy 24.5872 -294.005)
				(xy 24.9682 -294.386) (xy 24.9682 -295.1734) (xy 25.781 -295.9862) (xy 25.781 -296.799) (xy 26.543 -297.561)
				(xy 26.543 -298.8564) (xy 28.0416 -300.355) (xy 29.21 -300.355) (xy 29.4132 -300.1518) (xy 29.4132 -299.72)
				(xy 30.1498 -298.9834) (xy 30.1498 -294.4368) (xy 29.591 -293.878) (xy 26.2382 -293.878) (xy 25.7302 -293.37)
			)
		)
		(polygon
			(pts
				(xy 29.2481 -299.7073) (xy 29.0449 -299.7073) (xy 29.0449 -299.9105) (xy 29.2481 -299.9105)
			)
		)
		(polygon
			(pts
				(xy 28.6893 -299.7073) (xy 28.4861 -299.7073) (xy 28.4861 -299.9105) (xy 28.6893 -299.9105)
			)
		)
		(polygon
			(pts
				(xy 25.6286 -294.9194) (xy 25.4254 -294.9194) (xy 25.4254 -295.1226) (xy 25.6286 -295.1226)
			)
		)
		(polygon
			(pts
				(xy 25.6286 -294.3606) (xy 25.4254 -294.3606) (xy 25.4254 -294.5638) (xy 25.6286 -294.5638)
			)
		)
		(polygon
			(pts
				(xy 25.7302 -293.878) (xy 25.527 -293.878) (xy 25.527 -294.0812) (xy 25.7302 -294.0812)
			)
		)
		(polygon
			(pts
				(xy 25.1206 -293.878) (xy 24.9174 -293.878) (xy 24.9174 -294.0812) (xy 25.1206 -294.0812)
			)
		)
	)
	(zone
		(layer "F.Cu")
		(hatch none 0.5)
		(connect_pads
			(clearance 0)
		)
		(min_thickness 0.25)
		(keepout
			(tracks not_allowed)
			(vias allowed)
			(pads allowed)
			(copperpour not_allowed)
			(footprints allowed)
		)
		(placement
			(enabled no)
			(sheetname "")
		)
		(fill
			(thermal_gap 0.5)
			(thermal_bridge_width 0.5)
			(island_removal_mode 0)
		)
		(polygon
			(pts
				(arc
					(start 7.502906 -340.386924)
					(mid 6.992493 -339.87613)
					(end 6.481826 -340.38667)
				)
				(xy 6.481826 -340.54034) (xy 6.697218 -340.54034)
				(arc
					(start 6.746748 -340.49081)
					(mid 7.18101 -340.198026)
					(end 6.888226 -340.632288)
				)
				(xy 6.780022 -340.740492) (xy 6.481826 -340.740492) (xy 6.481826 -340.845394) (xy 6.779768 -340.845394)
				(arc
					(start 6.888226 -340.953852)
					(mid 7.18101 -341.388114)
					(end 6.746748 -341.09533)
				)
				(xy 6.696964 -341.045546) (xy 6.481826 -341.045546)
				(arc
					(start 6.481826 -341.19947)
					(mid 6.992366 -341.71001)
					(end 7.502906 -341.19947)
				)
			)
		)
	)
	(zone
		(layer "F.Cu")
		(hatch none 0.5)
		(connect_pads
			(clearance 0)
		)
		(min_thickness 0.25)
		(keepout
			(tracks allowed)
			(vias allowed)
			(pads allowed)
			(copperpour allowed)
			(footprints allowed)
		)
		(placement
			(enabled no)
			(sheetname "")
		)
		(fill
			(thermal_gap 0.5)
			(thermal_bridge_width 0.5)
			(island_removal_mode 0)
		)
		(polygon
			(pts
				(xy 87.63 -309.118) (xy 87.63 -305.054) (xy 83.439 -305.054) (xy 83.439 -304.292) (xy 88.011 -304.292)
				(xy 88.011 -301.244) (xy 89.916 -301.244) (xy 89.916 -309.118)
			)
		)
	)
	(zone
		(layer "F.Cu")
		(hatch none 0.5)
		(connect_pads
			(clearance 0)
		)
		(min_thickness 0.25)
		(keepout
			(tracks not_allowed)
			(vias allowed)
			(pads allowed)
			(copperpour not_allowed)
			(footprints allowed)
		)
		(placement
			(enabled no)
			(sheetname "")
		)
		(fill
			(thermal_gap 0.5)
			(thermal_bridge_width 0.5)
			(island_removal_mode 0)
		)
		(polygon
			(pts
				(arc
					(start 7.502906 -393.535916)
					(mid 6.992493 -393.025122)
					(end 6.481826 -393.535662)
				)
				(xy 6.481826 -393.689332) (xy 6.697218 -393.689332)
				(arc
					(start 6.746748 -393.639802)
					(mid 7.18101 -393.347018)
					(end 6.888226 -393.78128)
				)
				(xy 6.780022 -393.889484) (xy 6.481826 -393.889484) (xy 6.481826 -393.994386) (xy 6.779768 -393.994386)
				(arc
					(start 6.888226 -394.102844)
					(mid 7.18101 -394.537106)
					(end 6.746748 -394.244322)
				)
				(xy 6.696964 -394.194538) (xy 6.481826 -394.194538)
				(arc
					(start 6.481826 -394.348462)
					(mid 6.992366 -394.859002)
					(end 7.502906 -394.348462)
				)
			)
		)
	)
	(zone
		(net "GND")
		(layer "F.Cu")
		(hatch none 0.5)
		(connect_pads
			(clearance 0.5)
		)
		(min_thickness 0.25)
		(fill yes
			(thermal_gap 0.5)
			(thermal_bridge_width 0.5)
			(island_removal_mode 0)
		)
		(polygon
			(pts
				(xy 36.1442 -392.4554) (xy 35.5092 -393.0904) (xy 33.0454 -393.0904) (xy 32.893 -393.2428) (xy 32.893 -393.6746)
				(xy 33.9344 -394.716) (xy 36.0426 -394.716) (xy 36.6268 -394.1318) (xy 37.338 -394.1318) (xy 37.846 -393.6238)
				(xy 37.846 -392.7094) (xy 37.592 -392.4554)
			)
		)
		(polygon
			(pts
				(xy 37.4396 -393.4206) (xy 37.2364 -393.4206) (xy 37.2364 -393.6238) (xy 37.4396 -393.6238)
			)
		)
		(polygon
			(pts
				(xy 36.83 -393.4206) (xy 36.6268 -393.4206) (xy 36.6268 -393.6238) (xy 36.83 -393.6238)
			)
		)
	)
	(zone
		(layer "F.Cu")
		(hatch none 0.5)
		(connect_pads
			(clearance 0)
		)
		(min_thickness 0.25)
		(keepout
			(tracks not_allowed)
			(vias allowed)
			(pads allowed)
			(copperpour not_allowed)
			(footprints allowed)
		)
		(placement
			(enabled no)
			(sheetname "")
		)
		(fill
			(thermal_gap 0.5)
			(thermal_bridge_width 0.5)
			(island_removal_mode 0)
		)
		(polygon
			(pts
				(arc
					(start 25.88514 -345.05138)
					(mid 25.273127 -344.438986)
					(end 24.66086 -345.051126)
				)
				(xy 24.66086 -345.36507) (xy 24.817578 -345.36507)
				(arc
					(start 25.027382 -345.155266)
					(mid 25.461644 -344.862482)
					(end 25.16886 -345.296744)
				)
				(xy 24.900382 -345.565222) (xy 24.66086 -345.565222) (xy 24.66086 -345.670124) (xy 24.915876 -345.670124)
				(arc
					(start 25.16886 -345.923108)
					(mid 25.461644 -346.35737)
					(end 25.027382 -346.064586)
				)
				(xy 24.833072 -345.870276) (xy 24.66086 -345.870276)
				(arc
					(start 24.66086 -346.168726)
					(mid 25.273 -346.780866)
					(end 25.88514 -346.168726)
				)
			)
		)
	)
	(zone
		(net "P12V")
		(layer "F.Cu")
		(hatch none 0.5)
		(connect_pads
			(clearance 0.5)
		)
		(min_thickness 0.25)
		(fill yes
			(thermal_gap 0.5)
			(thermal_bridge_width 0.5)
			(island_removal_mode 0)
		)
		(polygon
			(pts
				(xy 45.602652 -7.5946) (xy 45.334174 -7.863078) (xy 45.334174 -8.327898) (xy 44.6786 -8.983472)
				(xy 44.6786 -13.8684) (xy 44.9072 -14.097) (xy 48.006 -14.097) (xy 48.6156 -14.7066) (xy 50.3174 -14.7066)
				(xy 50.419 -14.605) (xy 50.419 -14.097) (xy 50.292 -13.97) (xy 49.657 -13.97) (xy 49.3776 -13.6906)
				(xy 49.3776 -12.9286) (xy 49.022 -12.573) (xy 49.022 -11.176) (xy 47.9806 -10.1346) (xy 47.9806 -8.8646)
				(xy 46.7106 -7.5946)
			)
		)
		(polygon
			(pts
				(xy 49.4284 -13.9954) (xy 49.2252 -13.9954) (xy 49.2252 -14.1986) (xy 49.4284 -14.1986)
			)
		)
		(polygon
			(pts
				(xy 48.8188 -13.9954) (xy 48.6156 -13.9954) (xy 48.6156 -14.1986) (xy 48.8188 -14.1986)
			)
		)
		(polygon
			(pts
				(xy 48.9204 -13.5128) (xy 48.7172 -13.5128) (xy 48.7172 -13.716) (xy 48.9204 -13.716)
			)
		)
		(polygon
			(pts
				(xy 48.9204 -12.954) (xy 48.7172 -12.954) (xy 48.7172 -13.1572) (xy 48.9204 -13.1572)
			)
		)
		(polygon
			(pts
				(xy 46.3169 -8.0645) (xy 46.1137 -8.0645) (xy 46.1137 -8.2677) (xy 46.3169 -8.2677)
			)
		)
		(polygon
			(pts
				(xy 45.7581 -8.0645) (xy 45.5549 -8.0645) (xy 45.5549 -8.2677) (xy 45.7581 -8.2677)
			)
		)
	)
	(zone
		(net "GND")
		(layer "F.Cu")
		(hatch none 0.5)
		(connect_pads
			(clearance 0.5)
		)
		(min_thickness 0.25)
		(fill yes
			(thermal_gap 0.5)
			(thermal_bridge_width 0.5)
			(island_removal_mode 0)
		)
		(polygon
			(pts
				(xy 40.67429 -339.00491) (xy 39.9288 -339.7504) (xy 39.9288 -342.74633) (xy 40.56507 -343.3826)
				(xy 41.960546 -343.3826) (xy 42.042588 -343.300558) (xy 42.042588 -342.767412) (xy 42.562018 -342.247982)
				(xy 44.492418 -342.247982) (xy 45.637704 -341.102696) (xy 51.424078 -341.102696) (xy 52.056284 -341.734902)
				(xy 52.056284 -345.099132) (xy 49.758346 -347.39707) (xy 49.758346 -351.184972) (xy 49.008284 -351.935034)
				(xy 46.093126 -351.935034) (xy 45.394118 -352.634042) (xy 45.394118 -357.833168) (xy 45.85462 -358.29367)
				(xy 48.05807 -358.29367) (xy 64.143382 -342.208358) (xy 72.11695 -342.208358) (xy 73.402698 -340.92261)
				(xy 73.402698 -339.626956) (xy 72.780652 -339.00491)
			)
		)
	)
	(zone
		(net "GND")
		(layer "F.Cu")
		(hatch none 0.5)
		(connect_pads
			(clearance 0.5)
		)
		(min_thickness 0.25)
		(fill yes
			(thermal_gap 0.5)
			(thermal_bridge_width 0.5)
			(island_removal_mode 0)
		)
		(polygon
			(pts
				(xy 93.011244 -109.640624) (xy 92.879164 -109.772704) (xy 92.879164 -111.55426) (xy 93.207332 -111.882428)
				(xy 94.50705 -111.882428) (xy 94.894908 -111.49457) (xy 94.894908 -109.753908) (xy 94.781624 -109.640624)
			)
		)
		(polygon
			(pts
				(xy 94.2848 -110.1344) (xy 93.8022 -110.1344) (xy 93.8022 -110.3376) (xy 94.2848 -110.3376)
			)
		)
		(polygon
			(pts
				(xy 93.3958 -110.1344) (xy 93.1926 -110.1344) (xy 93.1926 -110.3376) (xy 93.3958 -110.3376)
			)
		)
	)
	(zone
		(layer "F.Cu")
		(hatch none 0.5)
		(connect_pads
			(clearance 0)
		)
		(min_thickness 0.25)
		(keepout
			(tracks not_allowed)
			(vias allowed)
			(pads allowed)
			(copperpour not_allowed)
			(footprints allowed)
		)
		(placement
			(enabled no)
			(sheetname "")
		)
		(fill
			(thermal_gap 0.5)
			(thermal_bridge_width 0.5)
			(island_removal_mode 0)
		)
		(polygon
			(pts
				(arc
					(start 7.502906 -211.13623)
					(mid 6.992493 -210.625436)
					(end 6.481826 -211.135976)
				)
				(xy 6.481826 -211.289392) (xy 6.697472 -211.289392)
				(arc
					(start 6.746748 -211.240116)
					(mid 7.18101 -210.947332)
					(end 6.888226 -211.381594)
				)
				(xy 6.780276 -211.489544) (xy 6.481826 -211.489544) (xy 6.481826 -211.594446) (xy 6.779514 -211.594446)
				(arc
					(start 6.888226 -211.703158)
					(mid 7.18101 -212.13742)
					(end 6.746748 -211.844636)
				)
				(xy 6.69671 -211.794598) (xy 6.481826 -211.794598)
				(arc
					(start 6.481826 -211.948776)
					(mid 6.992366 -212.459316)
					(end 7.502906 -211.948776)
				)
			)
		)
	)
	(zone
		(layer "F.Cu")
		(hatch none 0.5)
		(connect_pads
			(clearance 0)
		)
		(min_thickness 0.25)
		(keepout
			(tracks not_allowed)
			(vias allowed)
			(pads allowed)
			(copperpour not_allowed)
			(footprints allowed)
		)
		(placement
			(enabled no)
			(sheetname "")
		)
		(fill
			(thermal_gap 0.5)
			(thermal_bridge_width 0.5)
			(island_removal_mode 0)
		)
		(polygon
			(pts
				(arc
					(start 35.84067 -273.38401)
					(mid 35.330257 -272.873216)
					(end 34.81959 -273.383756)
				)
				(arc
					(start 34.81959 -274.196556)
					(mid 35.33013 -274.707096)
					(end 35.84067 -274.196556)
				)
				(xy 35.84067 -274.042632) (xy 35.625532 -274.042632)
				(arc
					(start 35.575748 -274.092416)
					(mid 35.141486 -274.3852)
					(end 35.43427 -273.950938)
				)
				(xy 35.542728 -273.84248) (xy 35.84067 -273.84248) (xy 35.84067 -273.737578) (xy 35.542474 -273.737578)
				(arc
					(start 35.43427 -273.629374)
					(mid 35.141486 -273.195112)
					(end 35.575748 -273.487896)
				)
				(xy 35.625278 -273.537426) (xy 35.84067 -273.537426)
			)
		)
	)
	(zone
		(layer "F.Cu")
		(hatch none 0.5)
		(connect_pads
			(clearance 0)
		)
		(min_thickness 0.25)
		(keepout
			(tracks not_allowed)
			(vias allowed)
			(pads allowed)
			(copperpour not_allowed)
			(footprints allowed)
		)
		(placement
			(enabled no)
			(sheetname "")
		)
		(fill
			(thermal_gap 0.5)
			(thermal_bridge_width 0.5)
			(island_removal_mode 0)
		)
		(polygon
			(pts
				(arc
					(start 17.78254 -341.60333)
					(mid 17.272 -341.09279)
					(end 16.76146 -341.60333)
				)
				(arc
					(start 16.76146 -342.415876)
					(mid 17.271873 -342.92667)
					(end 17.78254 -342.41613)
				)
				(xy 17.78254 -342.262206) (xy 17.567402 -342.262206)
				(arc
					(start 17.517618 -342.31199)
					(mid 17.083356 -342.604774)
					(end 17.37614 -342.170512)
				)
				(xy 17.484598 -342.062054) (xy 17.78254 -342.062054) (xy 17.78254 -341.957152) (xy 17.484344 -341.957152)
				(arc
					(start 17.37614 -341.848948)
					(mid 17.083356 -341.414686)
					(end 17.517618 -341.70747)
				)
				(xy 17.567148 -341.757) (xy 17.78254 -341.757)
			)
		)
	)
	(zone
		(layer "F.Cu")
		(hatch none 0.5)
		(connect_pads
			(clearance 0)
		)
		(min_thickness 0.25)
		(keepout
			(tracks not_allowed)
			(vias allowed)
			(pads allowed)
			(copperpour not_allowed)
			(footprints allowed)
		)
		(placement
			(enabled no)
			(sheetname "")
		)
		(fill
			(thermal_gap 0.5)
			(thermal_bridge_width 0.5)
			(island_removal_mode 0)
		)
		(polygon
			(pts
				(arc
					(start 37.33927 -74.431398)
					(mid 36.727257 -73.819004)
					(end 36.11499 -74.431144)
				)
				(arc
					(start 36.11499 -75.548744)
					(mid 36.72713 -76.160884)
					(end 37.33927 -75.548744)
				)
				(xy 37.33927 -75.242674) (xy 37.174678 -75.242674)
				(arc
					(start 36.972748 -75.444604)
					(mid 36.538486 -75.737388)
					(end 36.83127 -75.303126)
				)
				(xy 37.091874 -75.042522) (xy 37.33927 -75.042522) (xy 37.33927 -74.93762) (xy 37.092128 -74.93762)
				(arc
					(start 36.83127 -74.676762)
					(mid 36.538486 -74.2425)
					(end 36.972748 -74.535284)
				)
				(xy 37.174932 -74.737468) (xy 37.33927 -74.737468)
			)
		)
	)
	(zone
		(layer "F.Cu")
		(hatch none 0.5)
		(connect_pads
			(clearance 0)
		)
		(min_thickness 0.25)
		(keepout
			(tracks not_allowed)
			(vias allowed)
			(pads allowed)
			(copperpour not_allowed)
			(footprints allowed)
		)
		(placement
			(enabled no)
			(sheetname "")
		)
		(fill
			(thermal_gap 0.5)
			(thermal_bridge_width 0.5)
			(island_removal_mode 0)
		)
		(polygon
			(pts
				(xy 1.022096 -458.59573) (xy 3.758184 -458.59573) (xy 3.81 -458.647546) (xy 3.81 -458.839062) (xy 3.761232 -458.88783)
				(xy 1.025398 -458.88783) (xy 1.014984 -458.898244) (xy 1.010158 -458.898244) (xy 1.005332 -458.893418)
				(xy 1.005332 -458.590904) (xy 1.007872 -458.588364) (xy 1.01473 -458.588364)
			)
		)
	)
	(zone
		(layer "F.Cu")
		(hatch none 0.5)
		(connect_pads
			(clearance 0)
		)
		(min_thickness 0.25)
		(keepout
			(tracks not_allowed)
			(vias allowed)
			(pads allowed)
			(copperpour not_allowed)
			(footprints allowed)
		)
		(placement
			(enabled no)
			(sheetname "")
		)
		(fill
			(thermal_gap 0.5)
			(thermal_bridge_width 0.5)
			(island_removal_mode 0)
		)
		(polygon
			(pts
				(arc
					(start 27.18054 -21.003514)
					(mid 26.67 -20.492974)
					(end 26.15946 -21.003514)
				)
				(xy 26.15946 -21.157184) (xy 26.374852 -21.157184)
				(arc
					(start 26.424382 -21.107654)
					(mid 26.858644 -20.81487)
					(end 26.56586 -21.249132)
				)
				(xy 26.457656 -21.357336) (xy 26.15946 -21.357336) (xy 26.15946 -21.462238) (xy 26.457402 -21.462238)
				(arc
					(start 26.56586 -21.570696)
					(mid 26.858644 -22.004958)
					(end 26.424382 -21.712174)
				)
				(xy 26.374598 -21.66239) (xy 26.15946 -21.66239)
				(arc
					(start 26.15946 -21.81606)
					(mid 26.669873 -22.326854)
					(end 27.18054 -21.816314)
				)
			)
		)
	)
	(zone
		(net "P12V_SSD3")
		(layer "F.Cu")
		(hatch none 0.5)
		(connect_pads
			(clearance 0.5)
		)
		(min_thickness 0.25)
		(fill yes
			(thermal_gap 0.5)
			(thermal_bridge_width 0.5)
			(island_removal_mode 0)
		)
		(polygon
			(pts
				(xy 225.910648 -184.749186) (xy 225.806 -184.853834) (xy 225.806 -186.69) (xy 225.552 -186.944)
				(xy 225.1202 -186.944) (xy 222.6818 -189.3824) (xy 216.5096 -189.3824) (xy 216.2556 -189.6364) (xy 216.2556 -194.1322)
				(xy 216.4842 -194.3608) (xy 223.2152 -194.3608) (xy 223.5962 -194.7418) (xy 223.5962 -199.0598)
				(xy 224.0788 -199.5424) (xy 227.6348 -199.5424) (xy 228.219 -198.9582) (xy 228.219 -194.437) (xy 226.822 -193.04)
				(xy 226.822 -192.151) (xy 228.473 -190.5) (xy 228.473 -184.874154) (xy 228.348032 -184.749186)
			)
		)
		(polygon
			(pts
				(xy 226.5934 -198.0438) (xy 226.3902 -198.0438) (xy 226.3902 -198.247) (xy 226.5934 -198.247)
			)
		)
		(polygon
			(pts
				(xy 225.4504 -198.0438) (xy 225.2472 -198.0438) (xy 225.2472 -198.247) (xy 225.4504 -198.247)
			)
		)
		(polygon
			(pts
				(xy 226.5934 -195.2498) (xy 226.3902 -195.2498) (xy 226.3902 -195.453) (xy 226.5934 -195.453)
			)
		)
		(polygon
			(pts
				(xy 225.4504 -195.2498) (xy 225.2472 -195.2498) (xy 225.2472 -195.453) (xy 225.4504 -195.453)
			)
		)
		(polygon
			(pts
				(xy 220.2434 -193.294) (xy 220.0402 -193.294) (xy 220.0402 -193.4972) (xy 220.2434 -193.4972)
			)
		)
		(polygon
			(pts
				(xy 219.3798 -193.294) (xy 219.1766 -193.294) (xy 219.1766 -193.4972) (xy 219.3798 -193.4972)
			)
		)
		(polygon
			(pts
				(xy 222.4278 -189.8904) (xy 222.2246 -189.8904) (xy 222.2246 -190.0936) (xy 222.4278 -190.0936)
			)
		)
		(polygon
			(pts
				(xy 221.8182 -189.8904) (xy 221.615 -189.8904) (xy 221.615 -190.0936) (xy 221.8182 -190.0936)
			)
		)
	)
	(zone
		(layer "F.Cu")
		(hatch none 0.5)
		(connect_pads
			(clearance 0)
		)
		(min_thickness 0.25)
		(keepout
			(tracks not_allowed)
			(vias allowed)
			(pads allowed)
			(copperpour not_allowed)
			(footprints allowed)
		)
		(placement
			(enabled no)
			(sheetname "")
		)
		(fill
			(thermal_gap 0.5)
			(thermal_bridge_width 0.5)
			(island_removal_mode 0)
		)
		(polygon
			(pts
				(arc
					(start 7.502906 -325.136002)
					(mid 6.992366 -324.625462)
					(end 6.481826 -325.136002)
				)
				(xy 6.481826 -325.289418) (xy 6.697472 -325.289418)
				(arc
					(start 6.746748 -325.240142)
					(mid 7.18101 -324.947358)
					(end 6.888226 -325.38162)
				)
				(xy 6.780276 -325.48957) (xy 6.481826 -325.48957) (xy 6.481826 -325.594472) (xy 6.779514 -325.594472)
				(arc
					(start 6.888226 -325.703184)
					(mid 7.18101 -326.137446)
					(end 6.746748 -325.844662)
				)
				(xy 6.69671 -325.794624) (xy 6.481826 -325.794624)
				(arc
					(start 6.481826 -325.948548)
					(mid 6.992239 -326.459342)
					(end 7.502906 -325.948802)
				)
			)
		)
	)
	(zone
		(layer "F.Cu")
		(hatch none 0.5)
		(connect_pads
			(clearance 0)
		)
		(min_thickness 0.25)
		(keepout
			(tracks allowed)
			(vias allowed)
			(pads allowed)
			(copperpour allowed)
			(footprints allowed)
		)
		(placement
			(enabled no)
			(sheetname "")
		)
		(fill
			(thermal_gap 0.5)
			(thermal_bridge_width 0.5)
			(island_removal_mode 0)
		)
		(polygon
			(pts
				(xy 17.78 -239.776) (xy 17.78 -237.49) (xy 19.939 -237.49) (xy 19.939 -239.776)
			)
		)
	)
	(zone
		(layer "F.Cu")
		(hatch none 0.5)
		(connect_pads
			(clearance 0)
		)
		(min_thickness 0.25)
		(keepout
			(tracks allowed)
			(vias allowed)
			(pads allowed)
			(copperpour allowed)
			(footprints allowed)
		)
		(placement
			(enabled no)
			(sheetname "")
		)
		(fill
			(thermal_gap 0.5)
			(thermal_bridge_width 0.5)
			(island_removal_mode 0)
		)
		(polygon
			(pts
				(xy 87.63 -105.537) (xy 87.63 -101.473) (xy 83.439 -101.473) (xy 83.439 -100.711) (xy 88.011 -100.711)
				(xy 88.011 -97.663) (xy 89.916 -97.663) (xy 89.916 -105.537)
			)
		)
	)
	(zone
		(layer "F.Cu")
		(hatch none 0.5)
		(connect_pads
			(clearance 0)
		)
		(min_thickness 0.25)
		(keepout
			(tracks not_allowed)
			(vias allowed)
			(pads allowed)
			(copperpour not_allowed)
			(footprints allowed)
		)
		(placement
			(enabled no)
			(sheetname "")
		)
		(fill
			(thermal_gap 0.5)
			(thermal_bridge_width 0.5)
			(island_removal_mode 0)
		)
		(polygon
			(pts
				(arc
					(start 222.339154 -365.831628)
					(mid 221.727141 -365.219234)
					(end 221.114874 -365.831374)
				)
				(arc
					(start 221.114874 -366.948974)
					(mid 221.727014 -367.561114)
					(end 222.339154 -366.948974)
				)
				(xy 222.339154 -366.64265) (xy 222.174816 -366.64265)
				(arc
					(start 221.972632 -366.844834)
					(mid 221.53837 -367.137618)
					(end 221.831154 -366.703356)
				)
				(xy 222.092012 -366.442498) (xy 222.339154 -366.442498) (xy 222.339154 -366.337596) (xy 222.091758 -366.337596)
				(arc
					(start 221.831154 -366.076992)
					(mid 221.53837 -365.64273)
					(end 221.972632 -365.935514)
				)
				(xy 222.174562 -366.137444) (xy 222.339154 -366.137444)
			)
		)
	)
	(zone
		(layer "F.Cu")
		(hatch none 0.5)
		(connect_pads
			(clearance 0)
		)
		(min_thickness 0.25)
		(keepout
			(tracks allowed)
			(vias allowed)
			(pads allowed)
			(copperpour allowed)
			(footprints allowed)
		)
		(placement
			(enabled no)
			(sheetname "")
		)
		(fill
			(thermal_gap 0.5)
			(thermal_bridge_width 0.5)
			(island_removal_mode 0)
		)
		(polygon
			(pts
				(xy 222.377 -494.919) (xy 222.377 -478.282) (xy 224.536 -478.282) (xy 224.536 -494.919)
			)
		)
	)
	(zone
		(net "P12V_SSD9")
		(layer "F.Cu")
		(hatch none 0.5)
		(connect_pads
			(clearance 0.5)
		)
		(min_thickness 0.25)
		(fill yes
			(thermal_gap 0.5)
			(thermal_bridge_width 0.5)
			(island_removal_mode 0)
		)
		(polygon
			(pts
				(xy 40.845232 -81.71307) (xy 40.7162 -81.842102) (xy 40.7162 -83.7438) (xy 40.513 -83.947) (xy 39.7256 -83.947)
				(xy 37.5666 -86.106) (xy 32.893 -86.106) (xy 32.4866 -86.5124) (xy 31.3944 -86.5124) (xy 31.3182 -86.5886)
				(xy 31.3182 -91.0336) (xy 31.623 -91.3384) (xy 37.8714 -91.3384) (xy 38.227 -91.694) (xy 38.227 -95.6564)
				(xy 38.862 -96.2914) (xy 41.9862 -96.2914) (xy 43.18 -95.0976) (xy 43.18 -91.44) (xy 41.783 -90.043)
				(xy 41.783 -89.154) (xy 43.434 -87.503) (xy 43.434 -81.962752) (xy 43.184318 -81.71307)
			)
		)
		(polygon
			(pts
				(xy 41.402 -94.8436) (xy 41.1988 -94.8436) (xy 41.1988 -95.0468) (xy 41.402 -95.0468)
			)
		)
		(polygon
			(pts
				(xy 40.259 -94.8436) (xy 40.0558 -94.8436) (xy 40.0558 -95.0468) (xy 40.259 -95.0468)
			)
		)
		(polygon
			(pts
				(xy 41.402 -92.0496) (xy 41.1988 -92.0496) (xy 41.1988 -92.2528) (xy 41.402 -92.2528)
			)
		)
		(polygon
			(pts
				(xy 40.259 -92.0496) (xy 40.0558 -92.0496) (xy 40.0558 -92.2528) (xy 40.259 -92.2528)
			)
		)
		(polygon
			(pts
				(xy 37.7698 -90.2716) (xy 37.5666 -90.2716) (xy 37.5666 -90.4748) (xy 37.7698 -90.4748)
			)
		)
		(polygon
			(pts
				(xy 36.9062 -90.2716) (xy 36.703 -90.2716) (xy 36.703 -90.4748) (xy 36.9062 -90.4748)
			)
		)
		(polygon
			(pts
				(xy 37.4142 -86.614) (xy 37.211 -86.614) (xy 37.211 -86.8172) (xy 37.4142 -86.8172)
			)
		)
		(polygon
			(pts
				(xy 36.8046 -86.614) (xy 36.6014 -86.614) (xy 36.6014 -86.8172) (xy 36.8046 -86.8172)
			)
		)
	)
	(zone
		(layer "F.Cu")
		(hatch none 0.5)
		(connect_pads
			(clearance 0)
		)
		(min_thickness 0.25)
		(keepout
			(tracks allowed)
			(vias allowed)
			(pads allowed)
			(copperpour allowed)
			(footprints allowed)
		)
		(placement
			(enabled no)
			(sheetname "")
		)
		(fill
			(thermal_gap 0.5)
			(thermal_bridge_width 0.5)
			(island_removal_mode 0)
		)
		(polygon
			(pts
				(xy 94.869 -204.216) (xy 94.996 -204.089) (xy 94.996 -202.311) (xy 99.06 -202.311) (xy 99.06 -204.47)
				(xy 97.917 -205.613) (xy 97.917 -206.756) (xy 93.091 -206.756) (xy 93.091 -204.216)
			)
		)
	)
	(zone
		(layer "F.Cu")
		(hatch none 0.5)
		(connect_pads
			(clearance 0)
		)
		(min_thickness 0.25)
		(keepout
			(tracks not_allowed)
			(vias allowed)
			(pads allowed)
			(copperpour not_allowed)
			(footprints allowed)
		)
		(placement
			(enabled no)
			(sheetname "")
		)
		(fill
			(thermal_gap 0.5)
			(thermal_bridge_width 0.5)
			(island_removal_mode 0)
		)
		(polygon
			(pts
				(arc
					(start 27.18054 -428.203868)
					(mid 26.670127 -427.693074)
					(end 26.15946 -428.203614)
				)
				(xy 26.15946 -428.382684) (xy 26.349452 -428.382684)
				(arc
					(start 26.424382 -428.307754)
					(mid 26.858644 -428.01497)
					(end 26.56586 -428.449232)
				)
				(xy 26.432256 -428.582836) (xy 26.15946 -428.582836) (xy 26.15946 -428.687738) (xy 26.482802 -428.687738)
				(arc
					(start 26.56586 -428.770796)
					(mid 26.858644 -429.205058)
					(end 26.424382 -428.912274)
				)
				(xy 26.399998 -428.88789) (xy 26.15946 -428.88789)
				(arc
					(start 26.15946 -429.016414)
					(mid 26.67 -429.526954)
					(end 27.18054 -429.016414)
				)
			)
		)
	)
	(zone
		(net "GND")
		(layer "F.Cu")
		(hatch none 0.5)
		(connect_pads
			(clearance 0.5)
		)
		(min_thickness 0.25)
		(fill yes
			(thermal_gap 0.5)
			(thermal_bridge_width 0.5)
			(island_removal_mode 0)
		)
		(polygon
			(pts
				(xy 24.5364 -308.8132) (xy 24.0538 -309.2958) (xy 24.0538 -311.2008) (xy 24.2316 -311.3786) (xy 27.9908 -311.3786)
				(xy 28.2702 -311.0992) (xy 28.2702 -309.3974) (xy 27.686 -308.8132)
			)
		)
		(polygon
			(pts
				(xy 25.3238 -310.261) (xy 25.1206 -310.261) (xy 25.1206 -310.4642) (xy 25.3238 -310.4642)
			)
		)
		(polygon
			(pts
				(xy 24.4602 -310.261) (xy 24.257 -310.261) (xy 24.257 -310.4642) (xy 24.4602 -310.4642)
			)
		)
	)
	(zone
		(layer "F.Cu")
		(hatch none 0.5)
		(connect_pads
			(clearance 0)
		)
		(min_thickness 0.25)
		(keepout
			(tracks not_allowed)
			(vias allowed)
			(pads allowed)
			(copperpour not_allowed)
			(footprints allowed)
		)
		(placement
			(enabled no)
			(sheetname "")
		)
		(fill
			(thermal_gap 0.5)
			(thermal_bridge_width 0.5)
			(island_removal_mode 0)
		)
		(polygon
			(pts
				(arc
					(start 7.502906 -192.736216)
					(mid 6.992493 -192.225422)
					(end 6.481826 -192.735962)
				)
				(xy 6.481826 -192.889378) (xy 6.697472 -192.889378)
				(arc
					(start 6.746748 -192.840102)
					(mid 7.18101 -192.547318)
					(end 6.888226 -192.98158)
				)
				(xy 6.780276 -193.08953) (xy 6.481826 -193.08953) (xy 6.481826 -193.194432) (xy 6.779514 -193.194432)
				(arc
					(start 6.888226 -193.303144)
					(mid 7.18101 -193.737406)
					(end 6.746748 -193.444622)
				)
				(xy 6.69671 -193.394584) (xy 6.481826 -193.394584)
				(arc
					(start 6.481826 -193.548762)
					(mid 6.992366 -194.059302)
					(end 7.502906 -193.548762)
				)
			)
		)
	)
	(zone
		(net "GND")
		(layer "F.Cu")
		(hatch none 0.5)
		(connect_pads
			(clearance 0.5)
		)
		(min_thickness 0.25)
		(fill yes
			(thermal_gap 0.5)
			(thermal_bridge_width 0.5)
			(island_removal_mode 0)
		)
		(polygon
			(pts
				(xy 36.322 -214.122) (xy 33.274 -217.17) (xy 33.274 -218.821) (xy 32.004 -220.091) (xy 28.829 -220.091)
				(xy 27.432 -221.488) (xy 27.432 -233.856276) (xy 28.140152 -234.564428) (xy 35.709098 -234.564428)
				(xy 39.768526 -230.505) (xy 49.022 -230.505) (xy 51.4096 -232.8926) (xy 79.487268 -232.8926) (xy 84.429854 -227.950014)
				(xy 84.429854 -224.180654) (xy 78.2066 -217.9574) (xy 76.6064 -217.9574) (xy 72.771 -214.122)
			)
		)
	)
	(zone
		(layer "F.Cu")
		(hatch none 0.5)
		(connect_pads
			(clearance 0)
		)
		(min_thickness 0.25)
		(keepout
			(tracks not_allowed)
			(vias allowed)
			(pads allowed)
			(copperpour not_allowed)
			(footprints allowed)
		)
		(placement
			(enabled no)
			(sheetname "")
		)
		(fill
			(thermal_gap 0.5)
			(thermal_bridge_width 0.5)
			(island_removal_mode 0)
		)
		(polygon
			(pts
				(arc
					(start 7.502906 -214.285322)
					(mid 6.992493 -213.774528)
					(end 6.481826 -214.285068)
				)
				(xy 6.481826 -214.438484) (xy 6.697472 -214.438484)
				(arc
					(start 6.746748 -214.389208)
					(mid 7.18101 -214.096424)
					(end 6.888226 -214.530686)
				)
				(xy 6.780276 -214.638636) (xy 6.481826 -214.638636) (xy 6.481826 -214.743538) (xy 6.779514 -214.743538)
				(arc
					(start 6.888226 -214.85225)
					(mid 7.18101 -215.286512)
					(end 6.746748 -214.993728)
				)
				(xy 6.69671 -214.94369) (xy 6.481826 -214.94369)
				(arc
					(start 6.481826 -215.097868)
					(mid 6.992366 -215.608408)
					(end 7.502906 -215.097868)
				)
			)
		)
	)
	(zone
		(net "GND")
		(layer "F.Cu")
		(hatch none 0.5)
		(connect_pads
			(clearance 0.5)
		)
		(min_thickness 0.25)
		(fill yes
			(thermal_gap 0.5)
			(thermal_bridge_width 0.5)
			(island_removal_mode 0)
		)
		(polygon
			(pts
				(xy 24.511 -102.87) (xy 24.13 -103.251) (xy 24.13 -105.029) (xy 24.257 -105.156) (xy 27.813 -105.156)
				(xy 28.0924 -104.8766) (xy 28.0924 -103.4034) (xy 27.559 -102.87)
			)
		)
		(polygon
			(pts
				(xy 27.2034 -104.1146) (xy 27.0002 -104.1146) (xy 27.0002 -104.3178) (xy 27.2034 -104.3178)
			)
		)
	)
	(zone
		(layer "F.Cu")
		(hatch none 0.5)
		(connect_pads
			(clearance 0)
		)
		(min_thickness 0.25)
		(keepout
			(tracks allowed)
			(vias allowed)
			(pads allowed)
			(copperpour allowed)
			(footprints allowed)
		)
		(placement
			(enabled no)
			(sheetname "")
		)
		(fill
			(thermal_gap 0.5)
			(thermal_bridge_width 0.5)
			(island_removal_mode 0)
		)
		(polygon
			(pts
				(xy 44.323 -163.195) (xy 44.323 -165.481) (xy 42.164 -165.481) (xy 42.164 -163.195)
			)
		)
	)
	(zone
		(layer "F.Cu")
		(hatch none 0.5)
		(connect_pads
			(clearance 0)
		)
		(min_thickness 0.25)
		(keepout
			(tracks allowed)
			(vias allowed)
			(pads allowed)
			(copperpour allowed)
			(footprints allowed)
		)
		(placement
			(enabled no)
			(sheetname "")
		)
		(fill
			(thermal_gap 0.5)
			(thermal_bridge_width 0.5)
			(island_removal_mode 0)
		)
		(polygon
			(pts
				(xy 87.63 -435.737) (xy 87.63 -431.673) (xy 83.439 -431.673) (xy 83.439 -430.911) (xy 88.011 -430.911)
				(xy 88.011 -427.863) (xy 89.916 -427.863) (xy 89.916 -435.737)
			)
		)
	)
	(zone
		(layer "F.Cu")
		(hatch none 0.5)
		(connect_pads
			(clearance 0)
		)
		(min_thickness 0.25)
		(keepout
			(tracks not_allowed)
			(vias allowed)
			(pads allowed)
			(copperpour not_allowed)
			(footprints allowed)
		)
		(placement
			(enabled no)
			(sheetname "")
		)
		(fill
			(thermal_gap 0.5)
			(thermal_bridge_width 0.5)
			(island_removal_mode 0)
		)
		(polygon
			(pts
				(arc
					(start 35.84067 -72.183752)
					(mid 35.330257 -71.672958)
					(end 34.81959 -72.183498)
				)
				(arc
					(start 34.81959 -72.996298)
					(mid 35.33013 -73.506838)
					(end 35.84067 -72.996298)
				)
				(xy 35.84067 -72.842628) (xy 35.625278 -72.842628)
				(arc
					(start 35.575748 -72.892158)
					(mid 35.141486 -73.184942)
					(end 35.43427 -72.75068)
				)
				(xy 35.542474 -72.642476) (xy 35.84067 -72.642476) (xy 35.84067 -72.537574) (xy 35.542728 -72.537574)
				(arc
					(start 35.43427 -72.429116)
					(mid 35.141486 -71.994854)
					(end 35.575748 -72.287638)
				)
				(xy 35.625532 -72.337422) (xy 35.84067 -72.337422)
			)
		)
	)
	(zone
		(layer "F.Cu")
		(hatch none 0.5)
		(connect_pads
			(clearance 0)
		)
		(min_thickness 0.25)
		(keepout
			(tracks not_allowed)
			(vias allowed)
			(pads allowed)
			(copperpour not_allowed)
			(footprints allowed)
		)
		(placement
			(enabled no)
			(sheetname "")
		)
		(fill
			(thermal_gap 0.5)
			(thermal_bridge_width 0.5)
			(island_removal_mode 0)
		)
		(polygon
			(pts
				(arc
					(start 27.18054 -450.603874)
					(mid 26.670127 -450.09308)
					(end 26.15946 -450.60362)
				)
				(xy 26.15946 -450.78269) (xy 26.349452 -450.78269)
				(arc
					(start 26.424382 -450.70776)
					(mid 26.858644 -450.414976)
					(end 26.56586 -450.849238)
				)
				(xy 26.432256 -450.982842) (xy 26.15946 -450.982842) (xy 26.15946 -451.087744) (xy 26.482802 -451.087744)
				(arc
					(start 26.56586 -451.170802)
					(mid 26.858644 -451.605064)
					(end 26.424382 -451.31228)
				)
				(xy 26.399998 -451.287896) (xy 26.15946 -451.287896)
				(arc
					(start 26.15946 -451.41642)
					(mid 26.67 -451.92696)
					(end 27.18054 -451.41642)
				)
			)
		)
	)
	(zone
		(layer "F.Cu")
		(hatch none 0.5)
		(connect_pads
			(clearance 0)
		)
		(min_thickness 0.25)
		(keepout
			(tracks not_allowed)
			(vias allowed)
			(pads allowed)
			(copperpour not_allowed)
			(footprints allowed)
		)
		(placement
			(enabled no)
			(sheetname "")
		)
		(fill
			(thermal_gap 0.5)
			(thermal_bridge_width 0.5)
			(island_removal_mode 0)
		)
		(polygon
			(pts
				(arc
					(start 220.840554 -54.583838)
					(mid 220.330141 -54.073044)
					(end 219.819474 -54.583584)
				)
				(arc
					(start 219.819474 -55.396384)
					(mid 220.330014 -55.906924)
					(end 220.840554 -55.396384)
				)
				(xy 220.840554 -55.242714) (xy 220.625162 -55.242714)
				(arc
					(start 220.575632 -55.292244)
					(mid 220.14137 -55.585028)
					(end 220.434154 -55.150766)
				)
				(xy 220.542358 -55.042562) (xy 220.840554 -55.042562) (xy 220.840554 -54.93766) (xy 220.542612 -54.93766)
				(arc
					(start 220.434154 -54.829202)
					(mid 220.14137 -54.39494)
					(end 220.575632 -54.687724)
				)
				(xy 220.625416 -54.737508) (xy 220.840554 -54.737508)
			)
		)
	)
	(zone
		(net "P12V_SSD0")
		(layer "F.Cu")
		(hatch none 0.5)
		(connect_pads
			(clearance 0.5)
		)
		(min_thickness 0.25)
		(fill yes
			(thermal_gap 0.5)
			(thermal_bridge_width 0.5)
			(island_removal_mode 0)
		)
		(polygon
			(pts
				(xy 208.2546 -490.6772) (xy 207.9498 -490.982) (xy 207.9498 -496.4938) (xy 208.1911 -496.7351) (xy 208.1911 -498.3353)
				(xy 208.5848 -498.729) (xy 215.6206 -498.729) (xy 215.8746 -498.983) (xy 215.8746 -501.015) (xy 216.3318 -501.4722)
				(xy 219.329 -501.4722) (xy 219.71 -501.0912) (xy 219.71 -497.9924) (xy 220.1926 -497.5098) (xy 222.2754 -497.5098)
				(xy 222.508572 -497.742972) (xy 222.508572 -500.821452) (xy 222.70212 -501.015) (xy 227.076 -501.015)
				(xy 229.108 -498.983) (xy 229.108 -493.776) (xy 228.981 -493.649) (xy 225.806 -493.649) (xy 225.679 -493.776)
				(xy 225.679 -495.808) (xy 225.1964 -496.2906) (xy 223.1136 -496.2906) (xy 222.504 -495.681) (xy 220.1926 -495.681)
				(xy 219.583 -496.2906) (xy 214.2236 -496.2906) (xy 212.9536 -495.0206) (xy 212.9536 -492.3536) (xy 211.2772 -490.6772)
			)
		)
		(polygon
			(pts
				(xy 217.3986 -500.5324) (xy 217.1954 -500.5324) (xy 217.1954 -500.7356) (xy 217.3986 -500.7356)
			)
		)
		(polygon
			(pts
				(xy 216.2556 -500.5324) (xy 216.0524 -500.5324) (xy 216.0524 -500.7356) (xy 216.2556 -500.7356)
			)
		)
		(polygon
			(pts
				(xy 217.3986 -497.7384) (xy 217.1954 -497.7384) (xy 217.1954 -497.9416) (xy 217.3986 -497.9416)
			)
		)
		(polygon
			(pts
				(xy 216.2556 -497.7384) (xy 216.0524 -497.7384) (xy 216.0524 -497.9416) (xy 216.2556 -497.9416)
			)
		)
		(polygon
			(pts
				(xy 215.5444 -497.7384) (xy 215.3412 -497.7384) (xy 215.3412 -497.9416) (xy 215.5444 -497.9416)
			)
		)
		(polygon
			(pts
				(xy 214.6808 -497.7384) (xy 214.4776 -497.7384) (xy 214.4776 -497.9416) (xy 214.6808 -497.9416)
			)
		)
		(polygon
			(pts
				(xy 219.4814 -496.7986) (xy 219.2782 -496.7986) (xy 219.2782 -497.0018) (xy 219.4814 -497.0018)
			)
		)
		(polygon
			(pts
				(xy 218.8718 -496.7986) (xy 218.6686 -496.7986) (xy 218.6686 -497.0018) (xy 218.8718 -497.0018)
			)
		)
	)
	(zone
		(layer "F.Cu")
		(hatch none 0.5)
		(connect_pads
			(clearance 0)
		)
		(min_thickness 0.25)
		(keepout
			(tracks not_allowed)
			(vias allowed)
			(pads allowed)
			(copperpour not_allowed)
			(footprints allowed)
		)
		(placement
			(enabled no)
			(sheetname "")
		)
		(fill
			(thermal_gap 0.5)
			(thermal_bridge_width 0.5)
			(island_removal_mode 0)
		)
		(polygon
			(pts
				(arc
					(start 7.502906 -227.136198)
					(mid 6.992493 -226.625404)
					(end 6.481826 -227.135944)
				)
				(xy 6.481826 -227.28936) (xy 6.697472 -227.28936)
				(arc
					(start 6.746748 -227.240084)
					(mid 7.18101 -226.9473)
					(end 6.888226 -227.381562)
				)
				(xy 6.780276 -227.489512) (xy 6.481826 -227.489512) (xy 6.481826 -227.594414) (xy 6.779514 -227.594414)
				(arc
					(start 6.888226 -227.703126)
					(mid 7.18101 -228.137388)
					(end 6.746748 -227.844604)
				)
				(xy 6.69671 -227.794566) (xy 6.481826 -227.794566)
				(arc
					(start 6.481826 -227.948744)
					(mid 6.992366 -228.459284)
					(end 7.502906 -227.948744)
				)
			)
		)
	)
	(zone
		(layer "F.Cu")
		(hatch none 0.5)
		(connect_pads
			(clearance 0)
		)
		(min_thickness 0.25)
		(keepout
			(tracks not_allowed)
			(vias allowed)
			(pads allowed)
			(copperpour not_allowed)
			(footprints allowed)
		)
		(placement
			(enabled no)
			(sheetname "")
		)
		(fill
			(thermal_gap 0.5)
			(thermal_bridge_width 0.5)
			(island_removal_mode 0)
		)
		(polygon
			(pts
				(arc
					(start 220.840554 -67.383914)
					(mid 220.330141 -66.87312)
					(end 219.819474 -67.38366)
				)
				(arc
					(start 219.819474 -68.19646)
					(mid 220.330014 -68.707)
					(end 220.840554 -68.19646)
				)
				(xy 220.840554 -68.042536) (xy 220.625416 -68.042536)
				(arc
					(start 220.575632 -68.09232)
					(mid 220.14137 -68.385104)
					(end 220.434154 -67.950842)
				)
				(xy 220.542612 -67.842384) (xy 220.840554 -67.842384) (xy 220.840554 -67.737482) (xy 220.542358 -67.737482)
				(arc
					(start 220.434154 -67.629278)
					(mid 220.14137 -67.195016)
					(end 220.575632 -67.4878)
				)
				(xy 220.625162 -67.53733) (xy 220.840554 -67.53733)
			)
		)
	)
	(zone
		(net "P3V3")
		(layer "F.Cu")
		(hatch none 0.5)
		(connect_pads
			(clearance 0.5)
		)
		(min_thickness 0.25)
		(fill yes
			(thermal_gap 0.5)
			(thermal_bridge_width 0.5)
			(island_removal_mode 0)
		)
		(polygon
			(pts
				(xy 24.2824 -153.5176) (xy 24.159464 -153.640536) (xy 24.159464 -157.810454) (xy 24.36241 -158.0134)
				(xy 25.9588 -158.0134) (xy 26.7716 -157.2006) (xy 26.7716 -154.0002) (xy 26.289 -153.5176)
			)
		)
		(polygon
			(pts
				(xy 24.8158 -157.651958) (xy 24.6126 -157.651958) (xy 24.6126 -157.855158) (xy 24.8158 -157.855158)
			)
		)
		(polygon
			(pts
				(xy 24.8158 -157.093158) (xy 24.6126 -157.093158) (xy 24.6126 -157.296358) (xy 24.8158 -157.296358)
			)
		)
		(polygon
			(pts
				(xy 24.8158 -156.5148) (xy 24.6126 -156.5148) (xy 24.6126 -156.718) (xy 24.8158 -156.718)
			)
		)
		(polygon
			(pts
				(xy 24.8158 -155.956) (xy 24.6126 -155.956) (xy 24.6126 -156.1592) (xy 24.8158 -156.1592)
			)
		)
		(polygon
			(pts
				(xy 24.8158 -155.3718) (xy 24.6126 -155.3718) (xy 24.6126 -155.575) (xy 24.8158 -155.575)
			)
		)
		(polygon
			(pts
				(xy 24.8158 -154.813) (xy 24.6126 -154.813) (xy 24.6126 -155.0162) (xy 24.8158 -155.0162)
			)
		)
	)
	(zone
		(layer "F.Cu")
		(hatch none 0.5)
		(connect_pads
			(clearance 0)
		)
		(min_thickness 0.25)
		(keepout
			(tracks allowed)
			(vias allowed)
			(pads allowed)
			(copperpour allowed)
			(footprints allowed)
		)
		(placement
			(enabled no)
			(sheetname "")
		)
		(fill
			(thermal_gap 0.5)
			(thermal_bridge_width 0.5)
			(island_removal_mode 0)
		)
		(polygon
			(pts
				(xy 37.338 -470.916) (xy 37.338 -463.804) (xy 39.497 -463.804) (xy 39.497 -470.916)
			)
		)
	)
	(zone
		(net "P12V")
		(layer "F.Cu")
		(hatch none 0.5)
		(connect_pads
			(clearance 0.5)
		)
		(min_thickness 0.25)
		(fill yes
			(thermal_gap 0.5)
			(thermal_bridge_width 0.5)
			(island_removal_mode 0)
		)
		(polygon
			(pts
				(xy 8.001 -461.899) (xy 7.0358 -462.8642) (xy 5.135118 -462.8642) (xy 4.373118 -462.1022) (xy 1.0668 -462.1022)
				(xy 1.016 -462.153) (xy 1.016 -475.488) (xy 3.286252 -477.758252) (xy 8.134858 -477.758252) (xy 8.1534 -477.73971)
				(xy 8.1534 -466.3948) (xy 8.4328 -466.1154) (xy 8.4328 -463.55) (xy 8.5852 -463.3976) (xy 8.5852 -461.9752)
				(xy 8.509 -461.899)
			)
		)
		(polygon
			(pts
				(xy 7.6708 -465.6836) (xy 7.4676 -465.6836) (xy 7.4676 -465.8868) (xy 7.6708 -465.8868)
			)
		)
		(polygon
			(pts
				(xy 7.6708 -464.82) (xy 7.4676 -464.82) (xy 7.4676 -465.0232) (xy 7.6708 -465.0232)
			)
		)
		(polygon
			(pts
				(xy 7.6708 -464.4644) (xy 7.4676 -464.4644) (xy 7.4676 -464.6676) (xy 7.6708 -464.6676)
			)
		)
		(polygon
			(pts
				(xy 7.6708 -463.6008) (xy 7.4676 -463.6008) (xy 7.4676 -463.804) (xy 7.6708 -463.804)
			)
		)
		(polygon
			(pts
				(xy 8.0772 -463.296) (xy 7.874 -463.296) (xy 7.874 -463.4992) (xy 8.0772 -463.4992)
			)
		)
		(polygon
			(pts
				(xy 8.0772 -462.407) (xy 7.874 -462.407) (xy 7.874 -462.8896) (xy 8.0772 -462.8896)
			)
		)
	)
	(zone
		(layer "F.Cu")
		(hatch none 0.5)
		(connect_pads
			(clearance 0)
		)
		(min_thickness 0.25)
		(keepout
			(tracks not_allowed)
			(vias allowed)
			(pads allowed)
			(copperpour not_allowed)
			(footprints allowed)
		)
		(placement
			(enabled no)
			(sheetname "")
		)
		(fill
			(thermal_gap 0.5)
			(thermal_bridge_width 0.5)
			(island_removal_mode 0)
		)
		(polygon
			(pts
				(arc
					(start 48.89754 -60.579508)
					(mid 48.387127 -60.068714)
					(end 47.87646 -60.579254)
				)
				(arc
					(start 47.87646 -61.392054)
					(mid 48.387 -61.902594)
					(end 48.89754 -61.392054)
				)
				(xy 48.89754 -61.23813) (xy 48.682402 -61.23813)
				(arc
					(start 48.632618 -61.287914)
					(mid 48.198356 -61.580698)
					(end 48.49114 -61.146436)
				)
				(xy 48.599598 -61.037978) (xy 48.89754 -61.037978) (xy 48.89754 -60.933076) (xy 48.599344 -60.933076)
				(arc
					(start 48.49114 -60.824872)
					(mid 48.198356 -60.39061)
					(end 48.632618 -60.683394)
				)
				(xy 48.682148 -60.732924) (xy 48.89754 -60.732924)
			)
		)
	)
	(zone
		(layer "F.Cu")
		(hatch none 0.5)
		(connect_pads
			(clearance 0)
		)
		(min_thickness 0.25)
		(keepout
			(tracks not_allowed)
			(vias allowed)
			(pads allowed)
			(copperpour not_allowed)
			(footprints allowed)
		)
		(placement
			(enabled no)
			(sheetname "")
		)
		(fill
			(thermal_gap 0.5)
			(thermal_bridge_width 0.5)
			(island_removal_mode 0)
		)
		(polygon
			(pts
				(arc
					(start 7.502906 -436.784242)
					(mid 6.992366 -436.273702)
					(end 6.481826 -436.784242)
				)
				(xy 6.481826 -436.937912) (xy 6.697218 -436.937912)
				(arc
					(start 6.746748 -436.888382)
					(mid 7.18101 -436.595598)
					(end 6.888226 -437.02986)
				)
				(xy 6.780022 -437.138064) (xy 6.481826 -437.138064) (xy 6.481826 -437.242966) (xy 6.779768 -437.242966)
				(arc
					(start 6.888226 -437.351424)
					(mid 7.18101 -437.785686)
					(end 6.746748 -437.492902)
				)
				(xy 6.696964 -437.443118) (xy 6.481826 -437.443118)
				(arc
					(start 6.481826 -437.596788)
					(mid 6.992239 -438.107582)
					(end 7.502906 -437.597042)
				)
			)
		)
	)
	(zone
		(layer "F.Cu")
		(hatch none 0.5)
		(connect_pads
			(clearance 0)
		)
		(min_thickness 0.25)
		(keepout
			(tracks not_allowed)
			(vias allowed)
			(pads allowed)
			(copperpour not_allowed)
			(footprints allowed)
		)
		(placement
			(enabled no)
			(sheetname "")
		)
		(fill
			(thermal_gap 0.5)
			(thermal_bridge_width 0.5)
			(island_removal_mode 0)
		)
		(polygon
			(pts
				(arc
					(start 37.33927 -491.231428)
					(mid 36.72713 -490.619288)
					(end 36.11499 -491.231428)
				)
				(arc
					(start 36.11499 -492.348774)
					(mid 36.727003 -492.961168)
					(end 37.33927 -492.349028)
				)
				(xy 37.33927 -492.042704) (xy 37.174932 -492.042704)
				(arc
					(start 36.972748 -492.244888)
					(mid 36.538486 -492.537672)
					(end 36.83127 -492.10341)
				)
				(xy 37.092128 -491.842552) (xy 37.33927 -491.842552) (xy 37.33927 -491.73765) (xy 37.091874 -491.73765)
				(arc
					(start 36.83127 -491.477046)
					(mid 36.538486 -491.042784)
					(end 36.972748 -491.335568)
				)
				(xy 37.174678 -491.537498) (xy 37.33927 -491.537498)
			)
		)
	)
	(zone
		(layer "F.Cu")
		(hatch none 0.5)
		(connect_pads
			(clearance 0)
		)
		(min_thickness 0.25)
		(keepout
			(tracks allowed)
			(vias allowed)
			(pads allowed)
			(copperpour allowed)
			(footprints allowed)
		)
		(placement
			(enabled no)
			(sheetname "")
		)
		(fill
			(thermal_gap 0.5)
			(thermal_bridge_width 0.5)
			(island_removal_mode 0)
		)
		(polygon
			(pts
				(xy 37.338 -288.925) (xy 37.338 -272.288) (xy 39.497 -272.288) (xy 39.497 -288.925)
			)
		)
	)
	(zone
		(net "P3V3_SW")
		(layer "F.Cu")
		(hatch none 0.5)
		(connect_pads
			(clearance 0.5)
		)
		(min_thickness 0.25)
		(fill yes
			(thermal_gap 0.5)
			(thermal_bridge_width 0.5)
			(island_removal_mode 0)
		)
		(polygon
			(pts
				(xy 223.4692 -433.8828) (xy 222.25 -435.102) (xy 219.1258 -435.102) (xy 219.075 -435.1528) (xy 219.075 -438.6072)
				(xy 219.1258 -438.658) (xy 222.123 -438.658) (xy 222.631 -438.15) (xy 223.393 -438.15) (xy 223.52 -438.023)
				(xy 223.52 -436.88) (xy 223.647 -436.753) (xy 225.298 -436.753) (xy 225.8822 -436.1688) (xy 225.8822 -434.87086)
				(xy 225.8822 -434.82514) (xy 225.8822 -433.9844) (xy 225.7806 -433.8828)
			)
		)
		(polygon
			(pts
				(xy 222.6818 -437.1594) (xy 222.4786 -437.1594) (xy 222.4786 -437.3626) (xy 222.6818 -437.3626)
			)
		)
	)
	(zone
		(net "GND")
		(layer "F.Cu")
		(hatch none 0.5)
		(connect_pads
			(clearance 0.5)
		)
		(min_thickness 0.25)
		(fill yes
			(thermal_gap 0.5)
			(thermal_bridge_width 0.5)
			(island_removal_mode 0)
		)
		(polygon
			(pts
				(xy 23.4696 -499.1608) (xy 23.3172 -499.3132) (xy 23.3172 -501.2182) (xy 23.7998 -501.7008) (xy 30.2514 -501.7008)
				(xy 30.5562 -501.396) (xy 30.5562 -499.3386) (xy 30.3784 -499.1608)
			)
		)
		(polygon
			(pts
				(xy 29.7688 -500.0498) (xy 29.5656 -500.0498) (xy 29.5656 -500.253) (xy 29.7688 -500.253)
			)
		)
	)
	(zone
		(layer "F.Cu")
		(hatch none 0.5)
		(connect_pads
			(clearance 0)
		)
		(min_thickness 0.25)
		(keepout
			(tracks allowed)
			(vias allowed)
			(pads allowed)
			(copperpour allowed)
			(footprints allowed)
		)
		(placement
			(enabled no)
			(sheetname "")
		)
		(fill
			(thermal_gap 0.5)
			(thermal_bridge_width 0.5)
			(island_removal_mode 0)
		)
		(polygon
			(pts
				(xy 72.9234 -362.585) (xy 72.9234 -359.537) (xy 74.803 -359.537) (xy 74.803 -362.585)
			)
		)
	)
	(zone
		(layer "F.Cu")
		(hatch none 0.5)
		(connect_pads
			(clearance 0)
		)
		(min_thickness 0.25)
		(keepout
			(tracks not_allowed)
			(vias allowed)
			(pads allowed)
			(copperpour not_allowed)
			(footprints allowed)
		)
		(placement
			(enabled no)
			(sheetname "")
		)
		(fill
			(thermal_gap 0.5)
			(thermal_bridge_width 0.5)
			(island_removal_mode 0)
		)
		(polygon
			(pts
				(arc
					(start 222.339154 -486.43159)
					(mid 221.727141 -485.819196)
					(end 221.114874 -486.431336)
				)
				(arc
					(start 221.114874 -487.548936)
					(mid 221.727014 -488.161076)
					(end 222.339154 -487.548936)
				)
				(xy 222.339154 -487.242866) (xy 222.174562 -487.242866)
				(arc
					(start 221.972632 -487.444796)
					(mid 221.53837 -487.73758)
					(end 221.831154 -487.303318)
				)
				(xy 222.091758 -487.042714) (xy 222.339154 -487.042714) (xy 222.339154 -486.937812) (xy 222.092012 -486.937812)
				(arc
					(start 221.831154 -486.676954)
					(mid 221.53837 -486.242692)
					(end 221.972632 -486.535476)
				)
				(xy 222.174816 -486.73766) (xy 222.339154 -486.73766)
			)
		)
	)
	(zone
		(net "GND")
		(layer "F.Cu")
		(hatch none 0.5)
		(connect_pads
			(clearance 0.5)
		)
		(min_thickness 0.25)
		(fill yes
			(thermal_gap 0.5)
			(thermal_bridge_width 0.5)
			(island_removal_mode 0)
		)
		(polygon
			(pts
				(xy 66.167 -141.732) (xy 52.07 -155.829) (xy 52.07 -163.322) (xy 48.133 -167.259) (xy 48.133 -177.8)
				(xy 47.625 -178.308) (xy 47.625 -195.072) (xy 48.895 -196.342) (xy 62.103 -196.342) (xy 72.898 -185.547)
				(xy 80.564482 -185.547) (xy 82.30108 -183.810402) (xy 82.30108 -159.023304) (xy 81.900776 -158.623)
				(xy 73.279 -158.623) (xy 67.437 -152.781) (xy 67.437 -142.621) (xy 66.548 -141.732)
			)
		)
	)
	(zone
		(layer "F.Cu")
		(hatch none 0.5)
		(connect_pads
			(clearance 0)
		)
		(min_thickness 0.25)
		(keepout
			(tracks not_allowed)
			(vias allowed)
			(pads allowed)
			(copperpour not_allowed)
			(footprints allowed)
		)
		(placement
			(enabled no)
			(sheetname "")
		)
		(fill
			(thermal_gap 0.5)
			(thermal_bridge_width 0.5)
			(island_removal_mode 0)
		)
		(polygon
			(pts
				(arc
					(start 37.33927 -285.231586)
					(mid 36.727257 -284.619192)
					(end 36.11499 -285.231332)
				)
				(arc
					(start 36.11499 -286.348932)
					(mid 36.72713 -286.961072)
					(end 37.33927 -286.348932)
				)
				(xy 37.33927 -286.042608) (xy 37.174932 -286.042608)
				(arc
					(start 36.972748 -286.244792)
					(mid 36.538486 -286.537576)
					(end 36.83127 -286.103314)
				)
				(xy 37.092128 -285.842456) (xy 37.33927 -285.842456) (xy 37.33927 -285.737554) (xy 37.091874 -285.737554)
				(arc
					(start 36.83127 -285.47695)
					(mid 36.538486 -285.042688)
					(end 36.972748 -285.335472)
				)
				(xy 37.174678 -285.537402) (xy 37.33927 -285.537402)
			)
		)
	)
	(zone
		(layer "F.Cu")
		(hatch none 0.5)
		(connect_pads
			(clearance 0)
		)
		(min_thickness 0.25)
		(keepout
			(tracks not_allowed)
			(vias allowed)
			(pads allowed)
			(copperpour not_allowed)
			(footprints allowed)
		)
		(placement
			(enabled no)
			(sheetname "")
		)
		(fill
			(thermal_gap 0.5)
			(thermal_bridge_width 0.5)
			(island_removal_mode 0)
		)
		(polygon
			(pts
				(xy 95.39478 -309.02021) (xy 95.48368 -309.02021) (xy 95.48368 -310.18861) (xy 95.39478 -310.18861)
			)
		)
	)
	(zone
		(layer "F.Cu")
		(hatch none 0.5)
		(connect_pads
			(clearance 0)
		)
		(min_thickness 0.25)
		(keepout
			(tracks not_allowed)
			(vias allowed)
			(pads allowed)
			(copperpour not_allowed)
			(footprints allowed)
		)
		(placement
			(enabled no)
			(sheetname "")
		)
		(fill
			(thermal_gap 0.5)
			(thermal_bridge_width 0.5)
			(island_removal_mode 0)
		)
		(polygon
			(pts
				(arc
					(start 25.88514 -219.651326)
					(mid 25.273127 -219.038932)
					(end 24.66086 -219.651072)
				)
				(xy 24.66086 -219.957396) (xy 24.825198 -219.957396)
				(arc
					(start 25.027382 -219.755212)
					(mid 25.461644 -219.462428)
					(end 25.16886 -219.89669)
				)
				(xy 24.908002 -220.157548) (xy 24.66086 -220.157548) (xy 24.66086 -220.26245) (xy 24.908256 -220.26245)
				(arc
					(start 25.16886 -220.523054)
					(mid 25.461644 -220.957316)
					(end 25.027382 -220.664532)
				)
				(xy 24.825452 -220.462602) (xy 24.66086 -220.462602)
				(arc
					(start 24.66086 -220.768672)
					(mid 25.273 -221.380812)
					(end 25.88514 -220.768672)
				)
			)
		)
	)
	(zone
		(layer "F.Cu")
		(hatch none 0.5)
		(connect_pads
			(clearance 0)
		)
		(min_thickness 0.25)
		(keepout
			(tracks allowed)
			(vias allowed)
			(pads allowed)
			(copperpour allowed)
			(footprints allowed)
		)
		(placement
			(enabled no)
			(sheetname "")
		)
		(fill
			(thermal_gap 0.5)
			(thermal_bridge_width 0.5)
			(island_removal_mode 0)
		)
		(polygon
			(pts
				(xy 7.239 -457.073) (xy 1.905 -457.073) (xy 1.905 -422.021) (xy 7.239 -422.021)
			)
		)
	)
	(zone
		(net "P12V")
		(layer "F.Cu")
		(hatch none 0.5)
		(connect_pads
			(clearance 0.5)
		)
		(min_thickness 0.25)
		(fill yes
			(thermal_gap 0.5)
			(thermal_bridge_width 0.5)
			(island_removal_mode 0)
		)
		(polygon
			(pts
				(xy 32.8168 -205.613) (xy 32.512 -205.9178) (xy 32.512 -206.3496) (xy 32.004 -206.8576) (xy 32.004 -211.963)
				(xy 32.258 -212.217) (xy 35.7886 -212.217) (xy 36.2966 -212.725) (xy 37.973 -212.725) (xy 38.1 -212.598)
				(xy 38.1 -212.217) (xy 37.846 -211.963) (xy 37.211 -211.963) (xy 37.0332 -211.7852) (xy 37.0332 -211.0232)
				(xy 36.703 -210.693) (xy 36.703 -209.296) (xy 35.1536 -207.7466) (xy 35.1536 -206.8322) (xy 33.9344 -205.613)
			)
		)
		(polygon
			(pts
				(xy 37.084 -212.0138) (xy 36.8808 -212.0138) (xy 36.8808 -212.217) (xy 37.084 -212.217)
			)
		)
		(polygon
			(pts
				(xy 36.4744 -212.0138) (xy 36.2712 -212.0138) (xy 36.2712 -212.217) (xy 36.4744 -212.217)
			)
		)
		(polygon
			(pts
				(xy 36.576 -211.5312) (xy 36.3728 -211.5312) (xy 36.3728 -211.7344) (xy 36.576 -211.7344)
			)
		)
		(polygon
			(pts
				(xy 36.576 -210.9724) (xy 36.3728 -210.9724) (xy 36.3728 -211.1756) (xy 36.576 -211.1756)
			)
		)
		(polygon
			(pts
				(xy 33.4899 -206.0575) (xy 33.2867 -206.0575) (xy 33.2867 -206.2607) (xy 33.4899 -206.2607)
			)
		)
		(polygon
			(pts
				(xy 32.9311 -206.0575) (xy 32.7279 -206.0575) (xy 32.7279 -206.2607) (xy 32.9311 -206.2607)
			)
		)
	)
	(zone
		(layer "F.Cu")
		(hatch none 0.5)
		(connect_pads
			(clearance 0)
		)
		(min_thickness 0.25)
		(keepout
			(tracks allowed)
			(vias allowed)
			(pads allowed)
			(copperpour allowed)
			(footprints allowed)
		)
		(placement
			(enabled no)
			(sheetname "")
		)
		(fill
			(thermal_gap 0.5)
			(thermal_bridge_width 0.5)
			(island_removal_mode 0)
		)
		(polygon
			(pts
				(xy 7.239 -418.719) (xy 1.2446 -418.719) (xy 1.2446 -383.667) (xy 7.239 -383.667)
			)
		)
	)
	(zone
		(layer "F.Cu")
		(hatch none 0.5)
		(connect_pads
			(clearance 0)
		)
		(min_thickness 0.25)
		(keepout
			(tracks not_allowed)
			(vias allowed)
			(pads allowed)
			(copperpour not_allowed)
			(footprints allowed)
		)
		(placement
			(enabled no)
			(sheetname "")
		)
		(fill
			(thermal_gap 0.5)
			(thermal_bridge_width 0.5)
			(island_removal_mode 0)
		)
		(polygon
			(pts
				(arc
					(start 7.502906 -204.736192)
					(mid 6.992493 -204.225398)
					(end 6.481826 -204.735938)
				)
				(xy 6.481826 -204.889354) (xy 6.697472 -204.889354)
				(arc
					(start 6.746748 -204.840078)
					(mid 7.18101 -204.547294)
					(end 6.888226 -204.981556)
				)
				(xy 6.780276 -205.089506) (xy 6.481826 -205.089506) (xy 6.481826 -205.194408) (xy 6.779514 -205.194408)
				(arc
					(start 6.888226 -205.30312)
					(mid 7.18101 -205.737382)
					(end 6.746748 -205.444598)
				)
				(xy 6.69671 -205.39456) (xy 6.481826 -205.39456)
				(arc
					(start 6.481826 -205.548738)
					(mid 6.992366 -206.059278)
					(end 7.502906 -205.548738)
				)
			)
		)
	)
	(zone
		(layer "F.Cu")
		(hatch none 0.5)
		(connect_pads
			(clearance 0)
		)
		(min_thickness 0.25)
		(keepout
			(tracks allowed)
			(vias allowed)
			(pads allowed)
			(copperpour allowed)
			(footprints allowed)
		)
		(placement
			(enabled no)
			(sheetname "")
		)
		(fill
			(thermal_gap 0.5)
			(thermal_bridge_width 0.5)
			(island_removal_mode 0)
		)
		(polygon
			(pts
				(xy 78.4352 -433.0192) (xy 78.4352 -431.5206) (xy 79.3496 -431.5206) (xy 79.3496 -433.0192)
			)
		)
	)
	(zone
		(layer "F.Cu")
		(hatch none 0.5)
		(connect_pads
			(clearance 0)
		)
		(min_thickness 0.25)
		(keepout
			(tracks allowed)
			(vias allowed)
			(pads allowed)
			(copperpour allowed)
			(footprints allowed)
		)
		(placement
			(enabled no)
			(sheetname "")
		)
		(fill
			(thermal_gap 0.5)
			(thermal_bridge_width 0.5)
			(island_removal_mode 0)
		)
		(polygon
			(pts
				(xy 37.338 -367.919) (xy 37.338 -360.807) (xy 39.497 -360.807) (xy 39.497 -367.919)
			)
		)
	)
	(zone
		(net "GND")
		(layer "F.Cu")
		(hatch none 0.5)
		(connect_pads
			(clearance 0.5)
		)
		(min_thickness 0.25)
		(fill yes
			(thermal_gap 0.5)
			(thermal_bridge_width 0.5)
			(island_removal_mode 0)
		)
		(polygon
			(pts
				(xy 109.601 -314.452) (xy 76.962 -347.091) (xy 67.31 -347.091) (xy 52.324 -362.077) (xy 52.324 -368.808)
				(xy 48.006 -373.126) (xy 48.006 -383.413) (xy 47.117 -384.302) (xy 47.117 -384.383788) (xy 43.729148 -387.77164)
				(xy 43.729148 -388.940802) (xy 44.422568 -389.634222) (xy 44.422822 -389.634222) (xy 47.9552 -393.1666)
				(xy 47.9552 -403.4282) (xy 48.8061 -404.2791) (xy 49.8729 -404.2791) (xy 53.34 -400.812) (xy 53.34 -369.824)
				(xy 53.848 -369.316) (xy 55.1434 -369.316) (xy 55.595266 -369.767866) (xy 55.595266 -401.731734)
				(xy 41.5798 -415.7472) (xy 41.5798 -419.3032) (xy 40.513 -420.37) (xy 35.814 -420.37) (xy 34.163 -422.021)
				(xy 34.163 -424.815) (xy 33.274 -425.704) (xy 30.48 -425.704) (xy 28.702 -427.482) (xy 28.702 -432.308)
				(xy 29.337 -432.943) (xy 30.861 -432.943) (xy 51.6128 -412.1912) (xy 90.6272 -412.1912) (xy 93.091 -414.655)
				(xy 93.091 -423.926) (xy 93.6498 -424.4848) (xy 95.9612 -424.4848) (xy 96.1136 -424.3324) (xy 99.7204 -424.3324)
				(xy 100.457 -425.069) (xy 100.457 -427.609) (xy 104.902 -432.054) (xy 113.201704 -432.054) (xy 115.010184 -433.86248)
				(xy 179.60848 -433.86248) (xy 192.405 -446.659) (xy 202.057 -446.659) (xy 203.581 -445.135) (xy 203.581 -440.944)
				(xy 202.565 -439.928) (xy 197.739 -439.928) (xy 188.341 -430.53) (xy 188.341 -421.513) (xy 186.055 -419.227)
				(xy 115.57 -419.227) (xy 112.776 -422.021) (xy 112.776 -423.926) (xy 112.014 -424.688) (xy 109.093 -424.688)
				(xy 108.458 -424.053) (xy 108.458 -422.148) (xy 113.792 -416.814) (xy 243.586 -416.814) (xy 251.841 -408.559)
				(xy 258.572 -408.559) (xy 259.08 -408.051) (xy 259.08 -384.683) (xy 258.8768 -384.4798) (xy 249.0978 -384.4798)
				(xy 248.92 -384.6576) (xy 234.2134 -384.6576) (xy 232.721404 -386.149596) (xy 232.721404 -391.014204)
				(xy 234.188 -392.4808) (xy 234.188 -402.7678) (xy 232.2068 -404.749) (xy 224.361248 -404.749) (xy 222.93453 -406.175718)
				(xy 222.931482 -406.175718) (xy 221.6912 -407.416) (xy 217.1192 -407.416) (xy 215.878918 -406.175718)
				(xy 205.50632 -406.175718) (xy 204.241654 -404.911052) (xy 204.241654 -394.27785) (xy 203.155804 -393.192)
				(xy 115.9002 -393.192) (xy 92.6592 -369.951) (xy 71.628 -369.951) (xy 67.945 -366.268) (xy 67.945 -354.6602)
				(xy 72.6694 -349.9358) (xy 77.2922 -349.9358) (xy 79.550768 -352.194368) (xy 81.475326 -352.194368)
				(xy 81.875884 -352.594926) (xy 81.875884 -354.519484) (xy 85.0392 -357.6828) (xy 91.821 -357.6828)
				(xy 92.583 -358.4448) (xy 92.583 -365.379) (xy 116.586 -389.382) (xy 217.805 -389.382) (xy 219.583 -387.604)
				(xy 219.583 -374.269) (xy 217.520266 -372.206266) (xy 167.909494 -372.206266) (xy 167.005 -371.301772)
				(xy 167.005 -369.824) (xy 168.148 -368.681) (xy 216.662 -368.681) (xy 217.551 -367.792) (xy 217.551 -364.363)
				(xy 216.027 -362.839) (xy 176.53 -362.839) (xy 128.143 -314.452)
			)
		)
		(polygon
			(pts
				(xy 95.9104 -423.8244) (xy 95.7072 -423.8244) (xy 95.7072 -424.0276) (xy 95.9104 -424.0276)
			)
		)
		(polygon
			(pts
				(xy 95.3008 -423.8244) (xy 94.8182 -423.8244) (xy 94.8182 -424.0276) (xy 95.3008 -424.0276)
			)
		)
		(polygon
			(pts
				(xy 94.4118 -423.8244) (xy 94.2086 -423.8244) (xy 94.2086 -424.0276) (xy 94.4118 -424.0276)
			)
		)
		(polygon
			(pts
				(xy 244.1194 -412.2166) (xy 243.9162 -412.2166) (xy 243.9162 -412.4198) (xy 244.1194 -412.4198)
			)
		)
		(polygon
			(pts
				(xy 243.2558 -412.2166) (xy 243.0526 -412.2166) (xy 243.0526 -412.4198) (xy 243.2558 -412.4198)
			)
		)
		(polygon
			(pts
				(xy 244.1194 -411.353) (xy 243.9162 -411.353) (xy 243.9162 -411.5562) (xy 244.1194 -411.5562)
			)
		)
		(polygon
			(pts
				(xy 243.2558 -411.353) (xy 243.0526 -411.353) (xy 243.0526 -411.5562) (xy 243.2558 -411.5562)
			)
		)
	)
	(zone
		(net "GND")
		(layer "F.Cu")
		(hatch none 0.5)
		(connect_pads
			(clearance 0.5)
		)
		(min_thickness 0.25)
		(fill yes
			(thermal_gap 0.5)
			(thermal_bridge_width 0.5)
			(island_removal_mode 0)
		)
		(polygon
			(pts
				(xy 237.969298 -428.244) (xy 236.474 -429.739298) (xy 236.474 -445.135) (xy 237.48365 -446.14465)
				(xy 237.48365 -453.454262) (xy 235.769912 -455.168) (xy 234.442 -455.168) (xy 232.791 -456.819)
				(xy 232.791 -459.613) (xy 236.728 -463.55) (xy 236.728 -472.948) (xy 233.172 -476.504) (xy 233.172 -486.029)
				(xy 231.267 -487.934) (xy 231.267 -502.539) (xy 230.124 -503.682) (xy 221.615 -503.682) (xy 220.6752 -502.7422)
				(xy 207.3656 -502.7422) (xy 205.74 -501.1166) (xy 192.024 -501.1166) (xy 191.4398 -500.5324) (xy 191.4398 -499.6942)
				(xy 193.3702 -497.7638) (xy 193.3702 -492.4806) (xy 192.8876 -491.998) (xy 184.1246 -491.998) (xy 183.602884 -491.476284)
				(xy 183.602884 -489.682536) (xy 184.43702 -488.8484) (xy 208.712308 -488.8484) (xy 209.22107 -488.339638)
				(xy 209.22107 -474.152214) (xy 181.049168 -445.980312) (xy 115.577112 -445.980312) (xy 113.089182 -443.492382)
				(xy 113.089182 -442.463174) (xy 113.65992 -441.892436) (xy 117.303296 -441.892436) (xy 118.115588 -442.704728)
				(xy 118.115588 -443.769496) (xy 118.60911 -444.263018) (xy 179.410106 -444.263018) (xy 179.915058 -443.758066)
				(xy 179.915058 -442.924184) (xy 178.005232 -441.014358) (xy 105.822242 -441.014358) (xy 98.2726 -448.564)
				(xy 93.345 -448.564) (xy 92.583 -449.326) (xy 92.583 -454.66) (xy 72.898 -474.345) (xy 48.26 -474.345)
				(xy 47.752 -474.853) (xy 47.752 -486.156) (xy 45.339 -488.569) (xy 45.339 -492.70031) (xy 46.549564 -493.910874)
				(xy 46.549564 -503.129042) (xy 45.710602 -503.968004) (xy 36.955476 -503.968004) (xy 35.81527 -502.827798)
				(xy 35.81527 -502.054876) (xy 35.428682 -501.668288) (xy 32.696912 -501.668288) (xy 31.496 -502.8692)
				(xy 22.606 -502.8692) (xy 20.8788 -501.142) (xy 8.060182 -501.142) (xy 7.601458 -500.683276) (xy 7.601458 -500.084598)
				(xy 8.8646 -498.821456) (xy 8.8646 -497.012722) (xy 11.373104 -494.504218) (xy 11.373104 -481.400104)
				(xy 8.760714 -478.787714) (xy 2.84988 -478.787714) (xy 1.49606 -477.433894) (xy 0.763016 -477.433894)
				(arc
					(start 0.763016 -505.000006)
					(mid 0.832426 -505.167578)
					(end 0.999998 -505.236988)
				)
				(arc
					(start 262.50011 -505.236988)
					(mid 262.667682 -505.167578)
					(end 262.737092 -505.000006)
				)
				(xy 262.737092 -434.587904) (xy 262.121904 -434.587904) (xy 260.985 -433.451) (xy 257.81 -433.451)
				(xy 255.524 -431.165) (xy 255.524 -429.387) (xy 254.381 -428.244)
			)
		)
	)
	(zone
		(layer "F.Cu")
		(hatch none 0.5)
		(connect_pads
			(clearance 0)
		)
		(min_thickness 0.25)
		(keepout
			(tracks not_allowed)
			(vias allowed)
			(pads allowed)
			(copperpour not_allowed)
			(footprints allowed)
		)
		(placement
			(enabled no)
			(sheetname "")
		)
		(fill
			(thermal_gap 0.5)
			(thermal_bridge_width 0.5)
			(island_removal_mode 0)
		)
		(polygon
			(pts
				(xy 88.97239 -305.09591) (xy 90.14079 -305.09591) (xy 90.14079 -305.18481) (xy 88.97239 -305.18481)
			)
		)
	)
	(zone
		(layer "F.Cu")
		(hatch none 0.5)
		(connect_pads
			(clearance 0)
		)
		(min_thickness 0.25)
		(keepout
			(tracks not_allowed)
			(vias allowed)
			(pads allowed)
			(copperpour not_allowed)
			(footprints allowed)
		)
		(placement
			(enabled no)
			(sheetname "")
		)
		(fill
			(thermal_gap 0.5)
			(thermal_bridge_width 0.5)
			(island_removal_mode 0)
		)
		(polygon
			(pts
				(arc
					(start 25.88514 -425.651422)
					(mid 25.273127 -425.039028)
					(end 24.66086 -425.651168)
				)
				(xy 24.66086 -425.957492) (xy 24.825198 -425.957492)
				(arc
					(start 25.027382 -425.755308)
					(mid 25.461644 -425.462524)
					(end 25.16886 -425.896786)
				)
				(xy 24.908002 -426.157644) (xy 24.66086 -426.157644) (xy 24.66086 -426.262546) (xy 24.908256 -426.262546)
				(arc
					(start 25.16886 -426.52315)
					(mid 25.461644 -426.957412)
					(end 25.027382 -426.664628)
				)
				(xy 24.825452 -426.462698) (xy 24.66086 -426.462698)
				(arc
					(start 24.66086 -426.768768)
					(mid 25.273 -427.380908)
					(end 25.88514 -426.768768)
				)
			)
		)
	)
	(zone
		(net "P12V_SSD1")
		(layer "F.Cu")
		(hatch none 0.5)
		(connect_pads
			(clearance 0.5)
		)
		(min_thickness 0.25)
		(fill yes
			(thermal_gap 0.5)
			(thermal_bridge_width 0.5)
			(island_removal_mode 0)
		)
		(polygon
			(pts
				(xy 225.914712 -390.671812) (xy 225.806 -390.780524) (xy 225.806 -392.684) (xy 225.5012 -392.9888)
				(xy 224.8916 -392.9888) (xy 222.5802 -395.3002) (xy 217.7796 -395.3002) (xy 217.7034 -395.3764)
				(xy 216.535 -395.3764) (xy 216.3064 -395.605) (xy 216.3064 -400.1262) (xy 216.6112 -400.431) (xy 223.3676 -400.431)
				(xy 223.7486 -400.812) (xy 223.7486 -403.9362) (xy 224.1804 -404.368) (xy 227.5078 -404.368) (xy 228.219 -403.6568)
				(xy 228.219 -400.431) (xy 226.822 -399.034) (xy 226.822 -398.145) (xy 228.473 -396.494) (xy 228.473 -390.773158)
				(xy 228.371654 -390.671812)
			)
		)
		(polygon
			(pts
				(xy 227.2538 -403.7838) (xy 227.0506 -403.7838) (xy 227.0506 -403.987) (xy 227.2538 -403.987)
			)
		)
		(polygon
			(pts
				(xy 226.1108 -403.7838) (xy 225.9076 -403.7838) (xy 225.9076 -403.987) (xy 226.1108 -403.987)
			)
		)
		(polygon
			(pts
				(xy 227.2538 -400.9898) (xy 227.0506 -400.9898) (xy 227.0506 -401.193) (xy 227.2538 -401.193)
			)
		)
		(polygon
			(pts
				(xy 226.1108 -400.9898) (xy 225.9076 -400.9898) (xy 225.9076 -401.193) (xy 226.1108 -401.193)
			)
		)
		(polygon
			(pts
				(xy 220.4974 -399.4404) (xy 220.2942 -399.4404) (xy 220.2942 -399.6436) (xy 220.4974 -399.6436)
			)
		)
		(polygon
			(pts
				(xy 219.6338 -399.4404) (xy 219.4306 -399.4404) (xy 219.4306 -399.6436) (xy 219.6338 -399.6436)
			)
		)
		(polygon
			(pts
				(xy 222.4532 -395.8082) (xy 222.25 -395.8082) (xy 222.25 -396.0114) (xy 222.4532 -396.0114)
			)
		)
		(polygon
			(pts
				(xy 221.8436 -395.8082) (xy 221.6404 -395.8082) (xy 221.6404 -396.0114) (xy 221.8436 -396.0114)
			)
		)
	)
	(zone
		(layer "F.Cu")
		(hatch none 0.5)
		(connect_pads
			(clearance 0)
		)
		(min_thickness 0.25)
		(keepout
			(tracks allowed)
			(vias allowed)
			(pads allowed)
			(copperpour allowed)
			(footprints allowed)
		)
		(placement
			(enabled no)
			(sheetname "")
		)
		(fill
			(thermal_gap 0.5)
			(thermal_bridge_width 0.5)
			(island_removal_mode 0)
		)
		(polygon
			(pts
				(xy 37.338 -185.928) (xy 37.338 -169.291) (xy 39.497 -169.291) (xy 39.497 -185.928)
			)
		)
	)
	(zone
		(layer "F.Cu")
		(hatch none 0.5)
		(connect_pads
			(clearance 0)
		)
		(min_thickness 0.25)
		(keepout
			(tracks not_allowed)
			(vias allowed)
			(pads allowed)
			(copperpour not_allowed)
			(footprints allowed)
		)
		(placement
			(enabled no)
			(sheetname "")
		)
		(fill
			(thermal_gap 0.5)
			(thermal_bridge_width 0.5)
			(island_removal_mode 0)
		)
		(polygon
			(pts
				(arc
					(start 7.502906 -321.935856)
					(mid 6.992366 -321.425316)
					(end 6.481826 -321.935856)
				)
				(xy 6.481826 -322.089272) (xy 6.697472 -322.089272)
				(arc
					(start 6.746748 -322.039996)
					(mid 7.18101 -321.747212)
					(end 6.888226 -322.181474)
				)
				(xy 6.780276 -322.289424) (xy 6.481826 -322.289424) (xy 6.481826 -322.394326) (xy 6.779514 -322.394326)
				(arc
					(start 6.888226 -322.503038)
					(mid 7.18101 -322.9373)
					(end 6.746748 -322.644516)
				)
				(xy 6.69671 -322.594478) (xy 6.481826 -322.594478)
				(arc
					(start 6.481826 -322.748402)
					(mid 6.992239 -323.259196)
					(end 7.502906 -322.748656)
				)
			)
		)
	)
	(zone
		(net "P12V_SSD7")
		(layer "F.Cu")
		(hatch none 0.5)
		(connect_pads
			(clearance 0.5)
		)
		(min_thickness 0.25)
		(fill yes
			(thermal_gap 0.5)
			(thermal_bridge_width 0.5)
			(island_removal_mode 0)
		)
		(polygon
			(pts
				(xy 40.776398 -287.820608) (xy 40.7162 -287.880806) (xy 40.7162 -289.7378) (xy 40.4876 -289.9664)
				(xy 39.9288 -289.9664) (xy 37.9984 -291.8968) (xy 31.877 -291.8968) (xy 31.0896 -292.6842) (xy 31.0896 -296.9006)
				(xy 31.623 -297.434) (xy 38.3032 -297.434) (xy 38.5572 -297.688) (xy 38.5572 -302.4378) (xy 38.7096 -302.5902)
				(xy 42.7228 -302.5902) (xy 43.18 -302.133) (xy 43.18 -297.434) (xy 41.783 -296.037) (xy 41.783 -295.148)
				(xy 43.434 -293.497) (xy 43.434 -287.97377) (xy 43.280838 -287.820608)
			)
		)
		(polygon
			(pts
				(xy 41.3258 -300.8884) (xy 41.1226 -300.8884) (xy 41.1226 -301.0916) (xy 41.3258 -301.0916)
			)
		)
		(polygon
			(pts
				(xy 40.1828 -300.8884) (xy 39.9796 -300.8884) (xy 39.9796 -301.0916) (xy 40.1828 -301.0916)
			)
		)
		(polygon
			(pts
				(xy 41.3258 -298.0944) (xy 41.1226 -298.0944) (xy 41.1226 -298.2976) (xy 41.3258 -298.2976)
			)
		)
		(polygon
			(pts
				(xy 40.1828 -298.0944) (xy 39.9796 -298.0944) (xy 39.9796 -298.2976) (xy 40.1828 -298.2976)
			)
		)
		(polygon
			(pts
				(xy 38.2524 -296.3164) (xy 38.0492 -296.3164) (xy 38.0492 -296.5196) (xy 38.2524 -296.5196)
			)
		)
		(polygon
			(pts
				(xy 37.3888 -296.3164) (xy 37.1856 -296.3164) (xy 37.1856 -296.5196) (xy 37.3888 -296.5196)
			)
		)
		(polygon
			(pts
				(xy 37.4396 -292.4048) (xy 37.2364 -292.4048) (xy 37.2364 -292.608) (xy 37.4396 -292.608)
			)
		)
		(polygon
			(pts
				(xy 36.83 -292.4048) (xy 36.6268 -292.4048) (xy 36.6268 -292.608) (xy 36.83 -292.608)
			)
		)
	)
	(zone
		(net "VDD_DIFF_1")
		(layer "F.Cu")
		(hatch none 0.5)
		(connect_pads
			(clearance 0.5)
		)
		(min_thickness 0.25)
		(fill yes
			(thermal_gap 0.5)
			(thermal_bridge_width 0.5)
			(island_removal_mode 0)
		)
		(polygon
			(pts
				(xy 79.7814 -431.8762) (xy 79.260954 -432.396646) (xy 78.589124 -432.396646) (xy 78.5114 -432.47437)
				(xy 78.5114 -434.1114) (xy 79.2988 -434.8988) (xy 79.2988 -438.8866) (xy 79.4512 -439.039) (xy 82.4992 -439.039)
				(xy 82.7786 -438.7596) (xy 82.7786 -435.8386) (xy 82.6516 -435.7116) (xy 81.4578 -435.7116) (xy 81.0768 -435.3306)
				(xy 81.0768 -434.848) (xy 81.5086 -434.4162) (xy 82.7024 -434.4162) (xy 82.7786 -434.34) (xy 82.7786 -432.2318)
				(xy 82.423 -431.8762)
			)
		)
		(polygon
			(pts
				(xy 82.3214 -438.3278) (xy 82.1182 -438.3278) (xy 82.1182 -438.531) (xy 82.3214 -438.531)
			)
		)
		(polygon
			(pts
				(xy 82.3214 -437.769) (xy 82.1182 -437.769) (xy 82.1182 -437.9722) (xy 82.3214 -437.9722)
			)
		)
		(polygon
			(pts
				(xy 82.3214 -437.3118) (xy 82.1182 -437.3118) (xy 82.1182 -437.515) (xy 82.3214 -437.515)
			)
		)
		(polygon
			(pts
				(xy 82.3214 -436.753) (xy 82.1182 -436.753) (xy 82.1182 -436.9562) (xy 82.3214 -436.9562)
			)
		)
		(polygon
			(pts
				(xy 82.3214 -436.2958) (xy 82.1182 -436.2958) (xy 82.1182 -436.499) (xy 82.3214 -436.499)
			)
		)
		(polygon
			(pts
				(xy 80.4926 -436.118) (xy 80.2894 -436.118) (xy 80.2894 -436.3212) (xy 80.4926 -436.3212)
			)
		)
		(polygon
			(pts
				(xy 79.629 -436.118) (xy 79.4258 -436.118) (xy 79.4258 -436.3212) (xy 79.629 -436.3212)
			)
		)
		(polygon
			(pts
				(xy 80.4926 -435.2544) (xy 80.2894 -435.2544) (xy 80.2894 -435.4576) (xy 80.4926 -435.4576)
			)
		)
		(polygon
			(pts
				(xy 79.629 -435.2544) (xy 79.4258 -435.2544) (xy 79.4258 -435.4576) (xy 79.629 -435.4576)
			)
		)
		(polygon
			(pts
				(xy 82.3214 -433.578) (xy 82.1182 -433.578) (xy 82.1182 -433.7812) (xy 82.3214 -433.7812)
			)
		)
		(polygon
			(pts
				(xy 82.3214 -433.07) (xy 82.1182 -433.07) (xy 82.1182 -433.2732) (xy 82.3214 -433.2732)
			)
		)
		(polygon
			(pts
				(xy 79.1972 -432.8541) (xy 78.994 -432.8541) (xy 78.994 -433.0573) (xy 79.1972 -433.0573)
			)
		)
		(polygon
			(pts
				(xy 82.3214 -432.5112) (xy 82.1182 -432.5112) (xy 82.1182 -432.7144) (xy 82.3214 -432.7144)
			)
		)
	)
	(zone
		(net "GND")
		(layer "F.Cu")
		(hatch none 0.5)
		(connect_pads
			(clearance 0.5)
		)
		(min_thickness 0.25)
		(fill yes
			(thermal_gap 0.5)
			(thermal_bridge_width 0.5)
			(island_removal_mode 0)
		)
		(polygon
			(pts
				(xy 34.2646 -194.5894) (xy 33.8582 -194.9958) (xy 33.8582 -196.7992) (xy 34.3154 -197.2564) (xy 37.592 -197.2564)
				(xy 37.9984 -196.85) (xy 37.9984 -194.9196) (xy 37.6682 -194.5894)
			)
		)
		(polygon
			(pts
				(xy 37.7444 -195.3768) (xy 37.5412 -195.3768) (xy 37.5412 -195.58) (xy 37.7444 -195.58)
			)
		)
		(polygon
			(pts
				(xy 36.8808 -195.3768) (xy 36.6776 -195.3768) (xy 36.6776 -195.58) (xy 36.8808 -195.58)
			)
		)
	)
	(zone
		(layer "F.Cu")
		(hatch none 0.5)
		(connect_pads
			(clearance 0)
		)
		(min_thickness 0.25)
		(keepout
			(tracks allowed)
			(vias allowed)
			(pads allowed)
			(copperpour allowed)
			(footprints allowed)
		)
		(placement
			(enabled no)
			(sheetname "")
		)
		(fill
			(thermal_gap 0.5)
			(thermal_bridge_width 0.5)
			(island_removal_mode 0)
		)
		(polygon
			(pts
				(xy 37.338 -58.928) (xy 37.338 -51.816) (xy 39.497 -51.816) (xy 39.497 -58.928)
			)
		)
	)
	(zone
		(layer "F.Cu")
		(hatch none 0.5)
		(connect_pads
			(clearance 0)
		)
		(min_thickness 0.25)
		(keepout
			(tracks not_allowed)
			(vias allowed)
			(pads allowed)
			(copperpour not_allowed)
			(footprints allowed)
		)
		(placement
			(enabled no)
			(sheetname "")
		)
		(fill
			(thermal_gap 0.5)
			(thermal_bridge_width 0.5)
			(island_removal_mode 0)
		)
		(polygon
			(pts
				(xy 1.022096 -460.995776) (xy 3.758184 -460.995776) (xy 3.81 -461.047592) (xy 3.81 -461.239108)
				(xy 3.761232 -461.287876) (xy 1.025398 -461.287876) (xy 1.014984 -461.29829) (xy 1.010158 -461.29829)
				(xy 1.005332 -461.293464) (xy 1.005332 -460.99095) (xy 1.007872 -460.98841) (xy 1.01473 -460.98841)
			)
		)
	)
	(zone
		(net "P12V")
		(layer "F.Cu")
		(hatch none 0.5)
		(connect_pads
			(clearance 0.5)
		)
		(min_thickness 0.25)
		(fill yes
			(thermal_gap 0.5)
			(thermal_bridge_width 0.5)
			(island_removal_mode 0)
		)
		(polygon
			(pts
				(xy 200.085706 -491.263178) (xy 199.984106 -491.364778) (xy 199.984106 -491.745778) (xy 200.111106 -491.872778)
				(xy 200.746106 -491.872778) (xy 201.025506 -492.152178) (xy 201.025506 -493.599978) (xy 202.041506 -494.615978)
				(xy 202.041506 -497.164106) (xy 202.184 -497.3066) (xy 205.3844 -497.3066) (xy 206.715106 -495.975894)
				(xy 206.715106 -492.939578) (xy 205.826106 -492.050578) (xy 202.828906 -492.050578) (xy 202.041506 -491.263178)
			)
		)
		(polygon
			(pts
				(xy 201.685906 -492.812578) (xy 201.482706 -492.812578) (xy 201.482706 -493.015778) (xy 201.685906 -493.015778)
			)
		)
		(polygon
			(pts
				(xy 201.685906 -492.253778) (xy 201.482706 -492.253778) (xy 201.482706 -492.456978) (xy 201.685906 -492.456978)
			)
		)
		(polygon
			(pts
				(xy 201.787506 -491.771178) (xy 201.584306 -491.771178) (xy 201.584306 -491.974378) (xy 201.787506 -491.974378)
			)
		)
	)
	(zone
		(net "P12V_SSD13")
		(layer "F.Cu")
		(hatch none 0.5)
		(connect_pads
			(clearance 0.5)
		)
		(min_thickness 0.25)
		(fill yes
			(thermal_gap 0.5)
			(thermal_bridge_width 0.5)
			(island_removal_mode 0)
		)
		(polygon
			(pts
				(xy 20.1676 -100.6348) (xy 19.305016 -101.497384) (xy 19.305016 -106.046016) (xy 20.193 -106.934)
				(xy 20.193 -107.823) (xy 18.542 -109.474) (xy 18.542 -115.20551) (xy 18.657316 -115.320826) (xy 21.056092 -115.320826)
				(xy 21.209 -115.167918) (xy 21.209 -113.284) (xy 21.463 -113.03) (xy 22.479 -113.03) (xy 24.5618 -110.9472)
				(xy 30.099 -110.9472) (xy 30.607 -110.4392) (xy 30.607 -105.7656) (xy 30.3784 -105.537) (xy 24.003 -105.537)
				(xy 23.71852 -105.25252) (xy 23.71852 -100.88372) (xy 23.4696 -100.6348)
			)
		)
		(polygon
			(pts
				(xy 25.4 -110.236) (xy 25.1968 -110.236) (xy 25.1968 -110.4392) (xy 25.4 -110.4392)
			)
		)
		(polygon
			(pts
				(xy 24.7904 -110.236) (xy 24.5872 -110.236) (xy 24.5872 -110.4392) (xy 24.7904 -110.4392)
			)
		)
		(polygon
			(pts
				(xy 28.067 -106.4006) (xy 27.8638 -106.4006) (xy 27.8638 -106.6038) (xy 28.067 -106.6038)
			)
		)
		(polygon
			(pts
				(xy 27.2034 -106.4006) (xy 27.0002 -106.4006) (xy 27.0002 -106.6038) (xy 27.2034 -106.6038)
			)
		)
		(polygon
			(pts
				(xy 22.5298 -104.7242) (xy 22.3266 -104.7242) (xy 22.3266 -104.9274) (xy 22.5298 -104.9274)
			)
		)
		(polygon
			(pts
				(xy 21.3868 -104.7242) (xy 21.1836 -104.7242) (xy 21.1836 -104.9274) (xy 21.3868 -104.9274)
			)
		)
		(polygon
			(pts
				(xy 22.5298 -101.9302) (xy 22.3266 -101.9302) (xy 22.3266 -102.1334) (xy 22.5298 -102.1334)
			)
		)
		(polygon
			(pts
				(xy 21.3868 -101.9302) (xy 21.1836 -101.9302) (xy 21.1836 -102.1334) (xy 21.3868 -102.1334)
			)
		)
	)
	(zone
		(net "GND")
		(layer "F.Cu")
		(hatch none 0.5)
		(connect_pads
			(clearance 0.5)
		)
		(min_thickness 0.25)
		(fill yes
			(thermal_gap 0.5)
			(thermal_bridge_width 0.5)
			(island_removal_mode 0)
		)
		(polygon
			(pts
				(xy 42.820082 -127.595376) (xy 37.126418 -133.28904) (xy 37.126418 -134.88924) (xy 37.552884 -135.315706)
				(xy 41.897046 -135.315706) (xy 44.116752 -133.096) (xy 52.324 -133.096) (xy 53.131212 -133.903212)
				(xy 53.131212 -139.568428) (xy 55.903114 -142.34033) (xy 57.089294 -142.34033) (xy 69.413374 -130.01625)
				(xy 69.413374 -128.140714) (xy 68.868036 -127.595376)
			)
		)
	)
	(zone
		(net "GND")
		(layer "F.Cu")
		(hatch none 0.5)
		(connect_pads
			(clearance 0.5)
		)
		(min_thickness 0.25)
		(fill yes
			(thermal_gap 0.5)
			(thermal_bridge_width 0.5)
			(island_removal_mode 0)
		)
		(polygon
			(pts
				(xy 102.205028 -108.70565) (xy 101.383846 -109.526832) (xy 101.383846 -118.936516) (xy 87.060278 -133.260084)
				(xy 74.910696 -133.260084) (xy 73.418954 -134.751826) (xy 73.418954 -136.794494) (xy 74.131678 -137.507218)
				(xy 89.338912 -137.507218) (xy 105.261664 -121.584466) (xy 105.261664 -109.19968) (xy 104.767634 -108.70565)
			)
		)
	)
	(zone
		(net "GND")
		(layer "F.Cu")
		(hatch none 0.5)
		(connect_pads
			(clearance 0.5)
		)
		(min_thickness 0.25)
		(fill yes
			(thermal_gap 0.5)
			(thermal_bridge_width 0.5)
			(island_removal_mode 0)
		)
		(polygon
			(pts
				(xy 24.7396 -420.3446) (xy 24.13 -420.9542) (xy 24.13 -422.4274) (xy 24.257 -422.5544) (xy 25.8826 -422.5544)
				(xy 26.5684 -421.8686) (xy 28.8798 -421.8686) (xy 29.0576 -421.6908) (xy 29.0576 -420.6748) (xy 28.7274 -420.3446)
			)
		)
		(polygon
			(pts
				(xy 25.527 -420.8526) (xy 25.3238 -420.8526) (xy 25.3238 -421.0558) (xy 25.527 -421.0558)
			)
		)
		(polygon
			(pts
				(xy 24.9174 -420.8526) (xy 24.7142 -420.8526) (xy 24.7142 -421.0558) (xy 24.9174 -421.0558)
			)
		)
	)
	(zone
		(layer "F.Cu")
		(hatch none 0.5)
		(connect_pads
			(clearance 0)
		)
		(min_thickness 0.25)
		(keepout
			(tracks not_allowed)
			(vias allowed)
			(pads allowed)
			(copperpour not_allowed)
			(footprints allowed)
		)
		(placement
			(enabled no)
			(sheetname "")
		)
		(fill
			(thermal_gap 0.5)
			(thermal_bridge_width 0.5)
			(island_removal_mode 0)
		)
		(polygon
			(pts
				(arc
					(start 7.502906 -446.384172)
					(mid 6.992366 -445.873632)
					(end 6.481826 -446.384172)
				)
				(xy 6.481826 -446.537842) (xy 6.697218 -446.537842)
				(arc
					(start 6.746748 -446.488312)
					(mid 7.18101 -446.195528)
					(end 6.888226 -446.62979)
				)
				(xy 6.780022 -446.737994) (xy 6.481826 -446.737994) (xy 6.481826 -446.842896) (xy 6.779768 -446.842896)
				(arc
					(start 6.888226 -446.951354)
					(mid 7.18101 -447.385616)
					(end 6.746748 -447.092832)
				)
				(xy 6.696964 -447.043048) (xy 6.481826 -447.043048)
				(arc
					(start 6.481826 -447.196718)
					(mid 6.992239 -447.707512)
					(end 7.502906 -447.196972)
				)
			)
		)
	)
	(zone
		(layer "F.Cu")
		(hatch none 0.5)
		(connect_pads
			(clearance 0)
		)
		(min_thickness 0.25)
		(keepout
			(tracks not_allowed)
			(vias allowed)
			(pads allowed)
			(copperpour not_allowed)
			(footprints allowed)
		)
		(placement
			(enabled no)
			(sheetname "")
		)
		(fill
			(thermal_gap 0.5)
			(thermal_bridge_width 0.5)
			(island_removal_mode 0)
		)
		(polygon
			(pts
				(xy 97.81921 -306.59578) (xy 97.81921 -306.684426) (xy 97.819464 -306.68468) (xy 98.98761 -306.68468)
				(xy 98.98761 -306.59578)
			)
		)
	)
	(zone
		(layer "F.Cu")
		(hatch none 0.5)
		(connect_pads
			(clearance 0)
		)
		(min_thickness 0.25)
		(keepout
			(tracks not_allowed)
			(vias allowed)
			(pads allowed)
			(copperpour not_allowed)
			(footprints allowed)
		)
		(placement
			(enabled no)
			(sheetname "")
		)
		(fill
			(thermal_gap 0.5)
			(thermal_bridge_width 0.5)
			(island_removal_mode 0)
		)
		(polygon
			(pts
				(arc
					(start 7.502906 -431.184558)
					(mid 6.992493 -430.673764)
					(end 6.481826 -431.184304)
				)
				(xy 6.481826 -431.31867) (xy 6.716522 -431.31867)
				(arc
					(start 6.746748 -431.288444)
					(mid 7.18101 -430.99566)
					(end 6.888226 -431.429922)
				)
				(xy 6.799326 -431.518822) (xy 6.481826 -431.518822) (xy 6.481826 -431.623724) (xy 6.760464 -431.623724)
				(arc
					(start 6.888226 -431.751486)
					(mid 7.18101 -432.185748)
					(end 6.746748 -431.892964)
				)
				(xy 6.67766 -431.823876) (xy 6.481826 -431.823876)
				(arc
					(start 6.481826 -431.997104)
					(mid 6.992366 -432.507644)
					(end 7.502906 -431.997104)
				)
			)
		)
	)
	(zone
		(net "GND")
		(layer "F.Cu")
		(hatch none 0.5)
		(connect_pads
			(clearance 0.5)
		)
		(min_thickness 0.25)
		(fill yes
			(thermal_gap 0.5)
			(thermal_bridge_width 0.5)
			(island_removal_mode 0)
		)
		(polygon
			(pts
				(xy 217.8304 -495.3254) (xy 217.7542 -495.4016) (xy 217.7542 -495.8842) (xy 217.8558 -495.9858)
				(xy 219.329 -495.9858) (xy 219.3798 -495.935) (xy 219.3798 -495.3762) (xy 219.329 -495.3254)
			)
		)
	)
	(zone
		(net "VDD_DIFF_3")
		(layer "F.Cu")
		(hatch none 0.5)
		(connect_pads
			(clearance 0.5)
		)
		(min_thickness 0.25)
		(fill yes
			(thermal_gap 0.5)
			(thermal_bridge_width 0.5)
			(island_removal_mode 0)
		)
		(polygon
			(pts
				(xy 79.7814 -210.8962) (xy 79.249524 -211.428076) (xy 78.131924 -211.428076) (xy 78.0034 -211.5566)
				(xy 78.0034 -212.9536) (xy 79.2988 -214.249) (xy 79.2988 -218.0336) (xy 79.4766 -218.2114) (xy 82.3468 -218.2114)
				(xy 82.7786 -217.7796) (xy 82.7786 -214.8586) (xy 82.6516 -214.7316) (xy 81.4578 -214.7316) (xy 81.0768 -214.3506)
				(xy 81.0768 -213.868) (xy 81.5086 -213.4362) (xy 82.7024 -213.4362) (xy 82.7786 -213.36) (xy 82.7786 -211.2518)
				(xy 82.423 -210.8962)
			)
		)
		(polygon
			(pts
				(xy 82.3214 -217.3478) (xy 82.1182 -217.3478) (xy 82.1182 -217.551) (xy 82.3214 -217.551)
			)
		)
		(polygon
			(pts
				(xy 82.3214 -216.789) (xy 82.1182 -216.789) (xy 82.1182 -216.9922) (xy 82.3214 -216.9922)
			)
		)
		(polygon
			(pts
				(xy 82.3214 -216.3318) (xy 82.1182 -216.3318) (xy 82.1182 -216.535) (xy 82.3214 -216.535)
			)
		)
		(polygon
			(pts
				(xy 82.3214 -215.773) (xy 82.1182 -215.773) (xy 82.1182 -215.9762) (xy 82.3214 -215.9762)
			)
		)
		(polygon
			(pts
				(xy 80.2132 -215.392) (xy 80.01 -215.392) (xy 80.01 -215.5952) (xy 80.2132 -215.5952)
			)
		)
		(polygon
			(pts
				(xy 82.3214 -215.3158) (xy 82.1182 -215.3158) (xy 82.1182 -215.519) (xy 82.3214 -215.519)
			)
		)
		(polygon
			(pts
				(xy 80.2132 -214.5284) (xy 80.01 -214.5284) (xy 80.01 -214.7316) (xy 80.2132 -214.7316)
			)
		)
		(polygon
			(pts
				(xy 82.3214 -212.598) (xy 82.1182 -212.598) (xy 82.1182 -212.8012) (xy 82.3214 -212.8012)
			)
		)
		(polygon
			(pts
				(xy 82.3214 -212.1154) (xy 82.1182 -212.1154) (xy 82.1182 -212.3186) (xy 82.3214 -212.3186)
			)
		)
		(polygon
			(pts
				(xy 78.7654 -211.8868) (xy 78.5622 -211.8868) (xy 78.5622 -212.09) (xy 78.7654 -212.09)
			)
		)
		(polygon
			(pts
				(xy 82.3214 -211.5566) (xy 82.1182 -211.5566) (xy 82.1182 -211.7598) (xy 82.3214 -211.7598)
			)
		)
	)
	(zone
		(layer "F.Cu")
		(hatch none 0.5)
		(connect_pads
			(clearance 0)
		)
		(min_thickness 0.25)
		(keepout
			(tracks not_allowed)
			(vias allowed)
			(pads allowed)
			(copperpour not_allowed)
			(footprints allowed)
		)
		(placement
			(enabled no)
			(sheetname "")
		)
		(fill
			(thermal_gap 0.5)
			(thermal_bridge_width 0.5)
			(island_removal_mode 0)
		)
		(polygon
			(pts
				(arc
					(start 220.840554 -488.984036)
					(mid 220.330141 -488.473242)
					(end 219.819474 -488.983782)
				)
				(arc
					(start 219.819474 -489.796582)
					(mid 220.330014 -490.307122)
					(end 220.840554 -489.796582)
				)
				(xy 220.840554 -489.642912) (xy 220.625162 -489.642912)
				(arc
					(start 220.575632 -489.692442)
					(mid 220.14137 -489.985226)
					(end 220.434154 -489.550964)
				)
				(xy 220.542358 -489.44276) (xy 220.840554 -489.44276) (xy 220.840554 -489.337858) (xy 220.542612 -489.337858)
				(arc
					(start 220.434154 -489.2294)
					(mid 220.14137 -488.795138)
					(end 220.575632 -489.087922)
				)
				(xy 220.625416 -489.137706) (xy 220.840554 -489.137706)
			)
		)
	)
	(zone
		(layer "F.Cu")
		(hatch none 0.5)
		(connect_pads
			(clearance 0)
		)
		(min_thickness 0.25)
		(keepout
			(tracks allowed)
			(vias allowed)
			(pads allowed)
			(copperpour allowed)
			(footprints allowed)
		)
		(placement
			(enabled no)
			(sheetname "")
		)
		(fill
			(thermal_gap 0.5)
			(thermal_bridge_width 0.5)
			(island_removal_mode 0)
		)
		(polygon
			(pts
				(xy 44.323 -369.316) (xy 44.323 -371.602) (xy 42.164 -371.602) (xy 42.164 -369.316)
			)
		)
	)
	(zone
		(layer "F.Cu")
		(hatch none 0.5)
		(connect_pads
			(clearance 0)
		)
		(min_thickness 0.25)
		(keepout
			(tracks not_allowed)
			(vias allowed)
			(pads allowed)
			(copperpour not_allowed)
			(footprints allowed)
		)
		(placement
			(enabled no)
			(sheetname "")
		)
		(fill
			(thermal_gap 0.5)
			(thermal_bridge_width 0.5)
			(island_removal_mode 0)
		)
		(polygon
			(pts
				(arc
					(start 32.00654 -135.603996)
					(mid 31.496127 -135.093202)
					(end 30.98546 -135.603742)
				)
				(arc
					(start 30.98546 -136.416542)
					(mid 31.496 -136.927082)
					(end 32.00654 -136.416542)
				)
				(xy 32.00654 -136.262618) (xy 31.791402 -136.262618)
				(arc
					(start 31.741618 -136.312402)
					(mid 31.307356 -136.605186)
					(end 31.60014 -136.170924)
				)
				(xy 31.708598 -136.062466) (xy 32.00654 -136.062466) (xy 32.00654 -135.957564) (xy 31.708344 -135.957564)
				(arc
					(start 31.60014 -135.84936)
					(mid 31.307356 -135.415098)
					(end 31.741618 -135.707882)
				)
				(xy 31.791148 -135.757412) (xy 32.00654 -135.757412)
			)
		)
	)
	(zone
		(net "P12V")
		(layer "F.Cu")
		(hatch none 0.5)
		(connect_pads
			(clearance 0.5)
		)
		(min_thickness 0.25)
		(fill yes
			(thermal_gap 0.5)
			(thermal_bridge_width 0.5)
			(island_removal_mode 0)
		)
		(polygon
			(pts
				(xy 23.8506 -393.9794) (xy 23.749 -394.081) (xy 23.749 -394.462) (xy 23.876 -394.589) (xy 24.511 -394.589)
				(xy 24.7904 -394.8684) (xy 24.7904 -397.0274) (xy 25.908 -398.145) (xy 25.908 -399.83664) (xy 25.498806 -400.245834)
				(xy 25.498806 -401.754594) (xy 25.680162 -401.93595) (xy 26.597356 -401.93595) (xy 26.818844 -401.714462)
				(xy 26.818844 -401.139914) (xy 27.124406 -400.834352) (xy 29.390848 -400.834352) (xy 29.5402 -400.685)
				(xy 29.5402 -395.8336) (xy 29.2354 -395.5288) (xy 26.1366 -395.5288) (xy 25.908 -395.3002) (xy 25.908 -394.4874)
				(xy 25.4 -393.9794)
			)
		)
		(polygon
			(pts
				(xy 26.54935 -401.27555) (xy 26.34615 -401.27555) (xy 26.34615 -401.47875) (xy 26.54935 -401.47875)
			)
		)
		(polygon
			(pts
				(xy 25.99055 -401.27555) (xy 25.78735 -401.27555) (xy 25.78735 -401.47875) (xy 25.99055 -401.47875)
			)
		)
		(polygon
			(pts
				(xy 25.4508 -395.5288) (xy 25.2476 -395.5288) (xy 25.2476 -395.732) (xy 25.4508 -395.732)
			)
		)
		(polygon
			(pts
				(xy 25.4508 -394.97) (xy 25.2476 -394.97) (xy 25.2476 -395.1732) (xy 25.4508 -395.1732)
			)
		)
		(polygon
			(pts
				(xy 25.5524 -394.4874) (xy 25.3492 -394.4874) (xy 25.3492 -394.6906) (xy 25.5524 -394.6906)
			)
		)
	)
	(zone
		(layer "F.Cu")
		(hatch none 0.5)
		(connect_pads
			(clearance 0)
		)
		(min_thickness 0.25)
		(keepout
			(tracks not_allowed)
			(vias allowed)
			(pads allowed)
			(copperpour not_allowed)
			(footprints allowed)
		)
		(placement
			(enabled no)
			(sheetname "")
		)
		(fill
			(thermal_gap 0.5)
			(thermal_bridge_width 0.5)
			(island_removal_mode 0)
		)
		(polygon
			(pts
				(arc
					(start 7.502906 -201.536046)
					(mid 6.992493 -201.025252)
					(end 6.481826 -201.535792)
				)
				(xy 6.481826 -201.689208) (xy 6.697472 -201.689208)
				(arc
					(start 6.746748 -201.639932)
					(mid 7.18101 -201.347148)
					(end 6.888226 -201.78141)
				)
				(xy 6.780276 -201.88936) (xy 6.481826 -201.88936) (xy 6.481826 -201.994262) (xy 6.779514 -201.994262)
				(arc
					(start 6.888226 -202.102974)
					(mid 7.18101 -202.537236)
					(end 6.746748 -202.244452)
				)
				(xy 6.69671 -202.194414) (xy 6.481826 -202.194414)
				(arc
					(start 6.481826 -202.348592)
					(mid 6.992366 -202.859132)
					(end 7.502906 -202.348592)
				)
			)
		)
	)
	(zone
		(layer "F.Cu")
		(hatch none 0.5)
		(connect_pads
			(clearance 0)
		)
		(min_thickness 0.25)
		(keepout
			(tracks allowed)
			(vias allowed)
			(pads allowed)
			(copperpour allowed)
			(footprints allowed)
		)
		(placement
			(enabled no)
			(sheetname "")
		)
		(fill
			(thermal_gap 0.5)
			(thermal_bridge_width 0.5)
			(island_removal_mode 0)
		)
		(polygon
			(pts
				(xy 229.235 -472.313) (xy 229.235 -474.599) (xy 227.076 -474.599) (xy 227.076 -472.313)
			)
		)
	)
	(zone
		(layer "F.Cu")
		(hatch none 0.5)
		(connect_pads
			(clearance 0)
		)
		(min_thickness 0.25)
		(keepout
			(tracks allowed)
			(vias allowed)
			(pads allowed)
			(copperpour allowed)
			(footprints allowed)
		)
		(placement
			(enabled no)
			(sheetname "")
		)
		(fill
			(thermal_gap 0.5)
			(thermal_bridge_width 0.5)
			(island_removal_mode 0)
		)
		(polygon
			(pts
				(xy 78.0796 -102.9716) (xy 78.0796 -101.473) (xy 78.994 -101.473) (xy 78.994 -102.9716)
			)
		)
	)
	(zone
		(net "GND")
		(layer "F.Cu")
		(hatch none 0.5)
		(connect_pads
			(clearance 0.5)
		)
		(min_thickness 0.25)
		(fill yes
			(thermal_gap 0.5)
			(thermal_bridge_width 0.5)
			(island_removal_mode 0)
		)
		(polygon
			(pts
				(xy 24.4094 -205.74) (xy 24.13 -206.0194) (xy 24.13 -208.0514) (xy 24.2824 -208.2038) (xy 28.0162 -208.2038)
				(xy 28.1686 -208.0514) (xy 28.1686 -206.2988) (xy 27.6098 -205.74)
			)
		)
		(polygon
			(pts
				(xy 27.2796 -207.1116) (xy 27.0764 -207.1116) (xy 27.0764 -207.3148) (xy 27.2796 -207.3148)
			)
		)
	)
	(zone
		(layer "F.Cu")
		(hatch none 0.5)
		(connect_pads
			(clearance 0)
		)
		(min_thickness 0.25)
		(keepout
			(tracks not_allowed)
			(vias allowed)
			(pads allowed)
			(copperpour not_allowed)
			(footprints allowed)
		)
		(placement
			(enabled no)
			(sheetname "")
		)
		(fill
			(thermal_gap 0.5)
			(thermal_bridge_width 0.5)
			(island_removal_mode 0)
		)
		(polygon
			(pts
				(arc
					(start 27.18054 -325.203566)
					(mid 26.67 -324.693026)
					(end 26.15946 -325.203566)
				)
				(xy 26.15946 -325.357236) (xy 26.374852 -325.357236)
				(arc
					(start 26.424382 -325.307706)
					(mid 26.858644 -325.014922)
					(end 26.56586 -325.449184)
				)
				(xy 26.457656 -325.557388) (xy 26.15946 -325.557388) (xy 26.15946 -325.66229) (xy 26.457402 -325.66229)
				(arc
					(start 26.56586 -325.770748)
					(mid 26.858644 -326.20501)
					(end 26.424382 -325.912226)
				)
				(xy 26.374598 -325.862442) (xy 26.15946 -325.862442)
				(arc
					(start 26.15946 -326.016112)
					(mid 26.669873 -326.526906)
					(end 27.18054 -326.016366)
				)
			)
		)
	)
	(zone
		(layer "F.Cu")
		(hatch none 0.5)
		(connect_pads
			(clearance 0)
		)
		(min_thickness 0.25)
		(keepout
			(tracks not_allowed)
			(vias allowed)
			(pads allowed)
			(copperpour not_allowed)
			(footprints allowed)
		)
		(placement
			(enabled no)
			(sheetname "")
		)
		(fill
			(thermal_gap 0.5)
			(thermal_bridge_width 0.5)
			(island_removal_mode 0)
		)
		(polygon
			(pts
				(xy 96.89465 -205.81239) (xy 97.06483 -205.81239) (xy 97.06483 -206.98079) (xy 96.89465 -206.98079)
			)
		)
	)
	(zone
		(layer "F.Cu")
		(hatch none 0.5)
		(connect_pads
			(clearance 0)
		)
		(min_thickness 0.25)
		(keepout
			(tracks allowed)
			(vias allowed)
			(pads allowed)
			(copperpour allowed)
			(footprints allowed)
		)
		(placement
			(enabled no)
			(sheetname "")
		)
		(fill
			(thermal_gap 0.5)
			(thermal_bridge_width 0.5)
			(island_removal_mode 0)
		)
		(polygon
			(pts
				(xy 44.323 -266.192) (xy 44.323 -268.478) (xy 42.164 -268.478) (xy 42.164 -266.192)
			)
		)
	)
	(zone
		(net "GND")
		(layer "F.Cu")
		(hatch none 0.5)
		(connect_pads
			(clearance 0.5)
		)
		(min_thickness 0.25)
		(fill yes
			(thermal_gap 0.5)
			(thermal_bridge_width 0.5)
			(island_removal_mode 0)
		)
		(polygon
			(pts
				(xy 42.587164 -105.621836) (xy 41.06418 -107.14482) (xy 41.06418 -110.42142) (xy 40.425624 -111.059976)
				(xy 33.757108 -111.059976) (xy 33.239456 -111.577628) (xy 33.239456 -113.685066) (xy 33.699704 -114.145314)
				(xy 52.481734 -114.145314) (xy 56.137048 -110.49) (xy 58.674 -110.49) (xy 59.309 -111.125) (xy 59.309 -112.551464)
				(xy 56.036464 -115.824) (xy 31.369 -115.824) (xy 30.722824 -116.470176) (xy 28.44292 -116.470176)
				(xy 27.321764 -117.591332) (xy 27.321764 -130.048) (xy 27.577542 -130.303778) (xy 28.464256 -130.303778)
				(xy 38.372034 -120.396) (xy 43.942 -120.396) (xy 45.974 -122.428) (xy 79.121 -122.428) (xy 82.931 -118.618)
				(xy 82.931 -113.538) (xy 77.47 -108.077) (xy 75.565 -108.077) (xy 73.109836 -105.621836)
			)
		)
	)
	(zone
		(net "GND")
		(layer "F.Cu")
		(hatch none 0.5)
		(connect_pads
			(clearance 0.5)
		)
		(min_thickness 0.25)
		(fill yes
			(thermal_gap 0.5)
			(thermal_bridge_width 0.5)
			(island_removal_mode 0)
		)
		(polygon
			(pts
				(xy 23.213314 -381.511048) (xy 22.479 -382.245362) (xy 22.479 -390.779) (xy 23.749 -392.049) (xy 25.171146 -392.049)
				(xy 29.26461 -387.955536) (xy 30.461458 -387.955536) (xy 31.699962 -386.717032) (xy 31.699962 -383.605024)
				(xy 29.605986 -381.511048)
			)
		)
	)
	(zone
		(layer "F.Cu")
		(hatch none 0.5)
		(connect_pads
			(clearance 0)
		)
		(min_thickness 0.25)
		(keepout
			(tracks not_allowed)
			(vias allowed)
			(pads allowed)
			(copperpour not_allowed)
			(footprints allowed)
		)
		(placement
			(enabled no)
			(sheetname "")
		)
		(fill
			(thermal_gap 0.5)
			(thermal_bridge_width 0.5)
			(island_removal_mode 0)
		)
		(polygon
			(pts
				(arc
					(start 7.502906 -181.536086)
					(mid 6.992493 -181.025292)
					(end 6.481826 -181.535832)
				)
				(xy 6.481826 -181.689248) (xy 6.697472 -181.689248)
				(arc
					(start 6.746748 -181.639972)
					(mid 7.18101 -181.347188)
					(end 6.888226 -181.78145)
				)
				(xy 6.780276 -181.8894) (xy 6.481826 -181.8894) (xy 6.481826 -181.994302) (xy 6.779514 -181.994302)
				(arc
					(start 6.888226 -182.103014)
					(mid 7.18101 -182.537276)
					(end 6.746748 -182.244492)
				)
				(xy 6.69671 -182.194454) (xy 6.481826 -182.194454)
				(arc
					(start 6.481826 -182.348632)
					(mid 6.992366 -182.859172)
					(end 7.502906 -182.348632)
				)
			)
		)
	)
	(zone
		(layer "F.Cu")
		(hatch none 0.5)
		(connect_pads
			(clearance 0)
		)
		(min_thickness 0.25)
		(keepout
			(tracks not_allowed)
			(vias allowed)
			(pads allowed)
			(copperpour not_allowed)
			(footprints allowed)
		)
		(placement
			(enabled no)
			(sheetname "")
		)
		(fill
			(thermal_gap 0.5)
			(thermal_bridge_width 0.5)
			(island_removal_mode 0)
		)
		(polygon
			(pts
				(arc
					(start 7.502906 -328.335894)
					(mid 6.992366 -327.825354)
					(end 6.481826 -328.335894)
				)
				(xy 6.481826 -328.48931) (xy 6.697472 -328.48931)
				(arc
					(start 6.746748 -328.440034)
					(mid 7.18101 -328.14725)
					(end 6.888226 -328.581512)
				)
				(xy 6.780276 -328.689462) (xy 6.481826 -328.689462) (xy 6.481826 -328.794364) (xy 6.779514 -328.794364)
				(arc
					(start 6.888226 -328.903076)
					(mid 7.18101 -329.337338)
					(end 6.746748 -329.044554)
				)
				(xy 6.69671 -328.994516) (xy 6.481826 -328.994516)
				(arc
					(start 6.481826 -329.14844)
					(mid 6.992239 -329.659234)
					(end 7.502906 -329.148694)
				)
			)
		)
	)
	(zone
		(layer "F.Cu")
		(hatch none 0.5)
		(connect_pads
			(clearance 0)
		)
		(min_thickness 0.25)
		(keepout
			(tracks allowed)
			(vias allowed)
			(pads allowed)
			(copperpour allowed)
			(footprints allowed)
		)
		(placement
			(enabled no)
			(sheetname "")
		)
		(fill
			(thermal_gap 0.5)
			(thermal_bridge_width 0.5)
			(island_removal_mode 0)
		)
		(polygon
			(pts
				(xy 229.235 -60.198) (xy 229.235 -62.484) (xy 227.076 -62.484) (xy 227.076 -60.198)
			)
		)
	)
	(zone
		(layer "F.Cu")
		(hatch none 0.5)
		(connect_pads
			(clearance 0)
		)
		(min_thickness 0.25)
		(keepout
			(tracks not_allowed)
			(vias allowed)
			(pads allowed)
			(copperpour not_allowed)
			(footprints allowed)
		)
		(placement
			(enabled no)
			(sheetname "")
		)
		(fill
			(thermal_gap 0.5)
			(thermal_bridge_width 0.5)
			(island_removal_mode 0)
		)
		(polygon
			(pts
				(arc
					(start 17.78254 -135.603234)
					(mid 17.272 -135.092694)
					(end 16.76146 -135.603234)
				)
				(arc
					(start 16.76146 -136.41578)
					(mid 17.271873 -136.926574)
					(end 17.78254 -136.416034)
				)
				(xy 17.78254 -136.26211) (xy 17.567402 -136.26211)
				(arc
					(start 17.517618 -136.311894)
					(mid 17.083356 -136.604678)
					(end 17.37614 -136.170416)
				)
				(xy 17.484598 -136.061958) (xy 17.78254 -136.061958) (xy 17.78254 -135.957056) (xy 17.484344 -135.957056)
				(arc
					(start 17.37614 -135.848852)
					(mid 17.083356 -135.41459)
					(end 17.517618 -135.707374)
				)
				(xy 17.567148 -135.756904) (xy 17.78254 -135.756904)
			)
		)
	)
	(zone
		(layer "F.Cu")
		(hatch none 0.5)
		(connect_pads
			(clearance 0)
		)
		(min_thickness 0.25)
		(keepout
			(tracks not_allowed)
			(vias allowed)
			(pads allowed)
			(copperpour not_allowed)
			(footprints allowed)
		)
		(placement
			(enabled no)
			(sheetname "")
		)
		(fill
			(thermal_gap 0.5)
			(thermal_bridge_width 0.5)
			(island_removal_mode 0)
		)
		(polygon
			(pts
				(arc
					(start 233.897424 -472.579446)
					(mid 233.386884 -472.068906)
					(end 232.876344 -472.579446)
				)
				(arc
					(start 232.876344 -473.391992)
					(mid 233.386757 -473.902786)
					(end 233.897424 -473.392246)
				)
				(xy 233.897424 -473.238322) (xy 233.682286 -473.238322)
				(arc
					(start 233.632502 -473.288106)
					(mid 233.19824 -473.58089)
					(end 233.491024 -473.146628)
				)
				(xy 233.599482 -473.03817) (xy 233.897424 -473.03817) (xy 233.897424 -472.933268) (xy 233.599228 -472.933268)
				(arc
					(start 233.491024 -472.825064)
					(mid 233.19824 -472.390802)
					(end 233.632502 -472.683586)
				)
				(xy 233.682032 -472.733116) (xy 233.897424 -472.733116)
			)
		)
	)
	(zone
		(layer "F.Cu")
		(hatch none 0.5)
		(connect_pads
			(clearance 0)
		)
		(min_thickness 0.25)
		(keepout
			(tracks not_allowed)
			(vias allowed)
			(pads allowed)
			(copperpour not_allowed)
			(footprints allowed)
		)
		(placement
			(enabled no)
			(sheetname "")
		)
		(fill
			(thermal_gap 0.5)
			(thermal_bridge_width 0.5)
			(island_removal_mode 0)
		)
		(polygon
			(pts
				(arc
					(start 7.502906 -223.897952)
					(mid 6.992493 -223.387158)
					(end 6.481826 -223.897698)
				)
				(xy 6.481826 -224.051114) (xy 6.697472 -224.051114)
				(arc
					(start 6.746748 -224.001838)
					(mid 7.18101 -223.709054)
					(end 6.888226 -224.143316)
				)
				(xy 6.780276 -224.251266) (xy 6.481826 -224.251266) (xy 6.481826 -224.356168) (xy 6.779514 -224.356168)
				(arc
					(start 6.888226 -224.46488)
					(mid 7.18101 -224.899142)
					(end 6.746748 -224.606358)
				)
				(xy 6.69671 -224.55632) (xy 6.481826 -224.55632)
				(arc
					(start 6.481826 -224.710498)
					(mid 6.992366 -225.221038)
					(end 7.502906 -224.710498)
				)
			)
		)
	)
	(zone
		(layer "F.Cu")
		(hatch none 0.5)
		(connect_pads
			(clearance 0)
		)
		(min_thickness 0.25)
		(keepout
			(tracks not_allowed)
			(vias allowed)
			(pads allowed)
			(copperpour not_allowed)
			(footprints allowed)
		)
		(placement
			(enabled no)
			(sheetname "")
		)
		(fill
			(thermal_gap 0.5)
			(thermal_bridge_width 0.5)
			(island_removal_mode 0)
		)
		(polygon
			(pts
				(arc
					(start 35.84067 -67.383914)
					(mid 35.330257 -66.87312)
					(end 34.81959 -67.38366)
				)
				(arc
					(start 34.81959 -68.19646)
					(mid 35.33013 -68.707)
					(end 35.84067 -68.19646)
				)
				(xy 35.84067 -68.042536) (xy 35.625532 -68.042536)
				(arc
					(start 35.575748 -68.09232)
					(mid 35.141486 -68.385104)
					(end 35.43427 -67.950842)
				)
				(xy 35.542728 -67.842384) (xy 35.84067 -67.842384) (xy 35.84067 -67.737482) (xy 35.542474 -67.737482)
				(arc
					(start 35.43427 -67.629278)
					(mid 35.141486 -67.195016)
					(end 35.575748 -67.4878)
				)
				(xy 35.625278 -67.53733) (xy 35.84067 -67.53733)
			)
		)
	)
	(zone
		(layer "F.Cu")
		(hatch none 0.5)
		(connect_pads
			(clearance 0)
		)
		(min_thickness 0.25)
		(keepout
			(tracks not_allowed)
			(vias allowed)
			(pads allowed)
			(copperpour not_allowed)
			(footprints allowed)
		)
		(placement
			(enabled no)
			(sheetname "")
		)
		(fill
			(thermal_gap 0.5)
			(thermal_bridge_width 0.5)
			(island_removal_mode 0)
		)
		(polygon
			(pts
				(arc
					(start 7.502906 -175.186848)
					(mid 6.992493 -174.676054)
					(end 6.481826 -175.186594)
				)
				(xy 6.481826 -175.340264) (xy 6.697218 -175.340264)
				(arc
					(start 6.746748 -175.290734)
					(mid 7.18101 -174.99795)
					(end 6.888226 -175.432212)
				)
				(xy 6.780022 -175.540416) (xy 6.481826 -175.540416) (xy 6.481826 -175.645318) (xy 6.779768 -175.645318)
				(arc
					(start 6.888226 -175.753776)
					(mid 7.18101 -176.188038)
					(end 6.746748 -175.895254)
				)
				(xy 6.696964 -175.84547) (xy 6.481826 -175.84547)
				(arc
					(start 6.481826 -175.999394)
					(mid 6.992366 -176.509934)
					(end 7.502906 -175.999394)
				)
			)
		)
	)
	(zone
		(layer "F.Cu")
		(hatch none 0.5)
		(connect_pads
			(clearance 0)
		)
		(min_thickness 0.25)
		(keepout
			(tracks not_allowed)
			(vias allowed)
			(pads allowed)
			(copperpour not_allowed)
			(footprints allowed)
		)
		(placement
			(enabled no)
			(sheetname "")
		)
		(fill
			(thermal_gap 0.5)
			(thermal_bridge_width 0.5)
			(island_removal_mode 0)
		)
		(polygon
			(pts
				(arc
					(start 35.84067 -488.983782)
					(mid 35.33013 -488.473242)
					(end 34.81959 -488.983782)
				)
				(arc
					(start 34.81959 -489.796328)
					(mid 35.330003 -490.307122)
					(end 35.84067 -489.796582)
				)
				(xy 35.84067 -489.642912) (xy 35.625278 -489.642912)
				(arc
					(start 35.575748 -489.692442)
					(mid 35.141486 -489.985226)
					(end 35.43427 -489.550964)
				)
				(xy 35.542474 -489.44276) (xy 35.84067 -489.44276) (xy 35.84067 -489.337858) (xy 35.542728 -489.337858)
				(arc
					(start 35.43427 -489.2294)
					(mid 35.141486 -488.795138)
					(end 35.575748 -489.087922)
				)
				(xy 35.625532 -489.137706) (xy 35.84067 -489.137706)
			)
		)
	)
	(zone
		(layer "F.Cu")
		(hatch none 0.5)
		(connect_pads
			(clearance 0)
		)
		(min_thickness 0.25)
		(keepout
			(tracks not_allowed)
			(vias allowed)
			(pads allowed)
			(copperpour not_allowed)
			(footprints allowed)
		)
		(placement
			(enabled no)
			(sheetname "")
		)
		(fill
			(thermal_gap 0.5)
			(thermal_bridge_width 0.5)
			(island_removal_mode 0)
		)
		(polygon
			(pts
				(arc
					(start 35.84067 -282.98394)
					(mid 35.330257 -282.473146)
					(end 34.81959 -282.983686)
				)
				(arc
					(start 34.81959 -283.796486)
					(mid 35.33013 -284.307026)
					(end 35.84067 -283.796486)
				)
				(xy 35.84067 -283.642816) (xy 35.625278 -283.642816)
				(arc
					(start 35.575748 -283.692346)
					(mid 35.141486 -283.98513)
					(end 35.43427 -283.550868)
				)
				(xy 35.542474 -283.442664) (xy 35.84067 -283.442664) (xy 35.84067 -283.337762) (xy 35.542728 -283.337762)
				(arc
					(start 35.43427 -283.229304)
					(mid 35.141486 -282.795042)
					(end 35.575748 -283.087826)
				)
				(xy 35.625532 -283.13761) (xy 35.84067 -283.13761)
			)
		)
	)
	(zone
		(layer "F.Cu")
		(hatch none 0.5)
		(connect_pads
			(clearance 0)
		)
		(min_thickness 0.25)
		(keepout
			(tracks allowed)
			(vias allowed)
			(pads allowed)
			(copperpour allowed)
			(footprints not_allowed)
		)
		(placement
			(enabled no)
			(sheetname "")
		)
		(fill
			(thermal_gap 0.5)
			(thermal_bridge_width 0.5)
			(island_removal_mode 0)
		)
		(polygon
			(pts
				(xy 36.500054 -503.670062) (xy 36.500054 -447.170048) (xy 26.500074 -447.170048) (xy 26.500074 -467.460076)
				(xy 16.999966 -467.460076) (xy 16.999966 -503.670062)
			)
		)
	)
	(zone
		(layer "F.Cu")
		(hatch none 0.5)
		(connect_pads
			(clearance 0)
		)
		(min_thickness 0.25)
		(keepout
			(tracks not_allowed)
			(vias allowed)
			(pads allowed)
			(copperpour not_allowed)
			(footprints allowed)
		)
		(placement
			(enabled no)
			(sheetname "")
		)
		(fill
			(thermal_gap 0.5)
			(thermal_bridge_width 0.5)
			(island_removal_mode 0)
		)
		(polygon
			(pts
				(arc
					(start 220.840554 -278.183848)
					(mid 220.330141 -277.673054)
					(end 219.819474 -278.183594)
				)
				(arc
					(start 219.819474 -278.996394)
					(mid 220.330014 -279.506934)
					(end 220.840554 -278.996394)
				)
				(xy 220.840554 -278.842724) (xy 220.625162 -278.842724)
				(arc
					(start 220.575632 -278.892254)
					(mid 220.14137 -279.185038)
					(end 220.434154 -278.750776)
				)
				(xy 220.542358 -278.642572) (xy 220.840554 -278.642572) (xy 220.840554 -278.53767) (xy 220.542612 -278.53767)
				(arc
					(start 220.434154 -278.429212)
					(mid 220.14137 -277.99495)
					(end 220.575632 -278.287734)
				)
				(xy 220.625416 -278.337518) (xy 220.840554 -278.337518)
			)
		)
	)
	(zone
		(layer "F.Cu")
		(hatch none 0.5)
		(connect_pads
			(clearance 0)
		)
		(min_thickness 0.25)
		(keepout
			(tracks not_allowed)
			(vias allowed)
			(pads allowed)
			(copperpour not_allowed)
			(footprints allowed)
		)
		(placement
			(enabled no)
			(sheetname "")
		)
		(fill
			(thermal_gap 0.5)
			(thermal_bridge_width 0.5)
			(island_removal_mode 0)
		)
		(polygon
			(pts
				(arc
					(start 37.33927 -177.431446)
					(mid 36.727257 -176.819052)
					(end 36.11499 -177.431192)
				)
				(arc
					(start 36.11499 -178.548792)
					(mid 36.72713 -179.160932)
					(end 37.33927 -178.548792)
				)
				(xy 37.33927 -178.242722) (xy 37.174678 -178.242722)
				(arc
					(start 36.972748 -178.444652)
					(mid 36.538486 -178.737436)
					(end 36.83127 -178.303174)
				)
				(xy 37.091874 -178.04257) (xy 37.33927 -178.04257) (xy 37.33927 -177.937668) (xy 37.092128 -177.937668)
				(arc
					(start 36.83127 -177.67681)
					(mid 36.538486 -177.242548)
					(end 36.972748 -177.535332)
				)
				(xy 37.174932 -177.737516) (xy 37.33927 -177.737516)
			)
		)
	)
	(zone
		(layer "F.Cu")
		(hatch none 0.5)
		(connect_pads
			(clearance 0)
		)
		(min_thickness 0.25)
		(keepout
			(tracks not_allowed)
			(vias allowed)
			(pads allowed)
			(copperpour not_allowed)
			(footprints allowed)
		)
		(placement
			(enabled no)
			(sheetname "")
		)
		(fill
			(thermal_gap 0.5)
			(thermal_bridge_width 0.5)
			(island_removal_mode 0)
		)
		(polygon
			(pts
				(arc
					(start 7.502906 -356.335838)
					(mid 6.992366 -355.825298)
					(end 6.481826 -356.335838)
				)
				(xy 6.481826 -356.489508) (xy 6.697218 -356.489508)
				(arc
					(start 6.746748 -356.439978)
					(mid 7.18101 -356.147194)
					(end 6.888226 -356.581456)
				)
				(xy 6.780022 -356.68966) (xy 6.481826 -356.68966) (xy 6.481826 -356.794562) (xy 6.779768 -356.794562)
				(arc
					(start 6.888226 -356.90302)
					(mid 7.18101 -357.337282)
					(end 6.746748 -357.044498)
				)
				(xy 6.696964 -356.994714) (xy 6.481826 -356.994714)
				(arc
					(start 6.481826 -357.148384)
					(mid 6.992239 -357.659178)
					(end 7.502906 -357.148638)
				)
			)
		)
	)
	(zone
		(net "GND")
		(layer "F.Cu")
		(hatch none 0.5)
		(connect_pads
			(clearance 0.5)
		)
		(min_thickness 0.25)
		(fill yes
			(thermal_gap 0.5)
			(thermal_bridge_width 0.5)
			(island_removal_mode 0)
		)
		(polygon
			(pts
				(xy 15.153894 -96.1644) (xy 11.3538 -99.964494) (xy 11.3538 -163.858448) (xy 11.523726 -164.028374)
				(xy 13.160248 -164.028374) (xy 13.4112 -163.777422) (xy 13.4112 -100.9142) (xy 16.4846 -97.8408)
				(xy 16.4846 -96.6978) (xy 15.9512 -96.1644)
			)
		)
	)
	(zone
		(layer "F.Cu")
		(hatch none 0.5)
		(connect_pads
			(clearance 0)
		)
		(min_thickness 0.25)
		(keepout
			(tracks not_allowed)
			(vias allowed)
			(pads allowed)
			(copperpour not_allowed)
			(footprints allowed)
		)
		(placement
			(enabled no)
			(sheetname "")
		)
		(fill
			(thermal_gap 0.5)
			(thermal_bridge_width 0.5)
			(island_removal_mode 0)
		)
		(polygon
			(pts
				(arc
					(start 37.33927 -159.831532)
					(mid 36.727257 -159.219138)
					(end 36.11499 -159.831278)
				)
				(arc
					(start 36.11499 -160.948878)
					(mid 36.72713 -161.561018)
					(end 37.33927 -160.948878)
				)
				(xy 37.33927 -160.642554) (xy 37.174932 -160.642554)
				(arc
					(start 36.972748 -160.844738)
					(mid 36.538486 -161.137522)
					(end 36.83127 -160.70326)
				)
				(xy 37.092128 -160.442402) (xy 37.33927 -160.442402) (xy 37.33927 -160.3375) (xy 37.091874 -160.3375)
				(arc
					(start 36.83127 -160.076896)
					(mid 36.538486 -159.642634)
					(end 36.972748 -159.935418)
				)
				(xy 37.174678 -160.137348) (xy 37.33927 -160.137348)
			)
		)
	)
	(zone
		(layer "F.Cu")
		(hatch none 0.5)
		(connect_pads
			(clearance 0)
		)
		(min_thickness 0.25)
		(keepout
			(tracks not_allowed)
			(vias allowed)
			(pads allowed)
			(copperpour not_allowed)
			(footprints allowed)
		)
		(placement
			(enabled no)
			(sheetname "")
		)
		(fill
			(thermal_gap 0.5)
			(thermal_bridge_width 0.5)
			(island_removal_mode 0)
		)
		(polygon
			(pts
				(arc
					(start 7.502906 -178.386994)
					(mid 6.992493 -177.8762)
					(end 6.481826 -178.38674)
				)
				(xy 6.481826 -178.540156) (xy 6.697472 -178.540156)
				(arc
					(start 6.746748 -178.49088)
					(mid 7.18101 -178.198096)
					(end 6.888226 -178.632358)
				)
				(xy 6.780276 -178.740308) (xy 6.481826 -178.740308) (xy 6.481826 -178.84521) (xy 6.779514 -178.84521)
				(arc
					(start 6.888226 -178.953922)
					(mid 7.18101 -179.388184)
					(end 6.746748 -179.0954)
				)
				(xy 6.69671 -179.045362) (xy 6.481826 -179.045362)
				(arc
					(start 6.481826 -179.19954)
					(mid 6.992366 -179.71008)
					(end 7.502906 -179.19954)
				)
			)
		)
	)
	(zone
		(layer "F.Cu")
		(hatch none 0.5)
		(connect_pads
			(clearance 0)
		)
		(min_thickness 0.25)
		(keepout
			(tracks not_allowed)
			(vias allowed)
			(pads allowed)
			(copperpour not_allowed)
			(footprints allowed)
		)
		(placement
			(enabled no)
			(sheetname "")
		)
		(fill
			(thermal_gap 0.5)
			(thermal_bridge_width 0.5)
			(island_removal_mode 0)
		)
		(polygon
			(pts
				(arc
					(start 7.502906 -443.18428)
					(mid 6.992366 -442.67374)
					(end 6.481826 -443.18428)
				)
				(xy 6.481826 -443.33795) (xy 6.697218 -443.33795)
				(arc
					(start 6.746748 -443.28842)
					(mid 7.18101 -442.995636)
					(end 6.888226 -443.429898)
				)
				(xy 6.780022 -443.538102) (xy 6.481826 -443.538102) (xy 6.481826 -443.643004) (xy 6.779768 -443.643004)
				(arc
					(start 6.888226 -443.751462)
					(mid 7.18101 -444.185724)
					(end 6.746748 -443.89294)
				)
				(xy 6.696964 -443.843156) (xy 6.481826 -443.843156)
				(arc
					(start 6.481826 -443.996826)
					(mid 6.992239 -444.50762)
					(end 7.502906 -443.99708)
				)
			)
		)
	)
	(zone
		(layer "F.Cu")
		(hatch none 0.5)
		(connect_pads
			(clearance 0)
		)
		(min_thickness 0.25)
		(keepout
			(tracks not_allowed)
			(vias allowed)
			(pads allowed)
			(copperpour not_allowed)
			(footprints allowed)
		)
		(placement
			(enabled no)
			(sheetname "")
		)
		(fill
			(thermal_gap 0.5)
			(thermal_bridge_width 0.5)
			(island_removal_mode 0)
		)
		(polygon
			(pts
				(arc
					(start 25.88514 -18.451068)
					(mid 25.273 -17.838928)
					(end 24.66086 -18.451068)
				)
				(xy 24.66086 -18.757138) (xy 24.825452 -18.757138)
				(arc
					(start 25.027382 -18.555208)
					(mid 25.461644 -18.262424)
					(end 25.16886 -18.696686)
				)
				(xy 24.908256 -18.95729) (xy 24.66086 -18.95729) (xy 24.66086 -19.062192) (xy 24.908002 -19.062192)
				(arc
					(start 25.16886 -19.32305)
					(mid 25.461644 -19.757312)
					(end 25.027382 -19.464528)
				)
				(xy 24.825198 -19.262344) (xy 24.66086 -19.262344)
				(arc
					(start 24.66086 -19.568414)
					(mid 25.272873 -20.180808)
					(end 25.88514 -19.568668)
				)
			)
		)
	)
	(zone
		(net "P3V3_VIN")
		(layer "F.Cu")
		(hatch none 0.5)
		(connect_pads
			(clearance 0.5)
		)
		(min_thickness 0.25)
		(fill yes
			(thermal_gap 0.5)
			(thermal_bridge_width 0.5)
			(island_removal_mode 0)
		)
		(polygon
			(pts
				(xy 225.301302 -420.6621) (xy 225.044 -420.919402) (xy 225.044 -430.3776) (xy 225.5774 -430.911)
				(xy 225.5774 -432.8414) (xy 225.8822 -433.1462) (xy 226.7458 -433.1462) (xy 226.8474 -433.0446)
				(xy 226.8474 -426.9486) (xy 227.33 -426.466) (xy 227.33 -420.892732) (xy 227.099368 -420.6621)
			)
		)
		(polygon
			(pts
				(xy 226.2886 -431.4952) (xy 226.0854 -431.4952) (xy 226.0854 -431.6984) (xy 226.2886 -431.6984)
			)
		)
		(polygon
			(pts
				(xy 226.2886 -430.8856) (xy 226.0854 -430.8856) (xy 226.0854 -431.0888) (xy 226.2886 -431.0888)
			)
		)
	)
	(zone
		(layer "F.Cu")
		(hatch none 0.5)
		(connect_pads
			(clearance 0)
		)
		(min_thickness 0.25)
		(keepout
			(tracks allowed)
			(vias allowed)
			(pads allowed)
			(copperpour allowed)
			(footprints allowed)
		)
		(placement
			(enabled no)
			(sheetname "")
		)
		(fill
			(thermal_gap 0.5)
			(thermal_bridge_width 0.5)
			(island_removal_mode 0)
		)
		(polygon
			(pts
				(xy 17.78 -136.779) (xy 17.78 -134.493) (xy 19.939 -134.493) (xy 19.939 -136.779)
			)
		)
	)
	(zone
		(layer "F.Cu")
		(hatch none 0.5)
		(connect_pads
			(clearance 0)
		)
		(min_thickness 0.25)
		(keepout
			(tracks allowed)
			(vias allowed)
			(pads allowed)
			(copperpour allowed)
			(footprints allowed)
		)
		(placement
			(enabled no)
			(sheetname "")
		)
		(fill
			(thermal_gap 0.5)
			(thermal_bridge_width 0.5)
			(island_removal_mode 0)
		)
		(polygon
			(pts
				(xy 7.239 -186.69) (xy 1.905 -186.69) (xy 1.905 -151.638) (xy 7.239 -151.638)
			)
		)
	)
	(zone
		(layer "F.Cu")
		(hatch none 0.5)
		(connect_pads
			(clearance 0)
		)
		(min_thickness 0.25)
		(keepout
			(tracks not_allowed)
			(vias allowed)
			(pads allowed)
			(copperpour not_allowed)
			(footprints allowed)
		)
		(placement
			(enabled no)
			(sheetname "")
		)
		(fill
			(thermal_gap 0.5)
			(thermal_bridge_width 0.5)
			(island_removal_mode 0)
		)
		(polygon
			(pts
				(arc
					(start 222.339154 -79.23149)
					(mid 221.727141 -78.619096)
					(end 221.114874 -79.231236)
				)
				(arc
					(start 221.114874 -80.348836)
					(mid 221.727014 -80.960976)
					(end 222.339154 -80.348836)
				)
				(xy 222.339154 -80.042512) (xy 222.174816 -80.042512)
				(arc
					(start 221.972632 -80.244696)
					(mid 221.53837 -80.53748)
					(end 221.831154 -80.103218)
				)
				(xy 222.092012 -79.84236) (xy 222.339154 -79.84236) (xy 222.339154 -79.737458) (xy 222.091758 -79.737458)
				(arc
					(start 221.831154 -79.476854)
					(mid 221.53837 -79.042592)
					(end 221.972632 -79.335376)
				)
				(xy 222.174562 -79.537306) (xy 222.339154 -79.537306)
			)
		)
	)
	(zone
		(layer "F.Cu")
		(hatch none 0.5)
		(connect_pads
			(clearance 0)
		)
		(min_thickness 0.25)
		(keepout
			(tracks not_allowed)
			(vias allowed)
			(pads allowed)
			(copperpour not_allowed)
			(footprints allowed)
		)
		(placement
			(enabled no)
			(sheetname "")
		)
		(fill
			(thermal_gap 0.5)
			(thermal_bridge_width 0.5)
			(island_removal_mode 0)
		)
		(polygon
			(pts
				(arc
					(start 35.84067 -157.583886)
					(mid 35.330257 -157.073092)
					(end 34.81959 -157.583632)
				)
				(arc
					(start 34.81959 -158.396432)
					(mid 35.33013 -158.906972)
					(end 35.84067 -158.396432)
				)
				(xy 35.84067 -158.242762) (xy 35.625278 -158.242762)
				(arc
					(start 35.575748 -158.292292)
					(mid 35.141486 -158.585076)
					(end 35.43427 -158.150814)
				)
				(xy 35.542474 -158.04261) (xy 35.84067 -158.04261) (xy 35.84067 -157.937708) (xy 35.542728 -157.937708)
				(arc
					(start 35.43427 -157.82925)
					(mid 35.141486 -157.394988)
					(end 35.575748 -157.687772)
				)
				(xy 35.625532 -157.737556) (xy 35.84067 -157.737556)
			)
		)
	)
	(zone
		(layer "F.Cu")
		(hatch none 0.5)
		(connect_pads
			(clearance 0)
		)
		(min_thickness 0.25)
		(keepout
			(tracks not_allowed)
			(vias allowed)
			(pads allowed)
			(copperpour not_allowed)
			(footprints allowed)
		)
		(placement
			(enabled no)
			(sheetname "")
		)
		(fill
			(thermal_gap 0.5)
			(thermal_bridge_width 0.5)
			(island_removal_mode 0)
		)
		(polygon
			(pts
				(xy 1.022096 -465.795868) (xy 3.758184 -465.795868) (xy 3.81 -465.847684) (xy 3.81 -466.0392) (xy 3.761232 -466.087968)
				(xy 1.025398 -466.087968) (xy 1.014984 -466.098382) (xy 1.010158 -466.098382) (xy 1.005332 -466.093556)
				(xy 1.005332 -465.791042) (xy 1.007872 -465.788502) (xy 1.01473 -465.788502)
			)
		)
	)
	(zone
		(layer "F.Cu")
		(hatch none 0.5)
		(connect_pads
			(clearance 0)
		)
		(min_thickness 0.25)
		(keepout
			(tracks not_allowed)
			(vias allowed)
			(pads allowed)
			(copperpour not_allowed)
			(footprints allowed)
		)
		(placement
			(enabled no)
			(sheetname "")
		)
		(fill
			(thermal_gap 0.5)
			(thermal_bridge_width 0.5)
			(island_removal_mode 0)
		)
		(polygon
			(pts
				(arc
					(start 7.502906 -307.535834)
					(mid 6.992366 -307.025294)
					(end 6.481826 -307.535834)
				)
				(xy 6.481826 -307.68925) (xy 6.697472 -307.68925)
				(arc
					(start 6.746748 -307.639974)
					(mid 7.18101 -307.34719)
					(end 6.888226 -307.781452)
				)
				(xy 6.780276 -307.889402) (xy 6.481826 -307.889402) (xy 6.481826 -307.994304) (xy 6.779514 -307.994304)
				(arc
					(start 6.888226 -308.103016)
					(mid 7.18101 -308.537278)
					(end 6.746748 -308.244494)
				)
				(xy 6.69671 -308.194456) (xy 6.481826 -308.194456)
				(arc
					(start 6.481826 -308.34838)
					(mid 6.992239 -308.859174)
					(end 7.502906 -308.348634)
				)
			)
		)
	)
	(zone
		(net "GND")
		(layer "F.Cu")
		(hatch none 0.5)
		(connect_pads
			(clearance 0.5)
		)
		(min_thickness 0.25)
		(fill yes
			(thermal_gap 0.5)
			(thermal_bridge_width 0.5)
			(island_removal_mode 0)
		)
		(polygon
			(pts
				(xy 56.007 -34.798) (xy 53.594 -37.211) (xy 53.594 -53.594) (xy 54.991 -54.991) (xy 73.787 -54.991)
				(xy 90.932 -72.136) (xy 93.091 -72.136) (xy 93.98 -71.247) (xy 93.98 -68.072) (xy 60.706 -34.798)
			)
		)
	)
	(zone
		(layer "F.Cu")
		(hatch none 0.5)
		(connect_pads
			(clearance 0)
		)
		(min_thickness 0.25)
		(keepout
			(tracks allowed)
			(vias allowed)
			(pads allowed)
			(copperpour allowed)
			(footprints not_allowed)
		)
		(placement
			(enabled no)
			(sheetname "")
		)
		(fill
			(thermal_gap 0.5)
			(thermal_bridge_width 0.5)
			(island_removal_mode 0)
		)
		(polygon
			(pts
				(xy 36.049458 -42.66819) (xy 44.99991 -42.66819) (xy 44.99991 -10.668254) (xy 25.999948 -10.668254)
				(xy 25.999948 -51.32832) (xy 16.999966 -51.32832) (xy 16.999966 -67.168268) (xy 36.049458 -67.168268)
			)
		)
	)
	(zone
		(layer "F.Cu")
		(hatch none 0.5)
		(connect_pads
			(clearance 0)
		)
		(min_thickness 0.25)
		(keepout
			(tracks not_allowed)
			(vias allowed)
			(pads allowed)
			(copperpour not_allowed)
			(footprints allowed)
		)
		(placement
			(enabled no)
			(sheetname "")
		)
		(fill
			(thermal_gap 0.5)
			(thermal_bridge_width 0.5)
			(island_removal_mode 0)
		)
		(polygon
			(pts
				(arc
					(start 35.84067 -479.383852)
					(mid 35.33013 -478.873312)
					(end 34.81959 -479.383852)
				)
				(arc
					(start 34.81959 -480.196398)
					(mid 35.330003 -480.707192)
					(end 35.84067 -480.196652)
				)
				(xy 35.84067 -480.042728) (xy 35.625532 -480.042728)
				(arc
					(start 35.575748 -480.092512)
					(mid 35.141486 -480.385296)
					(end 35.43427 -479.951034)
				)
				(xy 35.542728 -479.842576) (xy 35.84067 -479.842576) (xy 35.84067 -479.737674) (xy 35.542474 -479.737674)
				(arc
					(start 35.43427 -479.62947)
					(mid 35.141486 -479.195208)
					(end 35.575748 -479.487992)
				)
				(xy 35.625278 -479.537522) (xy 35.84067 -479.537522)
			)
		)
	)
	(zone
		(layer "F.Cu")
		(hatch none 0.5)
		(connect_pads
			(clearance 0)
		)
		(min_thickness 0.25)
		(keepout
			(tracks not_allowed)
			(vias allowed)
			(pads allowed)
			(copperpour not_allowed)
			(footprints allowed)
		)
		(placement
			(enabled no)
			(sheetname "")
		)
		(fill
			(thermal_gap 0.5)
			(thermal_bridge_width 0.5)
			(island_removal_mode 0)
		)
		(polygon
			(pts
				(arc
					(start 25.88514 -23.25116)
					(mid 25.273 -22.63902)
					(end 24.66086 -23.25116)
				)
				(xy 24.66086 -23.55723) (xy 24.825452 -23.55723)
				(arc
					(start 25.027382 -23.3553)
					(mid 25.461644 -23.062516)
					(end 25.16886 -23.496778)
				)
				(xy 24.908256 -23.757382) (xy 24.66086 -23.757382) (xy 24.66086 -23.862284) (xy 24.908002 -23.862284)
				(arc
					(start 25.16886 -24.123142)
					(mid 25.461644 -24.557404)
					(end 25.027382 -24.26462)
				)
				(xy 24.825198 -24.062436) (xy 24.66086 -24.062436)
				(arc
					(start 24.66086 -24.368506)
					(mid 25.272873 -24.9809)
					(end 25.88514 -24.36876)
				)
			)
		)
	)
	(zone
		(layer "F.Cu")
		(hatch none 0.5)
		(connect_pads
			(clearance 0)
		)
		(min_thickness 0.25)
		(keepout
			(tracks allowed)
			(vias allowed)
			(pads allowed)
			(copperpour allowed)
			(footprints allowed)
		)
		(placement
			(enabled no)
			(sheetname "")
		)
		(fill
			(thermal_gap 0.5)
			(thermal_bridge_width 0.5)
			(island_removal_mode 0)
		)
		(polygon
			(pts
				(xy 100.584 -306.07) (xy 100.711 -306.197) (xy 102.489 -306.197) (xy 102.489 -311.912) (xy 101.219 -311.912)
				(xy 100.33 -311.023) (xy 100.33 -310.261) (xy 99.187 -309.118) (xy 98.044 -309.118) (xy 98.044 -304.292)
				(xy 100.584 -304.292)
			)
		)
	)
	(zone
		(layer "F.Cu")
		(hatch none 0.5)
		(connect_pads
			(clearance 0)
		)
		(min_thickness 0.25)
		(keepout
			(tracks not_allowed)
			(vias allowed)
			(pads allowed)
			(copperpour not_allowed)
			(footprints allowed)
		)
		(placement
			(enabled no)
			(sheetname "")
		)
		(fill
			(thermal_gap 0.5)
			(thermal_bridge_width 0.5)
			(island_removal_mode 0)
		)
		(polygon
			(pts
				(xy 97.81921 -433.21478) (xy 97.81921 -433.303426) (xy 97.819464 -433.30368) (xy 98.98761 -433.30368)
				(xy 98.98761 -433.21478)
			)
		)
	)
	(zone
		(net "GND")
		(layer "F.Cu")
		(hatch none 0.5)
		(connect_pads
			(clearance 0.5)
		)
		(min_thickness 0.25)
		(fill yes
			(thermal_gap 0.5)
			(thermal_bridge_width 0.5)
			(island_removal_mode 0)
		)
		(polygon
			(pts
				(xy 34.514536 -459.90256) (xy 32.3088 -462.108296) (xy 32.3088 -474.6244) (xy 30.790896 -476.142304)
				(xy 30.790896 -489.641896) (xy 31.1912 -490.0422) (xy 33.528 -490.0422) (xy 34.544 -489.0262) (xy 34.544 -464.566)
				(xy 35.814 -463.296) (xy 35.814 -460.756) (xy 34.96056 -459.90256)
			)
		)
	)
	(zone
		(net "P3V3")
		(layer "F.Cu")
		(hatch none 0.5)
		(connect_pads
			(clearance 0.5)
		)
		(min_thickness 0.25)
		(fill yes
			(thermal_gap 0.5)
			(thermal_bridge_width 0.5)
			(island_removal_mode 0)
		)
		(polygon
			(pts
				(xy 191.262 -420.37) (xy 189.611 -422.021) (xy 189.611 -429.768) (xy 198.628 -438.785) (xy 206.121 -438.785)
				(xy 206.248 -438.658) (xy 206.248 -429.26) (xy 197.358 -420.37)
			)
		)
	)
	(zone
		(layer "F.Cu")
		(hatch none 0.5)
		(connect_pads
			(clearance 0)
		)
		(min_thickness 0.25)
		(keepout
			(tracks not_allowed)
			(vias allowed)
			(pads allowed)
			(copperpour not_allowed)
			(footprints allowed)
		)
		(placement
			(enabled no)
			(sheetname "")
		)
		(fill
			(thermal_gap 0.5)
			(thermal_bridge_width 0.5)
			(island_removal_mode 0)
		)
		(polygon
			(pts
				(arc
					(start 27.18054 -347.603572)
					(mid 26.67 -347.093032)
					(end 26.15946 -347.603572)
				)
				(xy 26.15946 -347.757242) (xy 26.374852 -347.757242)
				(arc
					(start 26.424382 -347.707712)
					(mid 26.858644 -347.414928)
					(end 26.56586 -347.84919)
				)
				(xy 26.457656 -347.957394) (xy 26.15946 -347.957394) (xy 26.15946 -348.062296) (xy 26.457402 -348.062296)
				(arc
					(start 26.56586 -348.170754)
					(mid 26.858644 -348.605016)
					(end 26.424382 -348.312232)
				)
				(xy 26.374598 -348.262448) (xy 26.15946 -348.262448)
				(arc
					(start 26.15946 -348.416118)
					(mid 26.669873 -348.926912)
					(end 27.18054 -348.416372)
				)
			)
		)
	)
	(zone
		(layer "F.Cu")
		(hatch none 0.5)
		(connect_pads
			(clearance 0)
		)
		(min_thickness 0.25)
		(keepout
			(tracks not_allowed)
			(vias allowed)
			(pads allowed)
			(copperpour not_allowed)
			(footprints allowed)
		)
		(placement
			(enabled no)
			(sheetname "")
		)
		(fill
			(thermal_gap 0.5)
			(thermal_bridge_width 0.5)
			(island_removal_mode 0)
		)
		(polygon
			(pts
				(xy 97.81921 -435.21503) (xy 97.81921 -435.303676) (xy 97.819464 -435.30393) (xy 98.98761 -435.30393)
				(xy 98.98761 -435.21503)
			)
		)
	)
	(zone
		(layer "F.Cu")
		(hatch none 0.5)
		(connect_pads
			(clearance 0)
		)
		(min_thickness 0.25)
		(keepout
			(tracks not_allowed)
			(vias allowed)
			(pads allowed)
			(copperpour not_allowed)
			(footprints allowed)
		)
		(placement
			(enabled no)
			(sheetname "")
		)
		(fill
			(thermal_gap 0.5)
			(thermal_bridge_width 0.5)
			(island_removal_mode 0)
		)
		(polygon
			(pts
				(xy 97.81921 -210.23453) (xy 97.81921 -210.323176) (xy 97.819464 -210.32343) (xy 98.98761 -210.32343)
				(xy 98.98761 -210.23453)
			)
		)
	)
	(zone
		(layer "F.Cu")
		(hatch none 0.5)
		(connect_pads
			(clearance 0)
		)
		(min_thickness 0.25)
		(keepout
			(tracks allowed)
			(vias allowed)
			(pads allowed)
			(copperpour allowed)
			(footprints allowed)
		)
		(placement
			(enabled no)
			(sheetname "")
		)
		(fill
			(thermal_gap 0.5)
			(thermal_bridge_width 0.5)
			(island_removal_mode 0)
		)
		(polygon
			(pts
				(xy 77.089 -304.2158) (xy 77.089 -302.7172) (xy 78.0034 -302.7172) (xy 78.0034 -304.2158)
			)
		)
	)
	(zone
		(net "GND")
		(layer "F.Cu")
		(hatch none 0.5)
		(connect_pads
			(clearance 0.5)
		)
		(min_thickness 0.25)
		(fill yes
			(thermal_gap 0.5)
			(thermal_bridge_width 0.5)
			(island_removal_mode 0)
		)
		(polygon
			(pts
				(xy 34.2392 -400.7358) (xy 34.036 -400.939) (xy 34.036 -402.717) (xy 34.671 -403.352) (xy 37.719 -403.352)
				(xy 38.1254 -402.9456) (xy 38.1254 -401.0152) (xy 37.846 -400.7358)
			)
		)
		(polygon
			(pts
				(xy 35.2552 -401.5994) (xy 35.052 -401.5994) (xy 35.052 -401.8026) (xy 35.2552 -401.8026)
			)
		)
		(polygon
			(pts
				(xy 34.3916 -401.5994) (xy 34.1884 -401.5994) (xy 34.1884 -401.8026) (xy 34.3916 -401.8026)
			)
		)
	)
	(zone
		(layer "F.Cu")
		(hatch none 0.5)
		(connect_pads
			(clearance 0)
		)
		(min_thickness 0.25)
		(keepout
			(tracks not_allowed)
			(vias allowed)
			(pads allowed)
			(copperpour not_allowed)
			(footprints allowed)
		)
		(placement
			(enabled no)
			(sheetname "")
		)
		(fill
			(thermal_gap 0.5)
			(thermal_bridge_width 0.5)
			(island_removal_mode 0)
		)
		(polygon
			(pts
				(arc
					(start 222.339154 -159.831532)
					(mid 221.727141 -159.219138)
					(end 221.114874 -159.831278)
				)
				(arc
					(start 221.114874 -160.948878)
					(mid 221.727014 -161.561018)
					(end 222.339154 -160.948878)
				)
				(xy 222.339154 -160.642554) (xy 222.174816 -160.642554)
				(arc
					(start 221.972632 -160.844738)
					(mid 221.53837 -161.137522)
					(end 221.831154 -160.70326)
				)
				(xy 222.092012 -160.442402) (xy 222.339154 -160.442402) (xy 222.339154 -160.3375) (xy 222.091758 -160.3375)
				(arc
					(start 221.831154 -160.076896)
					(mid 221.53837 -159.642634)
					(end 221.972632 -159.935418)
				)
				(xy 222.174562 -160.137348) (xy 222.339154 -160.137348)
			)
		)
	)
	(zone
		(net "P12V")
		(layer "F.Cu")
		(hatch none 0.5)
		(connect_pads
			(clearance 0.5)
		)
		(min_thickness 0.25)
		(fill yes
			(thermal_gap 0.5)
			(thermal_bridge_width 0.5)
			(island_removal_mode 0)
		)
		(polygon
			(pts
				(xy 32.766 -411.861) (xy 32.5628 -412.0642) (xy 32.5628 -412.2674) (xy 31.9532 -412.877) (xy 31.9532 -417.3982)
				(xy 32.6644 -418.1094) (xy 36.0426 -418.1094) (xy 36.6522 -418.719) (xy 38.354 -418.719) (xy 38.4556 -418.6174)
				(xy 38.4556 -418.1094) (xy 38.3286 -417.9824) (xy 37.6936 -417.9824) (xy 37.4142 -417.703) (xy 37.4142 -416.941)
				(xy 37.0586 -416.5854) (xy 37.0586 -415.2138) (xy 35.1282 -413.2834) (xy 35.1282 -412.877) (xy 34.3916 -412.1404)
				(xy 33.9852 -412.1404) (xy 33.7058 -411.861)
			)
		)
		(polygon
			(pts
				(xy 37.465 -418.0078) (xy 37.2618 -418.0078) (xy 37.2618 -418.211) (xy 37.465 -418.211)
			)
		)
		(polygon
			(pts
				(xy 36.8554 -418.0078) (xy 36.6522 -418.0078) (xy 36.6522 -418.211) (xy 36.8554 -418.211)
			)
		)
		(polygon
			(pts
				(xy 36.957 -417.5252) (xy 36.7538 -417.5252) (xy 36.7538 -417.7284) (xy 36.957 -417.7284)
			)
		)
		(polygon
			(pts
				(xy 36.957 -416.9664) (xy 36.7538 -416.9664) (xy 36.7538 -417.1696) (xy 36.957 -417.1696)
			)
		)
		(polygon
			(pts
				(xy 33.4899 -412.3055) (xy 33.2867 -412.3055) (xy 33.2867 -412.5087) (xy 33.4899 -412.5087)
			)
		)
		(polygon
			(pts
				(xy 32.9311 -412.3055) (xy 32.7279 -412.3055) (xy 32.7279 -412.5087) (xy 32.9311 -412.5087)
			)
		)
	)
	(zone
		(layer "F.Cu")
		(hatch none 0.5)
		(connect_pads
			(clearance 0)
		)
		(min_thickness 0.25)
		(keepout
			(tracks allowed)
			(vias allowed)
			(pads allowed)
			(copperpour allowed)
			(footprints allowed)
		)
		(placement
			(enabled no)
			(sheetname "")
		)
		(fill
			(thermal_gap 0.5)
			(thermal_bridge_width 0.5)
			(island_removal_mode 0)
		)
		(polygon
			(pts
				(xy 24.638 -138.049) (xy 24.638 -145.161) (xy 22.479 -145.161) (xy 22.479 -138.049)
			)
		)
	)
	(zone
		(layer "F.Cu")
		(hatch none 0.5)
		(connect_pads
			(clearance 0)
		)
		(min_thickness 0.25)
		(keepout
			(tracks allowed)
			(vias allowed)
			(pads allowed)
			(copperpour allowed)
			(footprints allowed)
		)
		(placement
			(enabled no)
			(sheetname "")
		)
		(fill
			(thermal_gap 0.5)
			(thermal_bridge_width 0.5)
			(island_removal_mode 0)
		)
		(polygon
			(pts
				(xy 7.239 -360.68) (xy 1.905 -360.68) (xy 1.905 -315.976) (xy 7.239 -315.976)
			)
		)
	)
	(zone
		(net "GND")
		(layer "F.Cu")
		(hatch none 0.5)
		(connect_pads
			(clearance 0.5)
		)
		(min_thickness 0.25)
		(fill yes
			(thermal_gap 0.5)
			(thermal_bridge_width 0.5)
			(island_removal_mode 0)
		)
		(polygon
			(pts
				(xy 218.2622 -290.195) (xy 217.9574 -290.4998) (xy 217.9574 -291.5666) (xy 218.2114 -291.8206) (xy 222.4024 -291.8206)
				(xy 222.5802 -291.6428) (xy 222.5802 -290.322) (xy 222.4532 -290.195)
			)
		)
		(polygon
			(pts
				(xy 222.4278 -291.1094) (xy 222.2246 -291.1094) (xy 222.2246 -291.3126) (xy 222.4278 -291.3126)
			)
		)
		(polygon
			(pts
				(xy 221.8182 -291.1094) (xy 221.615 -291.1094) (xy 221.615 -291.3126) (xy 221.8182 -291.3126)
			)
		)
	)
	(zone
		(layer "F.Cu")
		(hatch none 0.5)
		(connect_pads
			(clearance 0)
		)
		(min_thickness 0.25)
		(keepout
			(tracks not_allowed)
			(vias allowed)
			(pads allowed)
			(copperpour not_allowed)
			(footprints allowed)
		)
		(placement
			(enabled no)
			(sheetname "")
		)
		(fill
			(thermal_gap 0.5)
			(thermal_bridge_width 0.5)
			(island_removal_mode 0)
		)
		(polygon
			(pts
				(arc
					(start 33.40354 -341.584788)
					(mid 32.893127 -341.073994)
					(end 32.38246 -341.584534)
				)
				(arc
					(start 32.38246 -342.397334)
					(mid 32.893 -342.907874)
					(end 33.40354 -342.397334)
				)
				(xy 33.40354 -342.243156) (xy 33.188656 -342.243156)
				(arc
					(start 33.138618 -342.293194)
					(mid 32.704356 -342.585978)
					(end 32.99714 -342.151716)
				)
				(xy 33.105852 -342.043004) (xy 33.40354 -342.043004) (xy 33.40354 -341.938102) (xy 33.10509 -341.938102)
				(arc
					(start 32.99714 -341.830152)
					(mid 32.704356 -341.39589)
					(end 33.138618 -341.688674)
				)
				(xy 33.187894 -341.73795) (xy 33.40354 -341.73795)
			)
		)
	)
	(zone
		(layer "F.Cu")
		(hatch none 0.5)
		(connect_pads
			(clearance 0)
		)
		(min_thickness 0.25)
		(keepout
			(tracks not_allowed)
			(vias allowed)
			(pads allowed)
			(copperpour not_allowed)
			(footprints allowed)
		)
		(placement
			(enabled no)
			(sheetname "")
		)
		(fill
			(thermal_gap 0.5)
			(thermal_bridge_width 0.5)
			(island_removal_mode 0)
		)
		(polygon
			(pts
				(arc
					(start 220.840554 -273.38401)
					(mid 220.330141 -272.873216)
					(end 219.819474 -273.383756)
				)
				(arc
					(start 219.819474 -274.196556)
					(mid 220.330014 -274.707096)
					(end 220.840554 -274.196556)
				)
				(xy 220.840554 -274.042632) (xy 220.625416 -274.042632)
				(arc
					(start 220.575632 -274.092416)
					(mid 220.14137 -274.3852)
					(end 220.434154 -273.950938)
				)
				(xy 220.542612 -273.84248) (xy 220.840554 -273.84248) (xy 220.840554 -273.737578) (xy 220.542358 -273.737578)
				(arc
					(start 220.434154 -273.629374)
					(mid 220.14137 -273.195112)
					(end 220.575632 -273.487896)
				)
				(xy 220.625162 -273.537426) (xy 220.840554 -273.537426)
			)
		)
	)
	(zone
		(layer "F.Cu")
		(hatch none 0.5)
		(connect_pads
			(clearance 0)
		)
		(min_thickness 0.25)
		(keepout
			(tracks allowed)
			(vias allowed)
			(pads allowed)
			(copperpour allowed)
			(footprints allowed)
		)
		(placement
			(enabled no)
			(sheetname "")
		)
		(fill
			(thermal_gap 0.5)
			(thermal_bridge_width 0.5)
			(island_removal_mode 0)
		)
		(polygon
			(pts
				(xy 17.78 -33.782) (xy 17.78 -31.496) (xy 19.939 -31.496) (xy 19.939 -33.782)
			)
		)
	)
	(zone
		(layer "F.Cu")
		(hatch none 0.5)
		(connect_pads
			(clearance 0)
		)
		(min_thickness 0.25)
		(keepout
			(tracks allowed)
			(vias allowed)
			(pads allowed)
			(copperpour allowed)
			(footprints allowed)
		)
		(placement
			(enabled no)
			(sheetname "")
		)
		(fill
			(thermal_gap 0.5)
			(thermal_bridge_width 0.5)
			(island_removal_mode 0)
		)
		(polygon
			(pts
				(xy 77.851 -151.765) (xy 74.803 -151.765) (xy 74.803 -150.114) (xy 77.851 -150.114)
			)
		)
	)
	(zone
		(layer "F.Cu")
		(hatch none 0.5)
		(connect_pads
			(clearance 0)
		)
		(min_thickness 0.25)
		(keepout
			(tracks not_allowed)
			(vias allowed)
			(pads allowed)
			(copperpour not_allowed)
			(footprints allowed)
		)
		(placement
			(enabled no)
			(sheetname "")
		)
		(fill
			(thermal_gap 0.5)
			(thermal_bridge_width 0.5)
			(island_removal_mode 0)
		)
		(polygon
			(pts
				(arc
					(start 37.33927 -486.43159)
					(mid 36.727257 -485.819196)
					(end 36.11499 -486.431336)
				)
				(arc
					(start 36.11499 -487.548936)
					(mid 36.72713 -488.161076)
					(end 37.33927 -487.548936)
				)
				(xy 37.33927 -487.242866) (xy 37.174678 -487.242866)
				(arc
					(start 36.972748 -487.444796)
					(mid 36.538486 -487.73758)
					(end 36.83127 -487.303318)
				)
				(xy 37.091874 -487.042714) (xy 37.33927 -487.042714) (xy 37.33927 -486.937812) (xy 37.092128 -486.937812)
				(arc
					(start 36.83127 -486.676954)
					(mid 36.538486 -486.242692)
					(end 36.972748 -486.535476)
				)
				(xy 37.174932 -486.73766) (xy 37.33927 -486.73766)
			)
		)
	)
	(zone
		(layer "F.Cu")
		(hatch none 0.5)
		(connect_pads
			(clearance 0)
		)
		(min_thickness 0.25)
		(keepout
			(tracks not_allowed)
			(vias allowed)
			(pads allowed)
			(copperpour not_allowed)
			(footprints allowed)
		)
		(placement
			(enabled no)
			(sheetname "")
		)
		(fill
			(thermal_gap 0.5)
			(thermal_bridge_width 0.5)
			(island_removal_mode 0)
		)
		(polygon
			(pts
				(arc
					(start 37.33927 -365.831628)
					(mid 36.727257 -365.219234)
					(end 36.11499 -365.831374)
				)
				(arc
					(start 36.11499 -366.948974)
					(mid 36.72713 -367.561114)
					(end 37.33927 -366.948974)
				)
				(xy 37.33927 -366.64265) (xy 37.174932 -366.64265)
				(arc
					(start 36.972748 -366.844834)
					(mid 36.538486 -367.137618)
					(end 36.83127 -366.703356)
				)
				(xy 37.092128 -366.442498) (xy 37.33927 -366.442498) (xy 37.33927 -366.337596) (xy 37.091874 -366.337596)
				(arc
					(start 36.83127 -366.076992)
					(mid 36.538486 -365.64273)
					(end 36.972748 -365.935514)
				)
				(xy 37.174678 -366.137444) (xy 37.33927 -366.137444)
			)
		)
	)
	(zone
		(layer "F.Cu")
		(hatch none 0.5)
		(connect_pads
			(clearance 0)
		)
		(min_thickness 0.25)
		(keepout
			(tracks not_allowed)
			(vias allowed)
			(pads allowed)
			(copperpour not_allowed)
			(footprints allowed)
		)
		(placement
			(enabled no)
			(sheetname "")
		)
		(fill
			(thermal_gap 0.5)
			(thermal_bridge_width 0.5)
			(island_removal_mode 0)
		)
		(polygon
			(pts
				(xy 1.022096 -462.595722) (xy 3.758184 -462.595722) (xy 3.81 -462.647538) (xy 3.81 -462.839054)
				(xy 3.761232 -462.887822) (xy 1.025398 -462.887822) (xy 1.014984 -462.898236) (xy 1.010158 -462.898236)
				(xy 1.005332 -462.89341) (xy 1.005332 -462.590896) (xy 1.007872 -462.588356) (xy 1.01473 -462.588356)
			)
		)
	)
	(zone
		(layer "F.Cu")
		(hatch none 0.5)
		(connect_pads
			(clearance 0)
		)
		(min_thickness 0.25)
		(keepout
			(tracks not_allowed)
			(vias allowed)
			(pads allowed)
			(copperpour not_allowed)
			(footprints allowed)
		)
		(placement
			(enabled no)
			(sheetname "")
		)
		(fill
			(thermal_gap 0.5)
			(thermal_bridge_width 0.5)
			(island_removal_mode 0)
		)
		(polygon
			(pts
				(arc
					(start 35.84067 -385.983988)
					(mid 35.330257 -385.473194)
					(end 34.81959 -385.983734)
				)
				(arc
					(start 34.81959 -386.796534)
					(mid 35.33013 -387.307074)
					(end 35.84067 -386.796534)
				)
				(xy 35.84067 -386.642864) (xy 35.625278 -386.642864)
				(arc
					(start 35.575748 -386.692394)
					(mid 35.141486 -386.985178)
					(end 35.43427 -386.550916)
				)
				(xy 35.542474 -386.442712) (xy 35.84067 -386.442712) (xy 35.84067 -386.33781) (xy 35.542728 -386.33781)
				(arc
					(start 35.43427 -386.229352)
					(mid 35.141486 -385.79509)
					(end 35.575748 -386.087874)
				)
				(xy 35.625532 -386.137658) (xy 35.84067 -386.137658)
			)
		)
	)
	(zone
		(net "P12V")
		(layer "F.Cu")
		(hatch none 0.5)
		(connect_pads
			(clearance 0.5)
		)
		(min_thickness 0.25)
		(fill yes
			(thermal_gap 0.5)
			(thermal_bridge_width 0.5)
			(island_removal_mode 0)
		)
		(polygon
			(pts
				(xy 23.9522 -190.2714) (xy 23.9268 -190.2968) (xy 23.9268 -190.8048) (xy 24.1808 -191.0588) (xy 24.8158 -191.0588)
				(xy 24.9682 -191.2112) (xy 24.9682 -191.9732) (xy 25.3238 -192.3288) (xy 25.3238 -193.7258) (xy 26.0858 -194.4878)
				(xy 26.0858 -194.7926) (xy 26.8224 -195.5292) (xy 26.8224 -196.1642) (xy 28.0162 -197.358) (xy 29.1084 -197.358)
				(xy 29.19984 -197.26656) (xy 29.19984 -196.93636) (xy 30.0228 -196.1134) (xy 30.0228 -191.0588)
				(xy 29.7688 -190.8048) (xy 26.2636 -190.8048) (xy 25.7302 -190.2714)
			)
		)
		(polygon
			(pts
				(xy 28.6893 -196.7103) (xy 28.4861 -196.7103) (xy 28.4861 -196.9135) (xy 28.6893 -196.9135)
			)
		)
		(polygon
			(pts
				(xy 25.6286 -191.8208) (xy 25.4254 -191.8208) (xy 25.4254 -192.024) (xy 25.6286 -192.024)
			)
		)
		(polygon
			(pts
				(xy 25.6286 -191.262) (xy 25.4254 -191.262) (xy 25.4254 -191.4652) (xy 25.6286 -191.4652)
			)
		)
		(polygon
			(pts
				(xy 25.7302 -190.7794) (xy 25.527 -190.7794) (xy 25.527 -190.9826) (xy 25.7302 -190.9826)
			)
		)
		(polygon
			(pts
				(xy 25.1206 -190.7794) (xy 24.9174 -190.7794) (xy 24.9174 -190.9826) (xy 25.1206 -190.9826)
			)
		)
		(polygon
			(pts
				(xy 24.6888 -190.7286) (xy 24.4856 -190.7286) (xy 24.4856 -190.9318) (xy 24.6888 -190.9318)
			)
		)
	)
	(zone
		(layer "F.Cu")
		(hatch none 0.5)
		(connect_pads
			(clearance 0)
		)
		(min_thickness 0.25)
		(keepout
			(tracks not_allowed)
			(vias allowed)
			(pads allowed)
			(copperpour not_allowed)
			(footprints allowed)
		)
		(placement
			(enabled no)
			(sheetname "")
		)
		(fill
			(thermal_gap 0.5)
			(thermal_bridge_width 0.5)
			(island_removal_mode 0)
		)
		(polygon
			(pts
				(arc
					(start 37.33927 -388.231634)
					(mid 36.727257 -387.61924)
					(end 36.11499 -388.23138)
				)
				(arc
					(start 36.11499 -389.34898)
					(mid 36.72713 -389.96112)
					(end 37.33927 -389.34898)
				)
				(xy 37.33927 -389.042656) (xy 37.174932 -389.042656)
				(arc
					(start 36.972748 -389.24484)
					(mid 36.538486 -389.537624)
					(end 36.83127 -389.103362)
				)
				(xy 37.092128 -388.842504) (xy 37.33927 -388.842504) (xy 37.33927 -388.737602) (xy 37.091874 -388.737602)
				(arc
					(start 36.83127 -388.476998)
					(mid 36.538486 -388.042736)
					(end 36.972748 -388.33552)
				)
				(xy 37.174678 -388.53745) (xy 37.33927 -388.53745)
			)
		)
	)
	(zone
		(layer "F.Cu")
		(hatch none 0.5)
		(connect_pads
			(clearance 0)
		)
		(min_thickness 0.25)
		(keepout
			(tracks not_allowed)
			(vias allowed)
			(pads allowed)
			(copperpour not_allowed)
			(footprints allowed)
		)
		(placement
			(enabled no)
			(sheetname "")
		)
		(fill
			(thermal_gap 0.5)
			(thermal_bridge_width 0.5)
			(island_removal_mode 0)
		)
		(polygon
			(pts
				(arc
					(start 220.840554 -179.983892)
					(mid 220.330141 -179.473098)
					(end 219.819474 -179.983638)
				)
				(arc
					(start 219.819474 -180.796438)
					(mid 220.330014 -181.306978)
					(end 220.840554 -180.796438)
				)
				(xy 220.840554 -180.642768) (xy 220.625162 -180.642768)
				(arc
					(start 220.575632 -180.692298)
					(mid 220.14137 -180.985082)
					(end 220.434154 -180.55082)
				)
				(xy 220.542358 -180.442616) (xy 220.840554 -180.442616) (xy 220.840554 -180.337714) (xy 220.542612 -180.337714)
				(arc
					(start 220.434154 -180.229256)
					(mid 220.14137 -179.794994)
					(end 220.575632 -180.087778)
				)
				(xy 220.625416 -180.137562) (xy 220.840554 -180.137562)
			)
		)
	)
	(zone
		(layer "F.Cu")
		(hatch none 0.5)
		(connect_pads
			(clearance 0)
		)
		(min_thickness 0.25)
		(keepout
			(tracks not_allowed)
			(vias allowed)
			(pads allowed)
			(copperpour not_allowed)
			(footprints allowed)
		)
		(placement
			(enabled no)
			(sheetname "")
		)
		(fill
			(thermal_gap 0.5)
			(thermal_bridge_width 0.5)
			(island_removal_mode 0)
		)
		(polygon
			(pts
				(arc
					(start 220.840554 -385.983988)
					(mid 220.330141 -385.473194)
					(end 219.819474 -385.983734)
				)
				(arc
					(start 219.819474 -386.796534)
					(mid 220.330014 -387.307074)
					(end 220.840554 -386.796534)
				)
				(xy 220.840554 -386.642864) (xy 220.625162 -386.642864)
				(arc
					(start 220.575632 -386.692394)
					(mid 220.14137 -386.985178)
					(end 220.434154 -386.550916)
				)
				(xy 220.542358 -386.442712) (xy 220.840554 -386.442712) (xy 220.840554 -386.33781) (xy 220.542612 -386.33781)
				(arc
					(start 220.434154 -386.229352)
					(mid 220.14137 -385.79509)
					(end 220.575632 -386.087874)
				)
				(xy 220.625416 -386.137658) (xy 220.840554 -386.137658)
			)
		)
	)
	(zone
		(net "P12V")
		(layer "F.Cu")
		(hatch none 0.5)
		(connect_pads
			(clearance 0.5)
		)
		(min_thickness 0.25)
		(fill yes
			(thermal_gap 0.5)
			(thermal_bridge_width 0.5)
			(island_removal_mode 0)
		)
		(polygon
			(pts
				(xy 32.7406 -308.61) (xy 32.4993 -308.8513) (xy 32.4993 -309.3593) (xy 31.9024 -309.9562) (xy 31.9024 -314.7568)
				(xy 32.3596 -315.214) (xy 35.7886 -315.214) (xy 36.2966 -315.722) (xy 38.0746 -315.722) (xy 38.2016 -315.595)
				(xy 38.2016 -315.214) (xy 37.9476 -314.96) (xy 37.3126 -314.96) (xy 37.1094 -314.7568) (xy 37.1094 -313.9948)
				(xy 36.8046 -313.69) (xy 36.8046 -312.293) (xy 35.1536 -310.642) (xy 35.1536 -309.8546) (xy 33.909 -308.61)
			)
		)
		(polygon
			(pts
				(xy 37.1602 -315.0108) (xy 36.957 -315.0108) (xy 36.957 -315.214) (xy 37.1602 -315.214)
			)
		)
		(polygon
			(pts
				(xy 36.5506 -315.0108) (xy 36.3474 -315.0108) (xy 36.3474 -315.214) (xy 36.5506 -315.214)
			)
		)
		(polygon
			(pts
				(xy 36.6522 -314.5282) (xy 36.449 -314.5282) (xy 36.449 -314.7314) (xy 36.6522 -314.7314)
			)
		)
		(polygon
			(pts
				(xy 36.6522 -313.9694) (xy 36.449 -313.9694) (xy 36.449 -314.1726) (xy 36.6522 -314.1726)
			)
		)
		(polygon
			(pts
				(xy 33.4899 -309.0545) (xy 33.2867 -309.0545) (xy 33.2867 -309.2577) (xy 33.4899 -309.2577)
			)
		)
		(polygon
			(pts
				(xy 32.9311 -309.0545) (xy 32.7279 -309.0545) (xy 32.7279 -309.2577) (xy 32.9311 -309.2577)
			)
		)
	)
	(zone
		(net "GND")
		(layer "F.Cu")
		(hatch none 0.5)
		(connect_pads
			(clearance 0.5)
		)
		(min_thickness 0.25)
		(fill yes
			(thermal_gap 0.5)
			(thermal_bridge_width 0.5)
			(island_removal_mode 0)
		)
		(polygon
			(pts
				(xy 51.562 -62.103) (xy 48.514 -65.151) (xy 48.514 -73.707498) (xy 45.360336 -76.861162) (xy 45.360336 -79.781908)
				(xy 47.726346 -82.147918) (xy 47.726346 -93.981778) (xy 48.112934 -94.368366) (xy 63.956184 -94.368366)
				(xy 65.751202 -96.163384) (xy 74.641964 -96.163384) (xy 75.533504 -97.054924) (xy 75.533504 -99.866704)
				(xy 75.79741 -100.13061) (xy 77.77099 -100.13061) (xy 77.9018 -99.9998) (xy 77.9018 -99.3394) (xy 78.0288 -99.2124)
				(xy 79.925418 -99.2124) (xy 80.255618 -98.8822) (xy 80.255618 -97.605342) (xy 82.81162 -95.04934)
				(xy 84.200238 -95.04934) (xy 84.293202 -94.956376) (xy 84.293202 -94.032578) (xy 85.107272 -93.218508)
				(xy 85.107272 -73.550272) (xy 73.66 -62.103)
			)
		)
		(polygon
			(pts
				(xy 77.3176 -99.4664) (xy 77.1144 -99.4664) (xy 77.1144 -99.6696) (xy 77.3176 -99.6696)
			)
		)
		(polygon
			(pts
				(xy 83.8454 -94.361) (xy 83.6422 -94.361) (xy 83.6422 -94.5642) (xy 83.8454 -94.5642)
			)
		)
	)
	(zone
		(layer "F.Cu")
		(hatch none 0.5)
		(connect_pads
			(clearance 0)
		)
		(min_thickness 0.25)
		(keepout
			(tracks allowed)
			(vias allowed)
			(pads allowed)
			(copperpour allowed)
			(footprints allowed)
		)
		(placement
			(enabled no)
			(sheetname "")
		)
		(fill
			(thermal_gap 0.5)
			(thermal_bridge_width 0.5)
			(island_removal_mode 0)
		)
		(polygon
			(pts
				(xy 37.338 -161.925) (xy 37.338 -154.813) (xy 39.497 -154.813) (xy 39.497 -161.925)
			)
		)
	)
	(zone
		(net "P3V3_OUT")
		(layer "F.Cu")
		(hatch none 0.5)
		(connect_pads
			(clearance 0.5)
		)
		(min_thickness 0.25)
		(fill yes
			(thermal_gap 0.5)
			(thermal_bridge_width 0.5)
			(island_removal_mode 0)
		)
		(polygon
			(pts
				(xy 213.4616 -432.1048) (xy 213.4108 -432.1556) (xy 213.4108 -432.736752) (xy 213.077552 -433.07)
				(xy 207.997552 -433.07) (xy 207.489552 -433.578) (xy 207.489552 -438.756552) (xy 207.645 -438.912)
				(xy 209.296 -438.912) (xy 209.423 -439.039) (xy 209.423 -439.293) (xy 209.55 -439.42) (xy 215.9 -439.42)
				(xy 216.535 -438.785) (xy 216.535 -433.959) (xy 214.6808 -432.1048)
			)
		)
		(polygon
			(pts
				(xy 214.1474 -432.5874) (xy 213.9442 -432.5874) (xy 213.9442 -432.7906) (xy 214.1474 -432.7906)
			)
		)
	)
	(zone
		(layer "F.Cu")
		(hatch none 0.5)
		(connect_pads
			(clearance 0)
		)
		(min_thickness 0.25)
		(keepout
			(tracks allowed)
			(vias allowed)
			(pads allowed)
			(copperpour allowed)
			(footprints allowed)
		)
		(placement
			(enabled no)
			(sheetname "")
		)
		(fill
			(thermal_gap 0.5)
			(thermal_bridge_width 0.5)
			(island_removal_mode 0)
		)
		(polygon
			(pts
				(xy 24.638 -447.04) (xy 24.638 -454.152) (xy 22.479 -454.152) (xy 22.479 -447.04)
			)
		)
	)
	(zone
		(layer "F.Cu")
		(hatch none 0.5)
		(connect_pads
			(clearance 0)
		)
		(min_thickness 0.25)
		(keepout
			(tracks not_allowed)
			(vias allowed)
			(pads allowed)
			(copperpour not_allowed)
			(footprints allowed)
		)
		(placement
			(enabled no)
			(sheetname "")
		)
		(fill
			(thermal_gap 0.5)
			(thermal_bridge_width 0.5)
			(island_removal_mode 0)
		)
		(polygon
			(pts
				(arc
					(start 37.33927 -280.431494)
					(mid 36.727257 -279.8191)
					(end 36.11499 -280.43124)
				)
				(arc
					(start 36.11499 -281.54884)
					(mid 36.72713 -282.16098)
					(end 37.33927 -281.54884)
				)
				(xy 37.33927 -281.24277) (xy 37.174678 -281.24277)
				(arc
					(start 36.972748 -281.4447)
					(mid 36.538486 -281.737484)
					(end 36.83127 -281.303222)
				)
				(xy 37.091874 -281.042618) (xy 37.33927 -281.042618) (xy 37.33927 -280.937716) (xy 37.092128 -280.937716)
				(arc
					(start 36.83127 -280.676858)
					(mid 36.538486 -280.242596)
					(end 36.972748 -280.53538)
				)
				(xy 37.174932 -280.737564) (xy 37.33927 -280.737564)
			)
		)
	)
	(zone
		(layer "F.Cu")
		(hatch none 0.5)
		(connect_pads
			(clearance 0)
		)
		(min_thickness 0.25)
		(keepout
			(tracks not_allowed)
			(vias allowed)
			(pads allowed)
			(copperpour not_allowed)
			(footprints allowed)
		)
		(placement
			(enabled no)
			(sheetname "")
		)
		(fill
			(thermal_gap 0.5)
			(thermal_bridge_width 0.5)
			(island_removal_mode 0)
		)
		(polygon
			(pts
				(arc
					(start 35.84067 -175.1838)
					(mid 35.330257 -174.673006)
					(end 34.81959 -175.183546)
				)
				(arc
					(start 34.81959 -175.996346)
					(mid 35.33013 -176.506886)
					(end 35.84067 -175.996346)
				)
				(xy 35.84067 -175.842676) (xy 35.625278 -175.842676)
				(arc
					(start 35.575748 -175.892206)
					(mid 35.141486 -176.18499)
					(end 35.43427 -175.750728)
				)
				(xy 35.542474 -175.642524) (xy 35.84067 -175.642524) (xy 35.84067 -175.537622) (xy 35.542728 -175.537622)
				(arc
					(start 35.43427 -175.429164)
					(mid 35.141486 -174.994902)
					(end 35.575748 -175.287686)
				)
				(xy 35.625532 -175.33747) (xy 35.84067 -175.33747)
			)
		)
	)
	(zone
		(layer "F.Cu")
		(hatch none 0.5)
		(connect_pads
			(clearance 0)
		)
		(min_thickness 0.25)
		(keepout
			(tracks not_allowed)
			(vias allowed)
			(pads allowed)
			(copperpour not_allowed)
			(footprints allowed)
		)
		(placement
			(enabled no)
			(sheetname "")
		)
		(fill
			(thermal_gap 0.5)
			(thermal_bridge_width 0.5)
			(island_removal_mode 0)
		)
		(polygon
			(pts
				(arc
					(start 8.382254 -385.092702)
					(mid 7.871714 -385.603242)
					(end 8.382254 -386.113782)
				)
				(arc
					(start 9.1948 -386.113782)
					(mid 9.705594 -385.603369)
					(end 9.195054 -385.092702)
				)
				(xy 9.040876 -385.092702) (xy 9.040876 -385.307586)
				(arc
					(start 9.090914 -385.357624)
					(mid 9.383698 -385.791886)
					(end 8.949436 -385.499102)
				)
				(xy 8.840724 -385.39039) (xy 8.840724 -385.092702) (xy 8.735822 -385.092702) (xy 8.735822 -385.391152)
				(arc
					(start 8.627872 -385.499102)
					(mid 8.19361 -385.791886)
					(end 8.486394 -385.357624)
				)
				(xy 8.53567 -385.308348) (xy 8.53567 -385.092702)
			)
		)
	)
	(zone
		(layer "F.Cu")
		(hatch none 0.5)
		(connect_pads
			(clearance 0)
		)
		(min_thickness 0.25)
		(keepout
			(tracks allowed)
			(vias allowed)
			(pads allowed)
			(copperpour allowed)
			(footprints allowed)
		)
		(placement
			(enabled no)
			(sheetname "")
		)
		(fill
			(thermal_gap 0.5)
			(thermal_bridge_width 0.5)
			(island_removal_mode 0)
		)
		(polygon
			(pts
				(xy 17.78 -445.77) (xy 17.78 -443.484) (xy 19.939 -443.484) (xy 19.939 -445.77)
			)
		)
	)
	(zone
		(layer "F.Cu")
		(hatch none 0.5)
		(connect_pads
			(clearance 0)
		)
		(min_thickness 0.25)
		(keepout
			(tracks not_allowed)
			(vias allowed)
			(pads allowed)
			(copperpour not_allowed)
			(footprints allowed)
		)
		(placement
			(enabled no)
			(sheetname "")
		)
		(fill
			(thermal_gap 0.5)
			(thermal_bridge_width 0.5)
			(island_removal_mode 0)
		)
		(polygon
			(pts
				(arc
					(start 37.33927 -378.63145)
					(mid 36.727257 -378.019056)
					(end 36.11499 -378.631196)
				)
				(arc
					(start 36.11499 -379.748796)
					(mid 36.72713 -380.360936)
					(end 37.33927 -379.748796)
				)
				(xy 37.33927 -379.442726) (xy 37.174678 -379.442726)
				(arc
					(start 36.972748 -379.644656)
					(mid 36.538486 -379.93744)
					(end 36.83127 -379.503178)
				)
				(xy 37.091874 -379.242574) (xy 37.33927 -379.242574) (xy 37.33927 -379.137672) (xy 37.092128 -379.137672)
				(arc
					(start 36.83127 -378.876814)
					(mid 36.538486 -378.442552)
					(end 36.972748 -378.735336)
				)
				(xy 37.174932 -378.93752) (xy 37.33927 -378.93752)
			)
		)
	)
	(zone
		(layer "F.Cu")
		(hatch none 0.5)
		(connect_pads
			(clearance 0)
		)
		(min_thickness 0.25)
		(keepout
			(tracks not_allowed)
			(vias allowed)
			(pads allowed)
			(copperpour not_allowed)
			(footprints allowed)
		)
		(placement
			(enabled no)
			(sheetname "")
		)
		(fill
			(thermal_gap 0.5)
			(thermal_bridge_width 0.5)
			(island_removal_mode 0)
		)
		(polygon
			(pts
				(arc
					(start 48.89754 -369.579652)
					(mid 48.387127 -369.068858)
					(end 47.87646 -369.579398)
				)
				(arc
					(start 47.87646 -370.392198)
					(mid 48.387 -370.902738)
					(end 48.89754 -370.392198)
				)
				(xy 48.89754 -370.238274) (xy 48.682402 -370.238274)
				(arc
					(start 48.632618 -370.288058)
					(mid 48.198356 -370.580842)
					(end 48.49114 -370.14658)
				)
				(xy 48.599598 -370.038122) (xy 48.89754 -370.038122) (xy 48.89754 -369.93322) (xy 48.599344 -369.93322)
				(arc
					(start 48.49114 -369.825016)
					(mid 48.198356 -369.390754)
					(end 48.632618 -369.683538)
				)
				(xy 48.682148 -369.733068) (xy 48.89754 -369.733068)
			)
		)
	)
	(zone
		(layer "F.Cu")
		(hatch none 0.5)
		(connect_pads
			(clearance 0)
		)
		(min_thickness 0.25)
		(keepout
			(tracks not_allowed)
			(vias allowed)
			(pads allowed)
			(copperpour not_allowed)
			(footprints allowed)
		)
		(placement
			(enabled no)
			(sheetname "")
		)
		(fill
			(thermal_gap 0.5)
			(thermal_bridge_width 0.5)
			(island_removal_mode 0)
		)
		(polygon
			(pts
				(xy 1.022096 -464.995768) (xy 3.758184 -464.995768) (xy 3.81 -465.047584) (xy 3.81 -465.2391) (xy 3.761232 -465.287868)
				(xy 1.025398 -465.287868) (xy 1.014984 -465.298282) (xy 1.010158 -465.298282) (xy 1.005332 -465.293456)
				(xy 1.005332 -464.990942) (xy 1.007872 -464.988402) (xy 1.01473 -464.988402)
			)
		)
	)
	(zone
		(layer "F.Cu")
		(hatch none 0.5)
		(connect_pads
			(clearance 0)
		)
		(min_thickness 0.25)
		(keepout
			(tracks not_allowed)
			(vias allowed)
			(pads allowed)
			(copperpour not_allowed)
			(footprints allowed)
		)
		(placement
			(enabled no)
			(sheetname "")
		)
		(fill
			(thermal_gap 0.5)
			(thermal_bridge_width 0.5)
			(island_removal_mode 0)
		)
		(polygon
			(pts
				(arc
					(start 220.840554 -376.384058)
					(mid 220.330141 -375.873264)
					(end 219.819474 -376.383804)
				)
				(arc
					(start 219.819474 -377.196604)
					(mid 220.330014 -377.707144)
					(end 220.840554 -377.196604)
				)
				(xy 220.840554 -377.04268) (xy 220.625416 -377.04268)
				(arc
					(start 220.575632 -377.092464)
					(mid 220.14137 -377.385248)
					(end 220.434154 -376.950986)
				)
				(xy 220.542612 -376.842528) (xy 220.840554 -376.842528) (xy 220.840554 -376.737626) (xy 220.542358 -376.737626)
				(arc
					(start 220.434154 -376.629422)
					(mid 220.14137 -376.19516)
					(end 220.575632 -376.487944)
				)
				(xy 220.625162 -376.537474) (xy 220.840554 -376.537474)
			)
		)
	)
	(zone
		(layer "F.Cu")
		(hatch none 0.5)
		(connect_pads
			(clearance 0)
		)
		(min_thickness 0.25)
		(keepout
			(tracks not_allowed)
			(vias allowed)
			(pads allowed)
			(copperpour not_allowed)
			(footprints allowed)
		)
		(placement
			(enabled no)
			(sheetname "")
		)
		(fill
			(thermal_gap 0.5)
			(thermal_bridge_width 0.5)
			(island_removal_mode 0)
		)
		(polygon
			(pts
				(arc
					(start 7.502906 -155.974288)
					(mid 6.992493 -155.463494)
					(end 6.481826 -155.974034)
				)
				(xy 6.481826 -156.12745) (xy 6.697472 -156.12745)
				(arc
					(start 6.746748 -156.078174)
					(mid 7.18101 -155.78539)
					(end 6.888226 -156.219652)
				)
				(xy 6.780276 -156.327602) (xy 6.481826 -156.327602) (xy 6.481826 -156.432504) (xy 6.779514 -156.432504)
				(arc
					(start 6.888226 -156.541216)
					(mid 7.18101 -156.975478)
					(end 6.746748 -156.682694)
				)
				(xy 6.69671 -156.632656) (xy 6.481826 -156.632656)
				(arc
					(start 6.481826 -156.786834)
					(mid 6.992366 -157.297374)
					(end 7.502906 -156.786834)
				)
			)
		)
	)
	(zone
		(layer "F.Cu")
		(hatch none 0.5)
		(connect_pads
			(clearance 0)
		)
		(min_thickness 0.25)
		(keepout
			(tracks allowed)
			(vias allowed)
			(pads allowed)
			(copperpour allowed)
			(footprints allowed)
		)
		(placement
			(enabled no)
			(sheetname "")
		)
		(fill
			(thermal_gap 0.5)
			(thermal_bridge_width 0.5)
			(island_removal_mode 0)
		)
		(polygon
			(pts
				(xy 222.377 -470.916) (xy 222.377 -463.804) (xy 224.536 -463.804) (xy 224.536 -470.916)
			)
		)
	)
	(zone
		(layer "F.Cu")
		(hatch none 0.5)
		(connect_pads
			(clearance 0)
		)
		(min_thickness 0.25)
		(keepout
			(tracks not_allowed)
			(vias allowed)
			(pads allowed)
			(copperpour not_allowed)
			(footprints allowed)
		)
		(placement
			(enabled no)
			(sheetname "")
		)
		(fill
			(thermal_gap 0.5)
			(thermal_bridge_width 0.5)
			(island_removal_mode 0)
		)
		(polygon
			(pts
				(arc
					(start 222.339154 -388.231634)
					(mid 221.727141 -387.61924)
					(end 221.114874 -388.23138)
				)
				(arc
					(start 221.114874 -389.34898)
					(mid 221.727014 -389.96112)
					(end 222.339154 -389.34898)
				)
				(xy 222.339154 -389.042656) (xy 222.174816 -389.042656)
				(arc
					(start 221.972632 -389.24484)
					(mid 221.53837 -389.537624)
					(end 221.831154 -389.103362)
				)
				(xy 222.092012 -388.842504) (xy 222.339154 -388.842504) (xy 222.339154 -388.737602) (xy 222.091758 -388.737602)
				(arc
					(start 221.831154 -388.476998)
					(mid 221.53837 -388.042736)
					(end 221.972632 -388.33552)
				)
				(xy 222.174562 -388.53745) (xy 222.339154 -388.53745)
			)
		)
	)
	(zone
		(layer "F.Cu")
		(hatch none 0.5)
		(connect_pads
			(clearance 0)
		)
		(min_thickness 0.25)
		(keepout
			(tracks not_allowed)
			(vias allowed)
			(pads allowed)
			(copperpour not_allowed)
			(footprints allowed)
		)
		(placement
			(enabled no)
			(sheetname "")
		)
		(fill
			(thermal_gap 0.5)
			(thermal_bridge_width 0.5)
			(island_removal_mode 0)
		)
		(polygon
			(pts
				(arc
					(start 25.88514 -322.65112)
					(mid 25.273 -322.03898)
					(end 24.66086 -322.65112)
				)
				(xy 24.66086 -322.947792) (xy 24.83485 -322.947792)
				(arc
					(start 25.027382 -322.75526)
					(mid 25.461644 -322.462476)
					(end 25.16886 -322.896738)
				)
				(xy 24.917654 -323.147944) (xy 24.66086 -323.147944) (xy 24.66086 -323.252846) (xy 24.898604 -323.252846)
				(arc
					(start 25.16886 -323.523102)
					(mid 25.461644 -323.957364)
					(end 25.027382 -323.66458)
				)
				(xy 24.8158 -323.452998) (xy 24.66086 -323.452998)
				(arc
					(start 24.66086 -323.768466)
					(mid 25.272873 -324.38086)
					(end 25.88514 -323.76872)
				)
			)
		)
	)
	(zone
		(net "P12V_SSD14")
		(layer "F.Cu")
		(hatch none 0.5)
		(connect_pads
			(clearance 0.5)
		)
		(min_thickness 0.25)
		(fill yes
			(thermal_gap 0.5)
			(thermal_bridge_width 0.5)
			(island_removal_mode 0)
		)
		(polygon
			(pts
				(xy 20.066 -4.826) (xy 17.272 -7.62) (xy 17.272 -10.9728) (xy 18.6182 -12.319) (xy 20.9296 -12.319)
				(xy 21.1582 -12.0904) (xy 21.1582 -10.3378) (xy 22.098 -9.398) (xy 24.0538 -9.398) (xy 25.3746 -10.7188)
				(xy 25.3746 -11.2776) (xy 25.4254 -11.3284) (xy 28.6004 -11.3284) (xy 28.7274 -11.2014) (xy 28.7274 -10.7188)
				(xy 28.9814 -10.4648) (xy 29.9466 -10.4648) (xy 30.8991 -11.4173) (xy 32.3215 -11.4173) (xy 32.5374 -11.6332)
				(xy 32.5374 -13.1572) (xy 32.9946 -13.6144) (xy 40.1828 -13.6144) (xy 40.7035 -14.1351) (xy 40.7035 -15.1003)
				(xy 41.1988 -15.5956) (xy 43.0022 -15.5956) (xy 43.18 -15.4178) (xy 43.18 -10.742422) (xy 43.01236 -10.574782)
				(xy 39.835582 -10.574782) (xy 39.5224 -10.2616) (xy 39.5224 -8.5344) (xy 39.362634 -8.374634) (xy 37.084 -8.374634)
				(xy 36.060634 -9.398) (xy 32.004 -9.398) (xy 29.5402 -6.9342) (xy 25.4508 -6.9342) (xy 25.3238 -6.8072)
				(xy 25.3238 -5.461) (xy 24.6888 -4.826)
			)
		)
		(polygon
			(pts
				(xy 33.8074 -13.2842) (xy 33.6042 -13.2842) (xy 33.6042 -13.4874) (xy 33.8074 -13.4874)
			)
		)
		(polygon
			(pts
				(xy 33.8074 -12.4206) (xy 33.6042 -12.4206) (xy 33.6042 -12.6238) (xy 33.8074 -12.6238)
			)
		)
		(polygon
			(pts
				(xy 32.9438 -12.4206) (xy 32.7406 -12.4206) (xy 32.7406 -12.6238) (xy 32.9438 -12.6238)
			)
		)
		(polygon
			(pts
				(xy 28.2702 -10.0838) (xy 28.067 -10.0838) (xy 28.067 -10.287) (xy 28.2702 -10.287)
			)
		)
		(polygon
			(pts
				(xy 25.4762 -10.0838) (xy 25.273 -10.0838) (xy 25.273 -10.287) (xy 25.4762 -10.287)
			)
		)
		(polygon
			(pts
				(xy 29.7942 -9.7536) (xy 29.591 -9.7536) (xy 29.591 -9.9568) (xy 29.7942 -9.9568)
			)
		)
		(polygon
			(pts
				(xy 29.1846 -9.7536) (xy 28.9814 -9.7536) (xy 28.9814 -9.9568) (xy 29.1846 -9.9568)
			)
		)
	)
	(zone
		(net "VDD_DIFF_2")
		(layer "F.Cu")
		(hatch none 0.5)
		(connect_pads
			(clearance 0.5)
		)
		(min_thickness 0.25)
		(fill yes
			(thermal_gap 0.5)
			(thermal_bridge_width 0.5)
			(island_removal_mode 0)
		)
		(polygon
			(pts
				(xy 79.7814 -305.2572) (xy 79.261462 -305.777138) (xy 78.335886 -305.777138) (xy 78.2574 -305.855624)
				(xy 78.2574 -307.467) (xy 79.2988 -308.5084) (xy 79.2988 -312.2676) (xy 79.4512 -312.42) (xy 82.4992 -312.42)
				(xy 82.7786 -312.1406) (xy 82.7786 -309.2196) (xy 82.6516 -309.0926) (xy 81.4578 -309.0926) (xy 81.0768 -308.7116)
				(xy 81.0768 -308.229) (xy 81.5086 -307.7972) (xy 82.7024 -307.7972) (xy 82.7786 -307.721) (xy 82.7786 -305.6128)
				(xy 82.423 -305.2572)
			)
		)
		(polygon
			(pts
				(xy 82.3214 -311.7088) (xy 82.1182 -311.7088) (xy 82.1182 -311.912) (xy 82.3214 -311.912)
			)
		)
		(polygon
			(pts
				(xy 82.3214 -311.15) (xy 82.1182 -311.15) (xy 82.1182 -311.3532) (xy 82.3214 -311.3532)
			)
		)
		(polygon
			(pts
				(xy 82.3214 -310.6928) (xy 82.1182 -310.6928) (xy 82.1182 -310.896) (xy 82.3214 -310.896)
			)
		)
		(polygon
			(pts
				(xy 82.3214 -310.134) (xy 82.1182 -310.134) (xy 82.1182 -310.3372) (xy 82.3214 -310.3372)
			)
		)
		(polygon
			(pts
				(xy 82.3214 -309.6768) (xy 82.1182 -309.6768) (xy 82.1182 -309.88) (xy 82.3214 -309.88)
			)
		)
		(polygon
			(pts
				(xy 80.2386 -309.5752) (xy 80.0354 -309.5752) (xy 80.0354 -309.7784) (xy 80.2386 -309.7784)
			)
		)
		(polygon
			(pts
				(xy 80.2386 -308.7116) (xy 80.0354 -308.7116) (xy 80.0354 -308.9148) (xy 80.2386 -308.9148)
			)
		)
		(polygon
			(pts
				(xy 82.3214 -306.959) (xy 82.1182 -306.959) (xy 82.1182 -307.1622) (xy 82.3214 -307.1622)
			)
		)
		(polygon
			(pts
				(xy 82.3214 -306.451) (xy 82.1182 -306.451) (xy 82.1182 -306.6542) (xy 82.3214 -306.6542)
			)
		)
		(polygon
			(pts
				(xy 78.9432 -306.2351) (xy 78.74 -306.2351) (xy 78.74 -306.4383) (xy 78.9432 -306.4383)
			)
		)
		(polygon
			(pts
				(xy 82.3214 -305.8922) (xy 82.1182 -305.8922) (xy 82.1182 -306.0954) (xy 82.3214 -306.0954)
			)
		)
	)
	(zone
		(net "GND")
		(layer "F.Cu")
		(hatch none 0.5)
		(connect_pads
			(clearance 0.5)
		)
		(min_thickness 0.25)
		(fill yes
			(thermal_gap 0.5)
			(thermal_bridge_width 0.5)
			(island_removal_mode 0)
		)
		(polygon
			(pts
				(xy 32.893 -494.1062) (xy 32.7152 -494.284) (xy 32.7152 -495.6556) (xy 32.893 -495.8334) (xy 34.671 -495.8334)
				(xy 34.8234 -495.681) (xy 34.8234 -494.9698) (xy 33.9598 -494.1062)
			)
		)
		(polygon
			(pts
				(xy 34.2392 -495.1222) (xy 34.036 -495.1222) (xy 34.036 -495.3254) (xy 34.2392 -495.3254)
			)
		)
		(polygon
			(pts
				(xy 33.6296 -495.1222) (xy 33.4264 -495.1222) (xy 33.4264 -495.3254) (xy 33.6296 -495.3254)
			)
		)
	)
	(zone
		(net "P3V3")
		(layer "F.Cu")
		(hatch none 0.5)
		(connect_pads
			(clearance 0.5)
		)
		(min_thickness 0.25)
		(fill yes
			(thermal_gap 0.5)
			(thermal_bridge_width 0.5)
			(island_removal_mode 0)
		)
		(polygon
			(pts
				(xy 25.146 -360.299) (xy 24.8158 -360.6292) (xy 24.2824 -360.6292) (xy 24.1808 -360.7308) (xy 24.1808 -364.0328)
				(xy 24.2824 -364.1344) (xy 25.2222 -364.1344) (xy 25.654 -363.7026) (xy 25.654 -360.4768) (xy 25.4762 -360.299)
			)
		)
		(polygon
			(pts
				(xy 24.8158 -363.6518) (xy 24.6126 -363.6518) (xy 24.6126 -363.855) (xy 24.8158 -363.855)
			)
		)
		(polygon
			(pts
				(xy 24.8158 -363.093) (xy 24.6126 -363.093) (xy 24.6126 -363.2962) (xy 24.8158 -363.2962)
			)
		)
		(polygon
			(pts
				(xy 24.8158 -362.5088) (xy 24.6126 -362.5088) (xy 24.6126 -362.712) (xy 24.8158 -362.712)
			)
		)
		(polygon
			(pts
				(xy 24.8158 -361.95) (xy 24.6126 -361.95) (xy 24.6126 -362.1532) (xy 24.8158 -362.1532)
			)
		)
		(polygon
			(pts
				(xy 24.8158 -361.3658) (xy 24.6126 -361.3658) (xy 24.6126 -361.569) (xy 24.8158 -361.569)
			)
		)
		(polygon
			(pts
				(xy 24.8158 -360.807) (xy 24.6126 -360.807) (xy 24.6126 -361.0102) (xy 24.8158 -361.0102)
			)
		)
	)
	(zone
		(net "GND")
		(layer "F.Cu")
		(hatch none 0.5)
		(connect_pads
			(clearance 0.5)
		)
		(min_thickness 0.25)
		(fill yes
			(thermal_gap 0.5)
			(thermal_bridge_width 0.5)
			(island_removal_mode 0)
		)
		(polygon
			(pts
				(xy 200.192894 -418.71773) (xy 199.278748 -419.631876) (xy 199.278748 -420.747952) (xy 206.540608 -428.009812)
				(xy 220.699838 -428.009812) (xy 221.381828 -427.327822) (xy 221.381828 -419.164516) (xy 220.935042 -418.71773)
			)
		)
	)
	(zone
		(layer "F.Cu")
		(hatch none 0.5)
		(connect_pads
			(clearance 0)
		)
		(min_thickness 0.25)
		(keepout
			(tracks not_allowed)
			(vias allowed)
			(pads allowed)
			(copperpour not_allowed)
			(footprints allowed)
		)
		(placement
			(enabled no)
			(sheetname "")
		)
		(fill
			(thermal_gap 0.5)
			(thermal_bridge_width 0.5)
			(island_removal_mode 0)
		)
		(polygon
			(pts
				(arc
					(start 222.339154 -280.431494)
					(mid 221.727141 -279.8191)
					(end 221.114874 -280.43124)
				)
				(arc
					(start 221.114874 -281.54884)
					(mid 221.727014 -282.16098)
					(end 222.339154 -281.54884)
				)
				(xy 222.339154 -281.24277) (xy 222.174562 -281.24277)
				(arc
					(start 221.972632 -281.4447)
					(mid 221.53837 -281.737484)
					(end 221.831154 -281.303222)
				)
				(xy 222.091758 -281.042618) (xy 222.339154 -281.042618) (xy 222.339154 -280.937716) (xy 222.092012 -280.937716)
				(arc
					(start 221.831154 -280.676858)
					(mid 221.53837 -280.242596)
					(end 221.972632 -280.53538)
				)
				(xy 222.174816 -280.737564) (xy 222.339154 -280.737564)
			)
		)
	)
	(zone
		(layer "F.Cu")
		(hatch none 0.5)
		(connect_pads
			(clearance 0)
		)
		(min_thickness 0.25)
		(keepout
			(tracks not_allowed)
			(vias allowed)
			(pads allowed)
			(copperpour not_allowed)
			(footprints allowed)
		)
		(placement
			(enabled no)
			(sheetname "")
		)
		(fill
			(thermal_gap 0.5)
			(thermal_bridge_width 0.5)
			(island_removal_mode 0)
		)
		(polygon
			(pts
				(arc
					(start 48.89754 -163.579556)
					(mid 48.387127 -163.068762)
					(end 47.87646 -163.579302)
				)
				(arc
					(start 47.87646 -164.392102)
					(mid 48.387 -164.902642)
					(end 48.89754 -164.392102)
				)
				(xy 48.89754 -164.238178) (xy 48.682402 -164.238178)
				(arc
					(start 48.632618 -164.287962)
					(mid 48.198356 -164.580746)
					(end 48.49114 -164.146484)
				)
				(xy 48.599598 -164.038026) (xy 48.89754 -164.038026) (xy 48.89754 -163.933124) (xy 48.599344 -163.933124)
				(arc
					(start 48.49114 -163.82492)
					(mid 48.198356 -163.390658)
					(end 48.632618 -163.683442)
				)
				(xy 48.682148 -163.732972) (xy 48.89754 -163.732972)
			)
		)
	)
	(zone
		(layer "F.Cu")
		(hatch none 0.5)
		(connect_pads
			(clearance 0)
		)
		(min_thickness 0.25)
		(keepout
			(tracks allowed)
			(vias allowed)
			(pads allowed)
			(copperpour allowed)
			(footprints not_allowed)
		)
		(placement
			(enabled no)
			(sheetname "")
		)
		(fill
			(thermal_gap 0.5)
			(thermal_bridge_width 0.5)
			(island_removal_mode 0)
		)
		(polygon
			(pts
				(xy 230.15829 -41.800018) (xy 230.15829 -8.670036) (xy 210.455256 -8.670036) (xy 210.455256 -67.170046)
				(xy 220.495368 -67.170046) (xy 220.495368 -41.800018)
			)
		)
	)
	(zone
		(layer "F.Cu")
		(hatch none 0.5)
		(connect_pads
			(clearance 0)
		)
		(min_thickness 0.25)
		(keepout
			(tracks not_allowed)
			(vias allowed)
			(pads allowed)
			(copperpour not_allowed)
			(footprints allowed)
		)
		(placement
			(enabled no)
			(sheetname "")
		)
		(fill
			(thermal_gap 0.5)
			(thermal_bridge_width 0.5)
			(island_removal_mode 0)
		)
		(polygon
			(pts
				(xy 88.97239 -210.73491) (xy 90.14079 -210.73491) (xy 90.14079 -210.82381) (xy 88.97239 -210.82381)
			)
		)
	)
	(zone
		(layer "F.Cu")
		(hatch none 0.5)
		(connect_pads
			(clearance 0)
		)
		(min_thickness 0.25)
		(keepout
			(tracks allowed)
			(vias allowed)
			(pads allowed)
			(copperpour allowed)
			(footprints allowed)
		)
		(placement
			(enabled no)
			(sheetname "")
		)
		(fill
			(thermal_gap 0.5)
			(thermal_bridge_width 0.5)
			(island_removal_mode 0)
		)
		(polygon
			(pts
				(xy 91.821 -423.291) (xy 91.821 -424.815) (xy 92.837 -425.831) (xy 92.837 -427.736) (xy 90.043 -427.736)
				(xy 90.043 -426.593) (xy 88.9 -425.45) (xy 87.757 -425.45) (xy 86.106 -423.799) (xy 86.106 -423.291)
			)
		)
	)
	(zone
		(net "P12V")
		(layer "F.Cu")
		(hatch none 0.5)
		(connect_pads
			(clearance 0.5)
		)
		(min_thickness 0.25)
		(fill yes
			(thermal_gap 0.5)
			(thermal_bridge_width 0.5)
			(island_removal_mode 0)
		)
		(polygon
			(pts
				(xy 24.0538 -87.2744) (xy 23.9268 -87.4014) (xy 23.9268 -87.9094) (xy 24.0538 -88.0364) (xy 24.6888 -88.0364)
				(xy 24.9682 -88.3158) (xy 24.9682 -89.0778) (xy 25.3238 -89.4334) (xy 25.3238 -90.8304) (xy 26.6446 -92.1512)
				(xy 26.6446 -92.9386) (xy 28.067 -94.361) (xy 29.1592 -94.361) (xy 29.4386 -94.0816) (xy 29.4386 -93.6752)
				(xy 30.0228 -93.091) (xy 30.0228 -88.1634) (xy 29.7688 -87.9094) (xy 26.3398 -87.9094) (xy 25.7048 -87.2744)
			)
		)
		(polygon
			(pts
				(xy 29.2481 -93.7133) (xy 29.0449 -93.7133) (xy 29.0449 -93.9165) (xy 29.2481 -93.9165)
			)
		)
		(polygon
			(pts
				(xy 28.6893 -93.7133) (xy 28.4861 -93.7133) (xy 28.4861 -93.9165) (xy 28.6893 -93.9165)
			)
		)
		(polygon
			(pts
				(xy 25.6286 -88.8238) (xy 25.4254 -88.8238) (xy 25.4254 -89.027) (xy 25.6286 -89.027)
			)
		)
		(polygon
			(pts
				(xy 25.6286 -88.265) (xy 25.4254 -88.265) (xy 25.4254 -88.4682) (xy 25.6286 -88.4682)
			)
		)
		(polygon
			(pts
				(xy 25.7302 -87.7824) (xy 25.527 -87.7824) (xy 25.527 -87.9856) (xy 25.7302 -87.9856)
			)
		)
		(polygon
			(pts
				(xy 25.1206 -87.7824) (xy 24.9174 -87.7824) (xy 24.9174 -87.9856) (xy 25.1206 -87.9856)
			)
		)
	)
	(zone
		(layer "F.Cu")
		(hatch none 0.5)
		(connect_pads
			(clearance 0)
		)
		(min_thickness 0.25)
		(keepout
			(tracks allowed)
			(vias allowed)
			(pads allowed)
			(copperpour allowed)
			(footprints allowed)
		)
		(placement
			(enabled no)
			(sheetname "")
		)
		(fill
			(thermal_gap 0.5)
			(thermal_bridge_width 0.5)
			(island_removal_mode 0)
		)
		(polygon
			(pts
				(xy 226.9744 -446.151) (xy 226.9744 -447.0146) (xy 225.7806 -447.0146) (xy 225.7806 -446.151)
			)
		)
	)
	(zone
		(layer "F.Cu")
		(hatch none 0.5)
		(connect_pads
			(clearance 0)
		)
		(min_thickness 0.25)
		(keepout
			(tracks not_allowed)
			(vias allowed)
			(pads allowed)
			(copperpour not_allowed)
			(footprints allowed)
		)
		(placement
			(enabled no)
			(sheetname "")
		)
		(fill
			(thermal_gap 0.5)
			(thermal_bridge_width 0.5)
			(island_removal_mode 0)
		)
		(polygon
			(pts
				(xy 1.022096 -459.39583) (xy 3.758184 -459.39583) (xy 3.81 -459.447646) (xy 3.81 -459.639162) (xy 3.761232 -459.68793)
				(xy 1.025398 -459.68793) (xy 1.014984 -459.698344) (xy 1.010158 -459.698344) (xy 1.005332 -459.693518)
				(xy 1.005332 -459.391004) (xy 1.007872 -459.388464) (xy 1.01473 -459.388464)
			)
		)
	)
	(zone
		(layer "F.Cu")
		(hatch none 0.5)
		(connect_pads
			(clearance 0)
		)
		(min_thickness 0.25)
		(keepout
			(tracks not_allowed)
			(vias allowed)
			(pads allowed)
			(copperpour not_allowed)
			(footprints allowed)
		)
		(placement
			(enabled no)
			(sheetname "")
		)
		(fill
			(thermal_gap 0.5)
			(thermal_bridge_width 0.5)
			(island_removal_mode 0)
		)
		(polygon
			(pts
				(arc
					(start 27.18054 -128.8034)
					(mid 26.67 -128.29286)
					(end 26.15946 -128.8034)
				)
				(xy 26.15946 -128.957324) (xy 26.374598 -128.957324)
				(arc
					(start 26.424382 -128.90754)
					(mid 26.858644 -128.614756)
					(end 26.56586 -129.049018)
				)
				(xy 26.457402 -129.157476) (xy 26.15946 -129.157476) (xy 26.15946 -129.262378) (xy 26.457656 -129.262378)
				(arc
					(start 26.56586 -129.370582)
					(mid 26.858644 -129.804844)
					(end 26.424382 -129.51206)
				)
				(xy 26.374852 -129.46253) (xy 26.15946 -129.46253)
				(arc
					(start 26.15946 -129.615946)
					(mid 26.669873 -130.12674)
					(end 27.18054 -129.6162)
				)
			)
		)
	)
	(zone
		(layer "F.Cu")
		(hatch none 0.5)
		(connect_pads
			(clearance 0)
		)
		(min_thickness 0.25)
		(keepout
			(tracks not_allowed)
			(vias allowed)
			(pads allowed)
			(copperpour not_allowed)
			(footprints allowed)
		)
		(placement
			(enabled no)
			(sheetname "")
		)
		(fill
			(thermal_gap 0.5)
			(thermal_bridge_width 0.5)
			(island_removal_mode 0)
		)
		(polygon
			(pts
				(arc
					(start 32.00654 -32.60344)
					(mid 31.496127 -32.092646)
					(end 30.98546 -32.603186)
				)
				(arc
					(start 30.98546 -33.415986)
					(mid 31.496 -33.926526)
					(end 32.00654 -33.415986)
				)
				(xy 32.00654 -33.26257) (xy 31.790894 -33.26257)
				(arc
					(start 31.741618 -33.311846)
					(mid 31.307356 -33.60463)
					(end 31.60014 -33.170368)
				)
				(xy 31.70809 -33.062418) (xy 32.00654 -33.062418) (xy 32.00654 -32.957516) (xy 31.708852 -32.957516)
				(arc
					(start 31.60014 -32.848804)
					(mid 31.307356 -32.414542)
					(end 31.741618 -32.707326)
				)
				(xy 31.791656 -32.757364) (xy 32.00654 -32.757364)
			)
		)
	)
	(zone
		(layer "F.Cu")
		(hatch none 0.5)
		(connect_pads
			(clearance 0)
		)
		(min_thickness 0.25)
		(keepout
			(tracks not_allowed)
			(vias allowed)
			(pads allowed)
			(copperpour not_allowed)
			(footprints allowed)
		)
		(placement
			(enabled no)
			(sheetname "")
		)
		(fill
			(thermal_gap 0.5)
			(thermal_bridge_width 0.5)
			(island_removal_mode 0)
		)
		(polygon
			(pts
				(arc
					(start 35.84067 -376.384058)
					(mid 35.330257 -375.873264)
					(end 34.81959 -376.383804)
				)
				(arc
					(start 34.81959 -377.196604)
					(mid 35.33013 -377.707144)
					(end 35.84067 -377.196604)
				)
				(xy 35.84067 -377.04268) (xy 35.625532 -377.04268)
				(arc
					(start 35.575748 -377.092464)
					(mid 35.141486 -377.385248)
					(end 35.43427 -376.950986)
				)
				(xy 35.542728 -376.842528) (xy 35.84067 -376.842528) (xy 35.84067 -376.737626) (xy 35.542474 -376.737626)
				(arc
					(start 35.43427 -376.629422)
					(mid 35.141486 -376.19516)
					(end 35.575748 -376.487944)
				)
				(xy 35.625278 -376.537474) (xy 35.84067 -376.537474)
			)
		)
	)
	(zone
		(layer "F.Cu")
		(hatch none 0.5)
		(connect_pads
			(clearance 0)
		)
		(min_thickness 0.25)
		(keepout
			(tracks not_allowed)
			(vias allowed)
			(pads allowed)
			(copperpour not_allowed)
			(footprints allowed)
		)
		(placement
			(enabled no)
			(sheetname "")
		)
		(fill
			(thermal_gap 0.5)
			(thermal_bridge_width 0.5)
			(island_removal_mode 0)
		)
		(polygon
			(pts
				(arc
					(start 233.897424 -60.579254)
					(mid 233.386884 -60.068714)
					(end 232.876344 -60.579254)
				)
				(arc
					(start 232.876344 -61.3918)
					(mid 233.386757 -61.902594)
					(end 233.897424 -61.392054)
				)
				(xy 233.897424 -61.23813) (xy 233.682286 -61.23813)
				(arc
					(start 233.632502 -61.287914)
					(mid 233.19824 -61.580698)
					(end 233.491024 -61.146436)
				)
				(xy 233.599482 -61.037978) (xy 233.897424 -61.037978) (xy 233.897424 -60.933076) (xy 233.599228 -60.933076)
				(arc
					(start 233.491024 -60.824872)
					(mid 233.19824 -60.39061)
					(end 233.632502 -60.683394)
				)
				(xy 233.682032 -60.732924) (xy 233.897424 -60.732924)
			)
		)
	)
	(zone
		(layer "F.Cu")
		(hatch none 0.5)
		(connect_pads
			(clearance 0)
		)
		(min_thickness 0.25)
		(keepout
			(tracks not_allowed)
			(vias allowed)
			(pads allowed)
			(copperpour not_allowed)
			(footprints allowed)
		)
		(placement
			(enabled no)
			(sheetname "")
		)
		(fill
			(thermal_gap 0.5)
			(thermal_bridge_width 0.5)
			(island_removal_mode 0)
		)
		(polygon
			(pts
				(arc
					(start 220.840554 -282.98394)
					(mid 220.330141 -282.473146)
					(end 219.819474 -282.983686)
				)
				(arc
					(start 219.819474 -283.796486)
					(mid 220.330014 -284.307026)
					(end 220.840554 -283.796486)
				)
				(xy 220.840554 -283.642816) (xy 220.625162 -283.642816)
				(arc
					(start 220.575632 -283.692346)
					(mid 220.14137 -283.98513)
					(end 220.434154 -283.550868)
				)
				(xy 220.542358 -283.442664) (xy 220.840554 -283.442664) (xy 220.840554 -283.337762) (xy 220.542612 -283.337762)
				(arc
					(start 220.434154 -283.229304)
					(mid 220.14137 -282.795042)
					(end 220.575632 -283.087826)
				)
				(xy 220.625416 -283.13761) (xy 220.840554 -283.13761)
			)
		)
	)
	(zone
		(net "P12V_SSD5")
		(layer "F.Cu")
		(hatch none 0.5)
		(connect_pads
			(clearance 0.5)
		)
		(min_thickness 0.25)
		(fill yes
			(thermal_gap 0.5)
			(thermal_bridge_width 0.5)
			(island_removal_mode 0)
		)
		(polygon
			(pts
				(xy 24.3586 -490.6772) (xy 23.876 -491.1598) (xy 23.876 -496.3922) (xy 23.5458 -496.7224) (xy 23.5458 -498.2718)
				(xy 24.003 -498.729) (xy 30.734 -498.729) (xy 30.8864 -498.8814) (xy 30.8864 -501.015) (xy 31.1658 -501.2944)
				(xy 35.011868 -501.2944) (xy 35.460178 -500.84609) (xy 35.460178 -497.533422) (xy 35.6108 -497.3828)
				(xy 37.2364 -497.3828) (xy 37.4396 -497.586) (xy 37.4396 -500.903494) (xy 37.551106 -501.015) (xy 42.037 -501.015)
				(xy 44.069 -498.983) (xy 44.069 -493.798606) (xy 43.952668 -493.682274) (xy 40.769032 -493.682274)
				(xy 40.64 -493.811306) (xy 40.64 -495.9096) (xy 40.4114 -496.1382) (xy 37.973 -496.1382) (xy 37.3888 -495.554)
				(xy 35.433 -495.554) (xy 34.8488 -496.1382) (xy 30.933644 -496.1382) (xy 28.199842 -493.404398)
				(xy 28.199842 -491.386622) (xy 27.49042 -490.6772)
			)
		)
		(polygon
			(pts
				(xy 32.4104 -500.4562) (xy 32.2072 -500.4562) (xy 32.2072 -500.6594) (xy 32.4104 -500.6594)
			)
		)
		(polygon
			(pts
				(xy 31.2674 -500.4562) (xy 31.0642 -500.4562) (xy 31.0642 -500.6594) (xy 31.2674 -500.6594)
			)
		)
		(polygon
			(pts
				(xy 30.6324 -497.7638) (xy 30.4292 -497.7638) (xy 30.4292 -497.967) (xy 30.6324 -497.967)
			)
		)
		(polygon
			(pts
				(xy 29.7688 -497.7638) (xy 29.5656 -497.7638) (xy 29.5656 -497.967) (xy 29.7688 -497.967)
			)
		)
		(polygon
			(pts
				(xy 32.4104 -497.6622) (xy 32.2072 -497.6622) (xy 32.2072 -497.8654) (xy 32.4104 -497.8654)
			)
		)
		(polygon
			(pts
				(xy 31.2674 -497.6622) (xy 31.0642 -497.6622) (xy 31.0642 -497.8654) (xy 31.2674 -497.8654)
			)
		)
		(polygon
			(pts
				(xy 34.2392 -496.6462) (xy 34.036 -496.6462) (xy 34.036 -496.8494) (xy 34.2392 -496.8494)
			)
		)
		(polygon
			(pts
				(xy 33.6296 -496.6462) (xy 33.4264 -496.6462) (xy 33.4264 -496.8494) (xy 33.6296 -496.8494)
			)
		)
	)
	(zone
		(net "GND")
		(layer "F.Cu")
		(hatch none 0.5)
		(connect_pads
			(clearance 0.5)
		)
		(min_thickness 0.25)
		(fill yes
			(thermal_gap 0.5)
			(thermal_bridge_width 0.5)
			(island_removal_mode 0)
		)
		(polygon
			(pts
				(xy 15.113 -481.33) (xy 14.224 -482.219) (xy 14.224 -489.712) (xy 14.707108 -490.195108) (xy 27.565096 -490.195108)
				(xy 27.686 -490.074204) (xy 27.686 -481.7618) (xy 27.2542 -481.33)
			)
		)
	)
	(zone
		(layer "F.Cu")
		(hatch none 0.5)
		(connect_pads
			(clearance 0)
		)
		(min_thickness 0.25)
		(keepout
			(tracks not_allowed)
			(vias allowed)
			(pads allowed)
			(copperpour not_allowed)
			(footprints allowed)
		)
		(placement
			(enabled no)
			(sheetname "")
		)
		(fill
			(thermal_gap 0.5)
			(thermal_bridge_width 0.5)
			(island_removal_mode 0)
		)
		(polygon
			(pts
				(arc
					(start 222.339154 -182.231538)
					(mid 221.727141 -181.619144)
					(end 221.114874 -182.231284)
				)
				(arc
					(start 221.114874 -183.348884)
					(mid 221.727014 -183.961024)
					(end 222.339154 -183.348884)
				)
				(xy 222.339154 -183.04256) (xy 222.174816 -183.04256)
				(arc
					(start 221.972632 -183.244744)
					(mid 221.53837 -183.537528)
					(end 221.831154 -183.103266)
				)
				(xy 222.092012 -182.842408) (xy 222.339154 -182.842408) (xy 222.339154 -182.737506) (xy 222.091758 -182.737506)
				(arc
					(start 221.831154 -182.476902)
					(mid 221.53837 -182.04264)
					(end 221.972632 -182.335424)
				)
				(xy 222.174562 -182.537354) (xy 222.339154 -182.537354)
			)
		)
	)
	(zone
		(net "GND")
		(layer "F.Cu")
		(hatch none 0.5)
		(connect_pads
			(clearance 0.5)
		)
		(min_thickness 0.25)
		(fill yes
			(thermal_gap 0.5)
			(thermal_bridge_width 0.5)
			(island_removal_mode 0)
		)
		(polygon
			(pts
				(xy 226.2632 -433.451) (xy 226.1997 -433.5145) (xy 226.1997 -435.2925) (xy 226.06 -435.4322) (xy 226.06 -437.007)
				(xy 226.187 -437.134) (xy 226.441 -437.134) (xy 226.822 -436.753) (xy 226.822 -435.2798) (xy 226.9998 -435.102)
				(xy 227.6094 -435.102) (xy 227.711 -435.0004) (xy 227.711 -433.5272) (xy 227.6348 -433.451)
			)
		)
	)
	(zone
		(layer "F.Cu")
		(hatch none 0.5)
		(connect_pads
			(clearance 0)
		)
		(min_thickness 0.25)
		(keepout
			(tracks allowed)
			(vias allowed)
			(pads allowed)
			(copperpour allowed)
			(footprints allowed)
		)
		(placement
			(enabled no)
			(sheetname "")
		)
		(fill
			(thermal_gap 0.5)
			(thermal_bridge_width 0.5)
			(island_removal_mode 0)
		)
		(polygon
			(pts
				(xy 77.724 -359.664) (xy 74.676 -359.664) (xy 74.676 -358.14) (xy 77.724 -358.14)
			)
		)
	)
	(zone
		(layer "F.Cu")
		(hatch none 0.5)
		(connect_pads
			(clearance 0)
		)
		(min_thickness 0.25)
		(keepout
			(tracks not_allowed)
			(vias allowed)
			(pads allowed)
			(copperpour not_allowed)
			(footprints allowed)
		)
		(placement
			(enabled no)
			(sheetname "")
		)
		(fill
			(thermal_gap 0.5)
			(thermal_bridge_width 0.5)
			(island_removal_mode 0)
		)
		(polygon
			(pts
				(arc
					(start 222.339154 -69.631306)
					(mid 221.727141 -69.018912)
					(end 221.114874 -69.631052)
				)
				(arc
					(start 221.114874 -70.748652)
					(mid 221.727014 -71.360792)
					(end 222.339154 -70.748652)
				)
				(xy 222.339154 -70.442582) (xy 222.174562 -70.442582)
				(arc
					(start 221.972632 -70.644512)
					(mid 221.53837 -70.937296)
					(end 221.831154 -70.503034)
				)
				(xy 222.091758 -70.24243) (xy 222.339154 -70.24243) (xy 222.339154 -70.137528) (xy 222.092012 -70.137528)
				(arc
					(start 221.831154 -69.87667)
					(mid 221.53837 -69.442408)
					(end 221.972632 -69.735192)
				)
				(xy 222.174816 -69.937376) (xy 222.339154 -69.937376)
			)
		)
	)
	(zone
		(layer "F.Cu")
		(hatch none 0.5)
		(connect_pads
			(clearance 0)
		)
		(min_thickness 0.25)
		(keepout
			(tracks not_allowed)
			(vias allowed)
			(pads allowed)
			(copperpour not_allowed)
			(footprints allowed)
		)
		(placement
			(enabled no)
			(sheetname "")
		)
		(fill
			(thermal_gap 0.5)
			(thermal_bridge_width 0.5)
			(island_removal_mode 0)
		)
		(polygon
			(pts
				(arc
					(start 48.89754 -472.5797)
					(mid 48.387127 -472.068906)
					(end 47.87646 -472.579446)
				)
				(arc
					(start 47.87646 -473.392246)
					(mid 48.387 -473.902786)
					(end 48.89754 -473.392246)
				)
				(xy 48.89754 -473.238322) (xy 48.682402 -473.238322)
				(arc
					(start 48.632618 -473.288106)
					(mid 48.198356 -473.58089)
					(end 48.49114 -473.146628)
				)
				(xy 48.599598 -473.03817) (xy 48.89754 -473.03817) (xy 48.89754 -472.933268) (xy 48.599344 -472.933268)
				(arc
					(start 48.49114 -472.825064)
					(mid 48.198356 -472.390802)
					(end 48.632618 -472.683586)
				)
				(xy 48.682148 -472.733116) (xy 48.89754 -472.733116)
			)
		)
	)
	(zone
		(layer "F.Cu")
		(hatch none 0.5)
		(connect_pads
			(clearance 0)
		)
		(min_thickness 0.25)
		(keepout
			(tracks not_allowed)
			(vias allowed)
			(pads allowed)
			(copperpour not_allowed)
			(footprints allowed)
		)
		(placement
			(enabled no)
			(sheetname "")
		)
		(fill
			(thermal_gap 0.5)
			(thermal_bridge_width 0.5)
			(island_removal_mode 0)
		)
		(polygon
			(pts
				(arc
					(start 220.840554 -157.583886)
					(mid 220.330141 -157.073092)
					(end 219.819474 -157.583632)
				)
				(arc
					(start 219.819474 -158.396432)
					(mid 220.330014 -158.906972)
					(end 220.840554 -158.396432)
				)
				(xy 220.840554 -158.242762) (xy 220.625162 -158.242762)
				(arc
					(start 220.575632 -158.292292)
					(mid 220.14137 -158.585076)
					(end 220.434154 -158.150814)
				)
				(xy 220.542358 -158.04261) (xy 220.840554 -158.04261) (xy 220.840554 -157.937708) (xy 220.542612 -157.937708)
				(arc
					(start 220.434154 -157.82925)
					(mid 220.14137 -157.394988)
					(end 220.575632 -157.687772)
				)
				(xy 220.625416 -157.737556) (xy 220.840554 -157.737556)
			)
		)
	)
	(zone
		(net "GND")
		(layer "F.Cu")
		(hatch none 0.5)
		(connect_pads
			(clearance 0.5)
		)
		(min_thickness 0.25)
		(fill yes
			(thermal_gap 0.5)
			(thermal_bridge_width 0.5)
			(island_removal_mode 0)
		)
		(polygon
			(pts
				(xy 32.639 -47.498) (xy 26.747724 -53.389276) (xy 26.747724 -56.32831) (xy 26.310082 -56.765952)
				(xy 25.80513 -56.765952) (xy 25.239472 -57.33161) (xy 25.239472 -58.354976) (xy 25.73655 -58.852054)
				(xy 25.73655 -60.91428) (xy 25.74544 -60.92317) (xy 25.74544 -62.585092) (xy 25.738582 -62.59195)
				(xy 24.215598 -62.59195) (xy 24.099012 -62.708536) (xy 24.099012 -63.714122) (xy 22.748748 -65.064386)
				(xy 16.118332 -65.064386) (xy 15.621 -65.561718) (xy 15.621 -73.81748) (xy 15.842996 -74.039476)
				(xy 19.432524 -74.039476) (xy 29.845 -63.627) (xy 32.893 -63.627) (xy 34.29 -62.23) (xy 34.29 -57.912)
				(xy 33.401 -57.023) (xy 33.401 -53.34) (xy 34.798 -51.943) (xy 34.798 -48.387) (xy 33.909 -47.498)
			)
		)
	)
	(zone
		(layer "F.Cu")
		(hatch none 0.5)
		(connect_pads
			(clearance 0)
		)
		(min_thickness 0.25)
		(keepout
			(tracks not_allowed)
			(vias allowed)
			(pads allowed)
			(copperpour not_allowed)
			(footprints allowed)
		)
		(placement
			(enabled no)
			(sheetname "")
		)
		(fill
			(thermal_gap 0.5)
			(thermal_bridge_width 0.5)
			(island_removal_mode 0)
		)
		(polygon
			(pts
				(arc
					(start 7.502906 -294.736012)
					(mid 6.992366 -294.225472)
					(end 6.481826 -294.736012)
				)
				(xy 6.481826 -294.889428) (xy 6.697472 -294.889428)
				(arc
					(start 6.746748 -294.840152)
					(mid 7.18101 -294.547368)
					(end 6.888226 -294.98163)
				)
				(xy 6.780276 -295.08958) (xy 6.481826 -295.08958) (xy 6.481826 -295.194482) (xy 6.779514 -295.194482)
				(arc
					(start 6.888226 -295.303194)
					(mid 7.18101 -295.737456)
					(end 6.746748 -295.444672)
				)
				(xy 6.69671 -295.394634) (xy 6.481826 -295.394634)
				(arc
					(start 6.481826 -295.548558)
					(mid 6.992239 -296.059352)
					(end 7.502906 -295.548812)
				)
			)
		)
	)
	(zone
		(net "GND")
		(layer "F.Cu")
		(hatch none 0.5)
		(connect_pads
			(clearance 0.5)
		)
		(min_thickness 0.25)
		(fill yes
			(thermal_gap 0.5)
			(thermal_bridge_width 0.5)
			(island_removal_mode 0)
		)
		(polygon
			(pts
				(xy 218.7194 -297.815) (xy 218.44 -298.0944) (xy 218.44 -300.3042) (xy 218.6178 -300.482) (xy 222.631 -300.482)
				(xy 222.885 -300.228) (xy 222.885 -297.942) (xy 222.758 -297.815)
			)
		)
		(polygon
			(pts
				(xy 222.6564 -298.7294) (xy 222.4532 -298.7294) (xy 222.4532 -298.9326) (xy 222.6564 -298.9326)
			)
		)
		(polygon
			(pts
				(xy 221.7928 -298.7294) (xy 221.5896 -298.7294) (xy 221.5896 -298.9326) (xy 221.7928 -298.9326)
			)
		)
	)
	(zone
		(layer "F.Cu")
		(hatch none 0.5)
		(connect_pads
			(clearance 0)
		)
		(min_thickness 0.25)
		(keepout
			(tracks not_allowed)
			(vias allowed)
			(pads allowed)
			(copperpour not_allowed)
			(footprints allowed)
		)
		(placement
			(enabled no)
			(sheetname "")
		)
		(fill
			(thermal_gap 0.5)
			(thermal_bridge_width 0.5)
			(island_removal_mode 0)
		)
		(polygon
			(pts
				(arc
					(start 233.897424 -266.57935)
					(mid 233.386884 -266.06881)
					(end 232.876344 -266.57935)
				)
				(arc
					(start 232.876344 -267.391896)
					(mid 233.386757 -267.90269)
					(end 233.897424 -267.39215)
				)
				(xy 233.897424 -267.238226) (xy 233.682286 -267.238226)
				(arc
					(start 233.632502 -267.28801)
					(mid 233.19824 -267.580794)
					(end 233.491024 -267.146532)
				)
				(xy 233.599482 -267.038074) (xy 233.897424 -267.038074) (xy 233.897424 -266.933172) (xy 233.599228 -266.933172)
				(arc
					(start 233.491024 -266.824968)
					(mid 233.19824 -266.390706)
					(end 233.632502 -266.68349)
				)
				(xy 233.682032 -266.73302) (xy 233.897424 -266.73302)
			)
		)
	)
	(zone
		(layer "F.Cu")
		(hatch none 0.5)
		(connect_pads
			(clearance 0)
		)
		(min_thickness 0.25)
		(keepout
			(tracks allowed)
			(vias allowed)
			(pads allowed)
			(copperpour allowed)
			(footprints allowed)
		)
		(placement
			(enabled no)
			(sheetname "")
		)
		(fill
			(thermal_gap 0.5)
			(thermal_bridge_width 0.5)
			(island_removal_mode 0)
		)
		(polygon
			(pts
				(xy 25.4 -268.0716) (xy 25.4 -268.9352) (xy 24.2062 -268.9352) (xy 24.2062 -268.0716)
			)
		)
	)
	(zone
		(net "GND")
		(layer "F.Cu")
		(hatch none 0.5)
		(connect_pads
			(clearance 0.5)
		)
		(min_thickness 0.25)
		(fill yes
			(thermal_gap 0.5)
			(thermal_bridge_width 0.5)
			(island_removal_mode 0)
		)
		(polygon
			(pts
				(xy 24.6888 -317.246) (xy 24.13 -317.8048) (xy 24.13 -319.151) (xy 24.4856 -319.5066) (xy 25.6286 -319.5066)
				(xy 26.289 -318.8462) (xy 28.702 -318.8462) (xy 28.956 -318.5922) (xy 28.956 -317.6016) (xy 28.6004 -317.246)
			)
		)
		(polygon
			(pts
				(xy 25.4 -317.754) (xy 25.1968 -317.754) (xy 25.1968 -317.9572) (xy 25.4 -317.9572)
			)
		)
		(polygon
			(pts
				(xy 24.7904 -317.754) (xy 24.5872 -317.754) (xy 24.5872 -317.9572) (xy 24.7904 -317.9572)
			)
		)
	)
	(zone
		(layer "F.Cu")
		(hatch none 0.5)
		(connect_pads
			(clearance 0)
		)
		(min_thickness 0.25)
		(keepout
			(tracks allowed)
			(vias allowed)
			(pads allowed)
			(copperpour allowed)
			(footprints allowed)
		)
		(placement
			(enabled no)
			(sheetname "")
		)
		(fill
			(thermal_gap 0.5)
			(thermal_bridge_width 0.5)
			(island_removal_mode 0)
		)
		(polygon
			(pts
				(xy 77.1906 -431.1142) (xy 77.1906 -429.6156) (xy 78.105 -429.6156) (xy 78.105 -431.1142)
			)
		)
	)
	(zone
		(net "GND")
		(layer "F.Cu")
		(hatch none 0.5)
		(connect_pads
			(clearance 0.5)
		)
		(min_thickness 0.25)
		(fill yes
			(thermal_gap 0.5)
			(thermal_bridge_width 0.5)
			(island_removal_mode 0)
		)
		(polygon
			(pts
				(xy 219.202 -400.812) (xy 219.075 -400.939) (xy 219.075 -403.352) (xy 219.583 -403.86) (xy 222.8342 -403.86)
				(xy 223.3422 -403.352) (xy 223.3422 -401.2438) (xy 222.9104 -400.812)
			)
		)
		(polygon
			(pts
				(xy 220.4974 -401.7264) (xy 220.2942 -401.7264) (xy 220.2942 -401.9296) (xy 220.4974 -401.9296)
			)
		)
		(polygon
			(pts
				(xy 219.6338 -401.7264) (xy 219.4306 -401.7264) (xy 219.4306 -401.9296) (xy 219.6338 -401.9296)
			)
		)
	)
	(zone
		(layer "F.Cu")
		(hatch none 0.5)
		(connect_pads
			(clearance 0)
		)
		(min_thickness 0.25)
		(keepout
			(tracks not_allowed)
			(vias allowed)
			(pads allowed)
			(copperpour not_allowed)
			(footprints allowed)
		)
		(placement
			(enabled no)
			(sheetname "")
		)
		(fill
			(thermal_gap 0.5)
			(thermal_bridge_width 0.5)
			(island_removal_mode 0)
		)
		(polygon
			(pts
				(arc
					(start 7.502906 -304.335942)
					(mid 6.992366 -303.825402)
					(end 6.481826 -304.335942)
				)
				(xy 6.481826 -304.489358) (xy 6.697472 -304.489358)
				(arc
					(start 6.746748 -304.440082)
					(mid 7.18101 -304.147298)
					(end 6.888226 -304.58156)
				)
				(xy 6.780276 -304.68951) (xy 6.481826 -304.68951) (xy 6.481826 -304.794412) (xy 6.779514 -304.794412)
				(arc
					(start 6.888226 -304.903124)
					(mid 7.18101 -305.337386)
					(end 6.746748 -305.044602)
				)
				(xy 6.69671 -304.994564) (xy 6.481826 -304.994564)
				(arc
					(start 6.481826 -305.148488)
					(mid 6.992239 -305.659282)
					(end 7.502906 -305.148742)
				)
			)
		)
	)
	(zone
		(layer "F.Cu")
		(hatch none 0.5)
		(connect_pads
			(clearance 0)
		)
		(min_thickness 0.25)
		(keepout
			(tracks not_allowed)
			(vias allowed)
			(pads allowed)
			(copperpour not_allowed)
			(footprints allowed)
		)
		(placement
			(enabled no)
			(sheetname "")
		)
		(fill
			(thermal_gap 0.5)
			(thermal_bridge_width 0.5)
			(island_removal_mode 0)
		)
		(polygon
			(pts
				(arc
					(start 27.18054 -330.003658)
					(mid 26.67 -329.493118)
					(end 26.15946 -330.003658)
				)
				(xy 26.15946 -330.157328) (xy 26.374852 -330.157328)
				(arc
					(start 26.424382 -330.107798)
					(mid 26.858644 -329.815014)
					(end 26.56586 -330.249276)
				)
				(xy 26.457656 -330.35748) (xy 26.15946 -330.35748) (xy 26.15946 -330.462382) (xy 26.457402 -330.462382)
				(arc
					(start 26.56586 -330.57084)
					(mid 26.858644 -331.005102)
					(end 26.424382 -330.712318)
				)
				(xy 26.374598 -330.662534) (xy 26.15946 -330.662534)
				(arc
					(start 26.15946 -330.816204)
					(mid 26.669873 -331.326998)
					(end 27.18054 -330.816458)
				)
			)
		)
	)
	(zone
		(layer "F.Cu")
		(hatch none 0.5)
		(connect_pads
			(clearance 0)
		)
		(min_thickness 0.25)
		(keepout
			(tracks not_allowed)
			(vias allowed)
			(pads allowed)
			(copperpour not_allowed)
			(footprints allowed)
		)
		(placement
			(enabled no)
			(sheetname "")
		)
		(fill
			(thermal_gap 0.5)
			(thermal_bridge_width 0.5)
			(island_removal_mode 0)
		)
		(polygon
			(pts
				(arc
					(start 27.18054 -16.203422)
					(mid 26.67 -15.692882)
					(end 26.15946 -16.203422)
				)
				(xy 26.15946 -16.357092) (xy 26.374852 -16.357092)
				(arc
					(start 26.424382 -16.307562)
					(mid 26.858644 -16.014778)
					(end 26.56586 -16.44904)
				)
				(xy 26.457656 -16.557244) (xy 26.15946 -16.557244) (xy 26.15946 -16.662146) (xy 26.457402 -16.662146)
				(arc
					(start 26.56586 -16.770604)
					(mid 26.858644 -17.204866)
					(end 26.424382 -16.912082)
				)
				(xy 26.374598 -16.862298) (xy 26.15946 -16.862298)
				(arc
					(start 26.15946 -17.015968)
					(mid 26.669873 -17.526762)
					(end 27.18054 -17.016222)
				)
			)
		)
	)
	(zone
		(layer "F.Cu")
		(hatch none 0.5)
		(connect_pads
			(clearance 0)
		)
		(min_thickness 0.25)
		(keepout
			(tracks not_allowed)
			(vias allowed)
			(pads allowed)
			(copperpour not_allowed)
			(footprints allowed)
		)
		(placement
			(enabled no)
			(sheetname "")
		)
		(fill
			(thermal_gap 0.5)
			(thermal_bridge_width 0.5)
			(island_removal_mode 0)
		)
		(polygon
			(pts
				(arc
					(start 37.33927 -481.631244)
					(mid 36.72713 -481.019104)
					(end 36.11499 -481.631244)
				)
				(arc
					(start 36.11499 -482.74859)
					(mid 36.727003 -483.360984)
					(end 37.33927 -482.748844)
				)
				(xy 37.33927 -482.442774) (xy 37.174678 -482.442774)
				(arc
					(start 36.972748 -482.644704)
					(mid 36.538486 -482.937488)
					(end 36.83127 -482.503226)
				)
				(xy 37.091874 -482.242622) (xy 37.33927 -482.242622) (xy 37.33927 -482.13772) (xy 37.092128 -482.13772)
				(arc
					(start 36.83127 -481.876862)
					(mid 36.538486 -481.4426)
					(end 36.972748 -481.735384)
				)
				(xy 37.174932 -481.937568) (xy 37.33927 -481.937568)
			)
		)
	)
	(zone
		(layer "F.Cu")
		(hatch none 0.5)
		(connect_pads
			(clearance 0)
		)
		(min_thickness 0.25)
		(keepout
			(tracks not_allowed)
			(vias allowed)
			(pads allowed)
			(copperpour not_allowed)
			(footprints allowed)
		)
		(placement
			(enabled no)
			(sheetname "")
		)
		(fill
			(thermal_gap 0.5)
			(thermal_bridge_width 0.5)
			(island_removal_mode 0)
		)
		(polygon
			(pts
				(arc
					(start 222.339154 -275.631402)
					(mid 221.727141 -275.019008)
					(end 221.114874 -275.631148)
				)
				(arc
					(start 221.114874 -276.748748)
					(mid 221.727014 -277.360888)
					(end 222.339154 -276.748748)
				)
				(xy 222.339154 -276.442678) (xy 222.174562 -276.442678)
				(arc
					(start 221.972632 -276.644608)
					(mid 221.53837 -276.937392)
					(end 221.831154 -276.50313)
				)
				(xy 222.091758 -276.242526) (xy 222.339154 -276.242526) (xy 222.339154 -276.137624) (xy 222.092012 -276.137624)
				(arc
					(start 221.831154 -275.876766)
					(mid 221.53837 -275.442504)
					(end 221.972632 -275.735288)
				)
				(xy 222.174816 -275.937472) (xy 222.339154 -275.937472)
			)
		)
	)
	(zone
		(layer "F.Cu")
		(hatch none 0.5)
		(connect_pads
			(clearance 0)
		)
		(min_thickness 0.25)
		(keepout
			(tracks not_allowed)
			(vias allowed)
			(pads allowed)
			(copperpour not_allowed)
			(footprints allowed)
		)
		(placement
			(enabled no)
			(sheetname "")
		)
		(fill
			(thermal_gap 0.5)
			(thermal_bridge_width 0.5)
			(island_removal_mode 0)
		)
		(polygon
			(pts
				(arc
					(start 7.502906 -184.736232)
					(mid 6.992493 -184.225438)
					(end 6.481826 -184.735978)
				)
				(xy 6.481826 -184.889394) (xy 6.697472 -184.889394)
				(arc
					(start 6.746748 -184.840118)
					(mid 7.18101 -184.547334)
					(end 6.888226 -184.981596)
				)
				(xy 6.780276 -185.089546) (xy 6.481826 -185.089546) (xy 6.481826 -185.194448) (xy 6.779514 -185.194448)
				(arc
					(start 6.888226 -185.30316)
					(mid 7.18101 -185.737422)
					(end 6.746748 -185.444638)
				)
				(xy 6.69671 -185.3946) (xy 6.481826 -185.3946)
				(arc
					(start 6.481826 -185.548778)
					(mid 6.992366 -186.059318)
					(end 7.502906 -185.548778)
				)
			)
		)
	)
	(zone
		(layer "F.Cu")
		(hatch none 0.5)
		(connect_pads
			(clearance 0)
		)
		(min_thickness 0.25)
		(keepout
			(tracks allowed)
			(vias allowed)
			(pads allowed)
			(copperpour allowed)
			(footprints allowed)
		)
		(placement
			(enabled no)
			(sheetname "")
		)
		(fill
			(thermal_gap 0.5)
			(thermal_bridge_width 0.5)
			(island_removal_mode 0)
		)
		(polygon
			(pts
				(xy 222.377 -264.922) (xy 222.377 -257.81) (xy 224.536 -257.81) (xy 224.536 -264.922)
			)
		)
	)
	(zone
		(layer "F.Cu")
		(hatch none 0.5)
		(connect_pads
			(clearance 0)
		)
		(min_thickness 0.25)
		(keepout
			(tracks not_allowed)
			(vias allowed)
			(pads allowed)
			(copperpour not_allowed)
			(footprints allowed)
		)
		(placement
			(enabled no)
			(sheetname "")
		)
		(fill
			(thermal_gap 0.5)
			(thermal_bridge_width 0.5)
			(island_removal_mode 0)
		)
		(polygon
			(pts
				(arc
					(start 48.89754 -266.579604)
					(mid 48.387127 -266.06881)
					(end 47.87646 -266.57935)
				)
				(arc
					(start 47.87646 -267.39215)
					(mid 48.387 -267.90269)
					(end 48.89754 -267.39215)
				)
				(xy 48.89754 -267.238226) (xy 48.682402 -267.238226)
				(arc
					(start 48.632618 -267.28801)
					(mid 48.198356 -267.580794)
					(end 48.49114 -267.146532)
				)
				(xy 48.599598 -267.038074) (xy 48.89754 -267.038074) (xy 48.89754 -266.933172) (xy 48.599344 -266.933172)
				(arc
					(start 48.49114 -266.824968)
					(mid 48.198356 -266.390706)
					(end 48.632618 -266.68349)
				)
				(xy 48.682148 -266.73302) (xy 48.89754 -266.73302)
			)
		)
	)
	(zone
		(layer "F.Cu")
		(hatch none 0.5)
		(connect_pads
			(clearance 0)
		)
		(min_thickness 0.25)
		(keepout
			(tracks not_allowed)
			(vias allowed)
			(pads allowed)
			(copperpour not_allowed)
			(footprints allowed)
		)
		(placement
			(enabled no)
			(sheetname "")
		)
		(fill
			(thermal_gap 0.5)
			(thermal_bridge_width 0.5)
			(island_removal_mode 0)
		)
		(polygon
			(pts
				(arc
					(start 27.18054 -244.603524)
					(mid 26.67 -244.092984)
					(end 26.15946 -244.603524)
				)
				(xy 26.15946 -244.757194) (xy 26.374852 -244.757194)
				(arc
					(start 26.424382 -244.707664)
					(mid 26.858644 -244.41488)
					(end 26.56586 -244.849142)
				)
				(xy 26.457656 -244.957346) (xy 26.15946 -244.957346) (xy 26.15946 -245.062248) (xy 26.457402 -245.062248)
				(arc
					(start 26.56586 -245.170706)
					(mid 26.858644 -245.604968)
					(end 26.424382 -245.312184)
				)
				(xy 26.374598 -245.2624) (xy 26.15946 -245.2624)
				(arc
					(start 26.15946 -245.41607)
					(mid 26.669873 -245.926864)
					(end 27.18054 -245.416324)
				)
			)
		)
	)
	(zone
		(layer "F.Cu")
		(hatch none 0.5)
		(connect_pads
			(clearance 0)
		)
		(min_thickness 0.25)
		(keepout
			(tracks not_allowed)
			(vias allowed)
			(pads allowed)
			(copperpour not_allowed)
			(footprints allowed)
		)
		(placement
			(enabled no)
			(sheetname "")
		)
		(fill
			(thermal_gap 0.5)
			(thermal_bridge_width 0.5)
			(island_removal_mode 0)
		)
		(polygon
			(pts
				(xy 94.89567 -205.81239) (xy 95.06458 -205.81239) (xy 95.06458 -206.98079) (xy 94.89567 -206.98079)
			)
		)
	)
	(zone
		(layer "F.Cu")
		(hatch none 0.5)
		(connect_pads
			(clearance 0)
		)
		(min_thickness 0.25)
		(keepout
			(tracks allowed)
			(vias allowed)
			(pads allowed)
			(copperpour allowed)
			(footprints allowed)
		)
		(placement
			(enabled no)
			(sheetname "")
		)
		(fill
			(thermal_gap 0.5)
			(thermal_bridge_width 0.5)
			(island_removal_mode 0)
		)
		(polygon
			(pts
				(xy 91.821 -26.416) (xy 91.821 -28.067) (xy 89.916 -28.067) (xy 89.916 -26.416)
			)
		)
	)
	(zone
		(layer "F.Cu")
		(hatch none 0.5)
		(connect_pads
			(clearance 0)
		)
		(min_thickness 0.25)
		(keepout
			(tracks not_allowed)
			(vias allowed)
			(pads allowed)
			(copperpour not_allowed)
			(footprints allowed)
		)
		(placement
			(enabled no)
			(sheetname "")
		)
		(fill
			(thermal_gap 0.5)
			(thermal_bridge_width 0.5)
			(island_removal_mode 0)
		)
		(polygon
			(pts
				(arc
					(start 25.88514 -327.451212)
					(mid 25.273 -326.839072)
					(end 24.66086 -327.451212)
				)
				(xy 24.66086 -327.74509) (xy 24.837644 -327.74509)
				(arc
					(start 25.027382 -327.555352)
					(mid 25.461644 -327.262568)
					(end 25.16886 -327.69683)
				)
				(xy 24.920448 -327.945242) (xy 24.66086 -327.945242) (xy 24.66086 -328.050144) (xy 24.89581 -328.050144)
				(arc
					(start 25.16886 -328.323194)
					(mid 25.461644 -328.757456)
					(end 25.027382 -328.464672)
				)
				(xy 24.813006 -328.250296) (xy 24.66086 -328.250296)
				(arc
					(start 24.66086 -328.568558)
					(mid 25.272873 -329.180952)
					(end 25.88514 -328.568812)
				)
			)
		)
	)
	(zone
		(layer "F.Cu")
		(hatch none 0.5)
		(connect_pads
			(clearance 0)
		)
		(min_thickness 0.25)
		(keepout
			(tracks allowed)
			(vias allowed)
			(pads allowed)
			(copperpour allowed)
			(footprints allowed)
		)
		(placement
			(enabled no)
			(sheetname "")
		)
		(fill
			(thermal_gap 0.5)
			(thermal_bridge_width 0.5)
			(island_removal_mode 0)
		)
		(polygon
			(pts
				(xy 87.63 -214.757) (xy 87.63 -210.693) (xy 83.439 -210.693) (xy 83.439 -209.931) (xy 88.011 -209.931)
				(xy 88.011 -206.883) (xy 89.916 -206.883) (xy 89.916 -214.757)
			)
		)
	)
	(zone
		(layer "F.Cu")
		(hatch none 0.5)
		(connect_pads
			(clearance 0)
		)
		(min_thickness 0.25)
		(keepout
			(tracks not_allowed)
			(vias allowed)
			(pads allowed)
			(copperpour not_allowed)
			(footprints allowed)
		)
		(placement
			(enabled no)
			(sheetname "")
		)
		(fill
			(thermal_gap 0.5)
			(thermal_bridge_width 0.5)
			(island_removal_mode 0)
		)
		(polygon
			(pts
				(arc
					(start 35.84067 -179.983892)
					(mid 35.330257 -179.473098)
					(end 34.81959 -179.983638)
				)
				(arc
					(start 34.81959 -180.796438)
					(mid 35.33013 -181.306978)
					(end 35.84067 -180.796438)
				)
				(xy 35.84067 -180.642768) (xy 35.625278 -180.642768)
				(arc
					(start 35.575748 -180.692298)
					(mid 35.141486 -180.985082)
					(end 35.43427 -180.55082)
				)
				(xy 35.542474 -180.442616) (xy 35.84067 -180.442616) (xy 35.84067 -180.337714) (xy 35.542728 -180.337714)
				(arc
					(start 35.43427 -180.229256)
					(mid 35.141486 -179.794994)
					(end 35.575748 -180.087778)
				)
				(xy 35.625532 -180.137562) (xy 35.84067 -180.137562)
			)
		)
	)
	(zone
		(layer "F.Cu")
		(hatch none 0.5)
		(connect_pads
			(clearance 0)
		)
		(min_thickness 0.25)
		(keepout
			(tracks allowed)
			(vias allowed)
			(pads allowed)
			(copperpour allowed)
			(footprints allowed)
		)
		(placement
			(enabled no)
			(sheetname "")
		)
		(fill
			(thermal_gap 0.5)
			(thermal_bridge_width 0.5)
			(island_removal_mode 0)
		)
		(polygon
			(pts
				(xy 96.393 -109.474) (xy 95.123 -108.204) (xy 92.075 -108.204) (xy 90.805 -109.474) (xy 86.614 -109.474)
				(xy 86.614 -108.966) (xy 87.63 -107.95) (xy 88.9 -107.95) (xy 90.043 -106.807) (xy 90.043 -105.664)
				(xy 97.917 -105.664) (xy 97.917 -107.315) (xy 98.552 -107.95) (xy 99.441 -107.95) (xy 100.711 -109.22)
				(xy 100.711 -109.474)
			)
		)
	)
	(zone
		(layer "F.Cu")
		(hatch none 0.5)
		(connect_pads
			(clearance 0)
		)
		(min_thickness 0.25)
		(keepout
			(tracks not_allowed)
			(vias allowed)
			(pads allowed)
			(copperpour not_allowed)
			(footprints allowed)
		)
		(placement
			(enabled no)
			(sheetname "")
		)
		(fill
			(thermal_gap 0.5)
			(thermal_bridge_width 0.5)
			(island_removal_mode 0)
		)
		(polygon
			(pts
				(arc
					(start 35.84067 -170.383962)
					(mid 35.330257 -169.873168)
					(end 34.81959 -170.383708)
				)
				(arc
					(start 34.81959 -171.196508)
					(mid 35.33013 -171.707048)
					(end 35.84067 -171.196508)
				)
				(xy 35.84067 -171.042584) (xy 35.625532 -171.042584)
				(arc
					(start 35.575748 -171.092368)
					(mid 35.141486 -171.385152)
					(end 35.43427 -170.95089)
				)
				(xy 35.542728 -170.842432) (xy 35.84067 -170.842432) (xy 35.84067 -170.73753) (xy 35.542474 -170.73753)
				(arc
					(start 35.43427 -170.629326)
					(mid 35.141486 -170.195064)
					(end 35.575748 -170.487848)
				)
				(xy 35.625278 -170.537378) (xy 35.84067 -170.537378)
			)
		)
	)
	(zone
		(net "VDD_DIFF_4")
		(layer "F.Cu")
		(hatch none 0.5)
		(connect_pads
			(clearance 0.5)
		)
		(min_thickness 0.25)
		(fill yes
			(thermal_gap 0.5)
			(thermal_bridge_width 0.5)
			(island_removal_mode 0)
		)
		(polygon
			(pts
				(xy 79.4766 -101.981) (xy 79.121762 -102.335838) (xy 78.308962 -102.335838) (xy 78.2574 -102.3874)
				(xy 78.2574 -103.8606) (xy 79.2226 -104.8258) (xy 79.2226 -108.6104) (xy 79.4512 -108.839) (xy 82.4992 -108.839)
				(xy 82.7786 -108.5596) (xy 82.7786 -105.6386) (xy 82.6516 -105.5116) (xy 81.4578 -105.5116) (xy 81.0768 -105.1306)
				(xy 81.0768 -104.648) (xy 81.5086 -104.2162) (xy 82.7024 -104.2162) (xy 82.7786 -104.14) (xy 82.7786 -102.3112)
				(xy 82.4484 -101.981)
			)
		)
		(polygon
			(pts
				(xy 82.3214 -108.1278) (xy 82.1182 -108.1278) (xy 82.1182 -108.331) (xy 82.3214 -108.331)
			)
		)
		(polygon
			(pts
				(xy 82.3214 -107.569) (xy 82.1182 -107.569) (xy 82.1182 -107.7722) (xy 82.3214 -107.7722)
			)
		)
		(polygon
			(pts
				(xy 82.3214 -107.1118) (xy 82.1182 -107.1118) (xy 82.1182 -107.315) (xy 82.3214 -107.315)
			)
		)
		(polygon
			(pts
				(xy 82.3214 -106.553) (xy 82.1182 -106.553) (xy 82.1182 -106.7562) (xy 82.3214 -106.7562)
			)
		)
		(polygon
			(pts
				(xy 82.3214 -106.0958) (xy 82.1182 -106.0958) (xy 82.1182 -106.299) (xy 82.3214 -106.299)
			)
		)
		(polygon
			(pts
				(xy 80.2132 -106.045) (xy 80.01 -106.045) (xy 80.01 -106.2482) (xy 80.2132 -106.2482)
			)
		)
		(polygon
			(pts
				(xy 80.2132 -105.1814) (xy 80.01 -105.1814) (xy 80.01 -105.3846) (xy 80.2132 -105.3846)
			)
		)
		(polygon
			(pts
				(xy 82.3214 -103.378) (xy 82.1182 -103.378) (xy 82.1182 -103.5812) (xy 82.3214 -103.5812)
			)
		)
		(polygon
			(pts
				(xy 82.3214 -102.8954) (xy 82.1182 -102.8954) (xy 82.1182 -103.0986) (xy 82.3214 -103.0986)
			)
		)
		(polygon
			(pts
				(xy 78.9432 -102.7938) (xy 78.74 -102.7938) (xy 78.74 -102.997) (xy 78.9432 -102.997)
			)
		)
		(polygon
			(pts
				(xy 82.3214 -102.3366) (xy 82.1182 -102.3366) (xy 82.1182 -102.5398) (xy 82.3214 -102.5398)
			)
		)
	)
	(zone
		(layer "F.Cu")
		(hatch none 0.5)
		(connect_pads
			(clearance 0)
		)
		(min_thickness 0.25)
		(keepout
			(tracks allowed)
			(vias allowed)
			(pads allowed)
			(copperpour allowed)
			(footprints allowed)
		)
		(placement
			(enabled no)
			(sheetname "")
		)
		(fill
			(thermal_gap 0.5)
			(thermal_bridge_width 0.5)
			(island_removal_mode 0)
		)
		(polygon
			(pts
				(xy 74.676 -145.796) (xy 77.724 -145.796) (xy 77.724 -147.32) (xy 74.676 -147.32)
			)
		)
	)
	(zone
		(layer "F.Cu")
		(hatch none 0.5)
		(connect_pads
			(clearance 0)
		)
		(min_thickness 0.25)
		(keepout
			(tracks not_allowed)
			(vias allowed)
			(pads allowed)
			(copperpour not_allowed)
			(footprints allowed)
		)
		(placement
			(enabled no)
			(sheetname "")
		)
		(fill
			(thermal_gap 0.5)
			(thermal_bridge_width 0.5)
			(island_removal_mode 0)
		)
		(polygon
			(pts
				(arc
					(start 7.502906 -427.984412)
					(mid 6.992493 -427.473618)
					(end 6.481826 -427.984158)
				)
				(xy 6.481826 -428.11827) (xy 6.716776 -428.11827)
				(arc
					(start 6.746748 -428.088298)
					(mid 7.18101 -427.795514)
					(end 6.888226 -428.229776)
				)
				(xy 6.79958 -428.318422) (xy 6.481826 -428.318422) (xy 6.481826 -428.423324) (xy 6.76021 -428.423324)
				(arc
					(start 6.888226 -428.55134)
					(mid 7.18101 -428.985602)
					(end 6.746748 -428.692818)
				)
				(xy 6.677406 -428.623476) (xy 6.481826 -428.623476)
				(arc
					(start 6.481826 -428.796958)
					(mid 6.992366 -429.307498)
					(end 7.502906 -428.796958)
				)
			)
		)
	)
	(zone
		(net "P12V_SSD4")
		(layer "F.Cu")
		(hatch none 0.5)
		(connect_pads
			(clearance 0.5)
		)
		(min_thickness 0.25)
		(fill yes
			(thermal_gap 0.5)
			(thermal_bridge_width 0.5)
			(island_removal_mode 0)
		)
		(polygon
			(pts
				(xy 225.918776 -81.726786) (xy 225.806 -81.839562) (xy 225.806 -83.693) (xy 225.5012 -83.9978) (xy 224.9678 -83.9978)
				(xy 222.8342 -86.1314) (xy 218.186 -86.1314) (xy 217.9955 -86.3219) (xy 216.5223 -86.3219) (xy 216.154 -86.6902)
				(xy 216.154 -91.1352) (xy 216.408 -91.3892) (xy 222.9612 -91.3892) (xy 223.5454 -91.9734) (xy 223.5454 -95.9612)
				(xy 223.8502 -96.266) (xy 227.7618 -96.266) (xy 228.219 -95.8088) (xy 228.219 -91.44) (xy 226.822 -90.043)
				(xy 226.822 -89.154) (xy 228.473 -87.503) (xy 228.473 -81.831688) (xy 228.368098 -81.726786)
			)
		)
		(polygon
			(pts
				(xy 226.6696 -94.9198) (xy 226.4664 -94.9198) (xy 226.4664 -95.123) (xy 226.6696 -95.123)
			)
		)
		(polygon
			(pts
				(xy 225.5266 -94.9198) (xy 225.3234 -94.9198) (xy 225.3234 -95.123) (xy 225.5266 -95.123)
			)
		)
		(polygon
			(pts
				(xy 226.6696 -92.1258) (xy 226.4664 -92.1258) (xy 226.4664 -92.329) (xy 226.6696 -92.329)
			)
		)
		(polygon
			(pts
				(xy 225.5266 -92.1258) (xy 225.3234 -92.1258) (xy 225.3234 -92.329) (xy 225.5266 -92.329)
			)
		)
		(polygon
			(pts
				(xy 220.3704 -91.059) (xy 220.1672 -91.059) (xy 220.1672 -91.2622) (xy 220.3704 -91.2622)
			)
		)
		(polygon
			(pts
				(xy 219.5068 -91.059) (xy 219.3036 -91.059) (xy 219.3036 -91.2622) (xy 219.5068 -91.2622)
			)
		)
		(polygon
			(pts
				(xy 220.3704 -90.1954) (xy 220.1672 -90.1954) (xy 220.1672 -90.3986) (xy 220.3704 -90.3986)
			)
		)
		(polygon
			(pts
				(xy 219.5068 -90.1954) (xy 219.3036 -90.1954) (xy 219.3036 -90.3986) (xy 219.5068 -90.3986)
			)
		)
		(polygon
			(pts
				(xy 222.4532 -86.6394) (xy 222.25 -86.6394) (xy 222.25 -86.8426) (xy 222.4532 -86.8426)
			)
		)
		(polygon
			(pts
				(xy 221.8436 -86.6394) (xy 221.6404 -86.6394) (xy 221.6404 -86.8426) (xy 221.8436 -86.8426)
			)
		)
	)
	(zone
		(layer "F.Cu")
		(hatch none 0.5)
		(connect_pads
			(clearance 0)
		)
		(min_thickness 0.25)
		(keepout
			(tracks not_allowed)
			(vias allowed)
			(pads allowed)
			(copperpour not_allowed)
			(footprints allowed)
		)
		(placement
			(enabled no)
			(sheetname "")
		)
		(fill
			(thermal_gap 0.5)
			(thermal_bridge_width 0.5)
			(island_removal_mode 0)
		)
		(polygon
			(pts
				(arc
					(start 222.339154 -491.231682)
					(mid 221.727141 -490.619288)
					(end 221.114874 -491.231428)
				)
				(arc
					(start 221.114874 -492.349028)
					(mid 221.727014 -492.961168)
					(end 222.339154 -492.349028)
				)
				(xy 222.339154 -492.042704) (xy 222.174816 -492.042704)
				(arc
					(start 221.972632 -492.244888)
					(mid 221.53837 -492.537672)
					(end 221.831154 -492.10341)
				)
				(xy 222.092012 -491.842552) (xy 222.339154 -491.842552) (xy 222.339154 -491.73765) (xy 222.091758 -491.73765)
				(arc
					(start 221.831154 -491.477046)
					(mid 221.53837 -491.042784)
					(end 221.972632 -491.335568)
				)
				(xy 222.174562 -491.537498) (xy 222.339154 -491.537498)
			)
		)
	)
	(zone
		(layer "F.Cu")
		(hatch none 0.5)
		(connect_pads
			(clearance 0)
		)
		(min_thickness 0.25)
		(keepout
			(tracks not_allowed)
			(vias allowed)
			(pads allowed)
			(copperpour not_allowed)
			(footprints allowed)
		)
		(placement
			(enabled no)
			(sheetname "")
		)
		(fill
			(thermal_gap 0.5)
			(thermal_bridge_width 0.5)
			(island_removal_mode 0)
		)
		(polygon
			(pts
				(arc
					(start 35.84067 -76.983844)
					(mid 35.330257 -76.47305)
					(end 34.81959 -76.98359)
				)
				(arc
					(start 34.81959 -77.79639)
					(mid 35.33013 -78.30693)
					(end 35.84067 -77.79639)
				)
				(xy 35.84067 -77.64272) (xy 35.625278 -77.64272)
				(arc
					(start 35.575748 -77.69225)
					(mid 35.141486 -77.985034)
					(end 35.43427 -77.550772)
				)
				(xy 35.542474 -77.442568) (xy 35.84067 -77.442568) (xy 35.84067 -77.337666) (xy 35.542728 -77.337666)
				(arc
					(start 35.43427 -77.229208)
					(mid 35.141486 -76.794946)
					(end 35.575748 -77.08773)
				)
				(xy 35.625532 -77.137514) (xy 35.84067 -77.137514)
			)
		)
	)
	(zone
		(layer "F.Cu")
		(hatch none 0.5)
		(connect_pads
			(clearance 0)
		)
		(min_thickness 0.25)
		(keepout
			(tracks allowed)
			(vias allowed)
			(pads allowed)
			(copperpour allowed)
			(footprints allowed)
		)
		(placement
			(enabled no)
			(sheetname "")
		)
		(fill
			(thermal_gap 0.5)
			(thermal_bridge_width 0.5)
			(island_removal_mode 0)
		)
		(polygon
			(pts
				(xy 37.338 -82.931) (xy 37.338 -66.294) (xy 39.497 -66.294) (xy 39.497 -82.931)
			)
		)
	)
	(zone
		(net "GND")
		(layer "F.Cu")
		(hatch none 0.5)
		(connect_pads
			(clearance 0.5)
		)
		(min_thickness 0.25)
		(fill yes
			(thermal_gap 0.5)
			(thermal_bridge_width 0.5)
			(island_removal_mode 0)
		)
		(polygon
			(pts
				(xy 221.879414 -423.165778) (xy 221.700598 -423.344594) (xy 221.700598 -428.428658) (xy 222.18396 -428.91202)
				(xy 224.058988 -428.91202) (xy 224.155 -428.816008) (xy 224.155 -423.343832) (xy 223.976946 -423.165778)
			)
		)
	)
	(zone
		(net "P12V_SSD11")
		(layer "F.Cu")
		(hatch none 0.5)
		(connect_pads
			(clearance 0.5)
		)
		(min_thickness 0.25)
		(fill yes
			(thermal_gap 0.5)
			(thermal_bridge_width 0.5)
			(island_removal_mode 0)
		)
		(polygon
			(pts
				(xy 19.9898 -306.6034) (xy 19.431 -307.1622) (xy 19.431 -312.166) (xy 20.193 -312.928) (xy 20.193 -313.817)
				(xy 18.4658 -315.5442) (xy 18.4658 -321.047618) (xy 18.669508 -321.251326) (xy 21.104352 -321.251326)
				(xy 21.209 -321.146678) (xy 21.209 -319.278) (xy 21.463 -319.024) (xy 22.4028 -319.024) (xy 24.4856 -316.9412)
				(xy 30.3784 -316.9412) (xy 30.6578 -316.6618) (xy 30.6578 -311.785) (xy 30.5816 -311.7088) (xy 24.003 -311.7088)
				(xy 23.693628 -311.399428) (xy 23.693628 -307.030628) (xy 23.2664 -306.6034)
			)
		)
		(polygon
			(pts
				(xy 25.4 -316.23) (xy 25.1968 -316.23) (xy 25.1968 -316.4332) (xy 25.4 -316.4332)
			)
		)
		(polygon
			(pts
				(xy 24.7904 -316.23) (xy 24.5872 -316.23) (xy 24.5872 -316.4332) (xy 24.7904 -316.4332)
			)
		)
		(polygon
			(pts
				(xy 25.3238 -312.547) (xy 25.1206 -312.547) (xy 25.1206 -312.7502) (xy 25.3238 -312.7502)
			)
		)
		(polygon
			(pts
				(xy 24.4602 -312.547) (xy 24.257 -312.547) (xy 24.257 -312.7502) (xy 24.4602 -312.7502)
			)
		)
		(polygon
			(pts
				(xy 22.6822 -310.8452) (xy 22.479 -310.8452) (xy 22.479 -311.0484) (xy 22.6822 -311.0484)
			)
		)
		(polygon
			(pts
				(xy 21.5392 -310.8452) (xy 21.336 -310.8452) (xy 21.336 -311.0484) (xy 21.5392 -311.0484)
			)
		)
		(polygon
			(pts
				(xy 22.6822 -308.0512) (xy 22.479 -308.0512) (xy 22.479 -308.2544) (xy 22.6822 -308.2544)
			)
		)
	)
	(zone
		(layer "F.Cu")
		(hatch none 0.5)
		(connect_pads
			(clearance 0)
		)
		(min_thickness 0.25)
		(keepout
			(tracks allowed)
			(vias allowed)
			(pads allowed)
			(copperpour allowed)
			(footprints not_allowed)
		)
		(placement
			(enabled no)
			(sheetname "")
		)
		(fill
			(thermal_gap 0.5)
			(thermal_bridge_width 0.5)
			(island_removal_mode 0)
		)
		(polygon
			(pts
				(arc
					(start 0.999998 -506.000004)
					(mid 0.292893 -505.707111)
					(end 0 -505.000006)
				)
				(xy 0 -422.042082) (xy 0.500126 -421.541956)
				(arc
					(start 4.299966 -421.541956)
					(mid 5.499862 -420.34206)
					(end 4.299966 -419.14191)
				)
				(xy 0.500126 -419.14191) (xy 0 -418.642038) (xy 0 -316.04204) (xy 0.500126 -315.541914)
				(arc
					(start 4.299966 -315.541914)
					(mid 5.499862 -314.342018)
					(end 4.299966 -313.142122)
				)
				(xy 0.500126 -313.142122) (xy 0 -312.641996) (xy 0 -190.042038) (xy 0.500126 -189.541912)
				(arc
					(start 4.299966 -189.541912)
					(mid 5.499862 -188.342016)
					(end 4.299966 -187.14212)
				)
				(xy 0.500126 -187.14212) (xy 0 -186.641994) (xy 0 -31.24835) (xy 25.999948 -31.24835) (xy 25.999948 -51.32832)
				(xy 16.999966 -51.32832) (xy 16.999966 -67.168268) (xy 36.049458 -67.168268) (xy 36.049458 -42.66819)
				(xy 44.99991 -42.66819) (xy 44.99991 -10.668254) (xy 25.999948 -10.668254) (xy 25.999948 -30.748224)
				(xy 0 -30.748224)
				(arc
					(start 0 -0.999998)
					(mid 0.292893 -0.292893)
					(end 0.999998 0)
				)
				(xy 218.74988 0) (xy 218.74988 -8.670036) (xy 210.455256 -8.670036) (xy 210.455256 -67.170046) (xy 220.495368 -67.170046)
				(xy 220.495368 -41.800018) (xy 230.15829 -41.800018) (xy 230.15829 -8.670036) (xy 219.250006 -8.670036)
				(xy 219.250006 0)
				(arc
					(start 262.50011 0)
					(mid 263.207215 -0.292893)
					(end 263.500108 -0.999998)
				)
				(xy 263.500108 -361.920028) (xy 262.50011 -362.920026)
				(arc
					(start 261.290054 -362.920026)
					(mid 260.307165 -363.327099)
					(end 259.899912 -364.309914)
				)
				(xy 259.899912 -408.414982) (xy 258.899914 -409.41498)
				(arc
					(start 252.394974 -409.41498)
					(mid 251.859796 -409.950158)
					(end 252.394974 -410.485082)
				)
				(xy 258.899914 -410.485082) (xy 259.899912 -411.48508)
				(arc
					(start 259.899912 -425.69003)
					(mid 260.307091 -426.672919)
					(end 261.290054 -427.079918)
				)
				(xy 262.50011 -427.079918) (xy 263.500108 -428.079916) (xy 263.500108 -436.919878) (xy 223.089978 -436.919878)
				(xy 223.089978 -432.170078) (xy 213.089998 -432.170078) (xy 213.089998 -442.170058) (xy 223.089978 -442.170058)
				(xy 223.089978 -437.420004) (xy 263.500108 -437.420004)
				(arc
					(start 263.500108 -505.000006)
					(mid 263.207215 -505.707111)
					(end 262.50011 -506.000004)
				)
				(xy 26.75001 -506.000004) (xy 26.75001 -503.670062) (xy 36.500054 -503.670062) (xy 36.500054 -447.170048)
				(xy 26.500074 -447.170048) (xy 26.500074 -467.460076) (xy 16.999966 -467.460076) (xy 16.999966 -503.670062)
				(xy 26.249884 -503.670062) (xy 26.249884 -506.000004)
			)
		)
	)
	(zone
		(net "GND")
		(layer "F.Cu")
		(hatch none 0.5)
		(connect_pads
			(clearance 0.5)
		)
		(min_thickness 0.25)
		(fill yes
			(thermal_gap 0.5)
			(thermal_bridge_width 0.5)
			(island_removal_mode 0)
		)
		(polygon
			(pts
				(xy 92.837 -439.4454) (xy 92.4306 -439.8518) (xy 92.4306 -440.9186) (xy 92.9132 -441.4012) (xy 94.4118 -441.4012)
				(xy 94.996 -440.817) (xy 94.996 -439.547) (xy 94.8944 -439.4454)
			)
		)
		(polygon
			(pts
				(xy 94.4118 -439.9534) (xy 93.9292 -439.9534) (xy 93.9292 -440.1566) (xy 94.4118 -440.1566)
			)
		)
		(polygon
			(pts
				(xy 93.5228 -439.9534) (xy 93.3196 -439.9534) (xy 93.3196 -440.1566) (xy 93.5228 -440.1566)
			)
		)
	)
	(zone
		(net "GND")
		(layer "F.Cu")
		(hatch none 0.5)
		(connect_pads
			(clearance 0.5)
		)
		(min_thickness 0.25)
		(fill yes
			(thermal_gap 0.5)
			(thermal_bridge_width 0.5)
			(island_removal_mode 0)
		)
		(polygon
			(pts
				(xy 219.296996 -194.660774) (xy 219.085414 -194.872356) (xy 219.085414 -197.241414) (xy 219.329 -197.485)
				(xy 222.8596 -197.485) (xy 223.2406 -197.104) (xy 223.2406 -194.9196) (xy 222.981774 -194.660774)
			)
		)
		(polygon
			(pts
				(xy 220.2434 -195.58) (xy 220.0402 -195.58) (xy 220.0402 -195.7832) (xy 220.2434 -195.7832)
			)
		)
	)
	(zone
		(net "GND")
		(layer "F.Cu")
		(hatch none 0.5)
		(connect_pads
			(clearance 0.5)
		)
		(min_thickness 0.25)
		(fill yes
			(thermal_gap 0.5)
			(thermal_bridge_width 0.5)
			(island_removal_mode 0)
		)
		(polygon
			(pts
				(xy 53.34 -417.957) (xy 37.592 -433.705) (xy 37.592 -437.314594) (xy 40.078406 -439.801) (xy 41.656 -439.801)
				(xy 51.435 -430.022) (xy 76.6318 -430.022) (xy 76.80071 -430.19091) (xy 78.01229 -430.19091) (xy 78.0796 -430.1236)
				(xy 78.0796 -428.5742) (xy 83.1088 -423.545) (xy 84.836 -423.545) (xy 85.344 -423.037) (xy 85.344 -418.973)
				(xy 84.328 -417.957)
			)
		)
		(polygon
			(pts
				(xy 77.597 -429.5267) (xy 77.3938 -429.5267) (xy 77.3938 -429.7299) (xy 77.597 -429.7299)
			)
		)
	)
	(zone
		(layer "F.Cu")
		(hatch none 0.5)
		(connect_pads
			(clearance 0)
		)
		(min_thickness 0.25)
		(keepout
			(tracks not_allowed)
			(vias allowed)
			(pads allowed)
			(copperpour not_allowed)
			(footprints allowed)
		)
		(placement
			(enabled no)
			(sheetname "")
		)
		(fill
			(thermal_gap 0.5)
			(thermal_bridge_width 0.5)
			(island_removal_mode 0)
		)
		(polygon
			(pts
				(arc
					(start 27.18054 -433.00396)
					(mid 26.670127 -432.493166)
					(end 26.15946 -433.003706)
				)
				(xy 26.15946 -433.182776) (xy 26.349452 -433.182776)
				(arc
					(start 26.424382 -433.107846)
					(mid 26.858644 -432.815062)
					(end 26.56586 -433.249324)
				)
				(xy 26.432256 -433.382928) (xy 26.15946 -433.382928) (xy 26.15946 -433.48783) (xy 26.482802 -433.48783)
				(arc
					(start 26.56586 -433.570888)
					(mid 26.858644 -434.00515)
					(end 26.424382 -433.712366)
				)
				(xy 26.399998 -433.687982) (xy 26.15946 -433.687982)
				(arc
					(start 26.15946 -433.816506)
					(mid 26.67 -434.327046)
					(end 27.18054 -433.816506)
				)
			)
		)
	)
	(zone
		(net "GND")
		(layer "F.Cu")
		(hatch none 0.5)
		(connect_pads
			(clearance 0.5)
		)
		(min_thickness 0.25)
		(fill yes
			(thermal_gap 0.5)
			(thermal_bridge_width 0.5)
			(island_removal_mode 0)
		)
		(polygon
			(pts
				(xy 36.322 -186.436) (xy 35.6362 -187.1218) (xy 33.3248 -187.1218) (xy 33.02 -187.4266) (xy 33.02 -188.5442)
				(xy 33.3248 -188.849) (xy 37.4396 -188.849) (xy 37.8714 -188.4172) (xy 37.8714 -186.5376) (xy 37.7698 -186.436)
			)
		)
		(polygon
			(pts
				(xy 37.4396 -188.1378) (xy 37.2364 -188.1378) (xy 37.2364 -188.341) (xy 37.4396 -188.341)
			)
		)
		(polygon
			(pts
				(xy 36.83 -188.1378) (xy 36.6268 -188.1378) (xy 36.6268 -188.341) (xy 36.83 -188.341)
			)
		)
	)
	(zone
		(layer "F.Cu")
		(hatch none 0.5)
		(connect_pads
			(clearance 0)
		)
		(min_thickness 0.25)
		(keepout
			(tracks not_allowed)
			(vias allowed)
			(pads allowed)
			(copperpour not_allowed)
			(footprints allowed)
		)
		(placement
			(enabled no)
			(sheetname "")
		)
		(fill
			(thermal_gap 0.5)
			(thermal_bridge_width 0.5)
			(island_removal_mode 0)
		)
		(polygon
			(pts
				(arc
					(start 7.502906 -411.935676)
					(mid 6.992366 -411.425136)
					(end 6.481826 -411.935676)
				)
				(xy 6.481826 -412.089092) (xy 6.697472 -412.089092)
				(arc
					(start 6.746748 -412.039816)
					(mid 7.18101 -411.747032)
					(end 6.888226 -412.181294)
				)
				(xy 6.780276 -412.289244) (xy 6.481826 -412.289244) (xy 6.481826 -412.394146) (xy 6.779514 -412.394146)
				(arc
					(start 6.888226 -412.502858)
					(mid 7.18101 -412.93712)
					(end 6.746748 -412.644336)
				)
				(xy 6.69671 -412.594298) (xy 6.481826 -412.594298)
				(arc
					(start 6.481826 -412.748222)
					(mid 6.992239 -413.259016)
					(end 7.502906 -412.748476)
				)
			)
		)
	)
	(zone
		(layer "F.Cu")
		(hatch none 0.5)
		(connect_pads
			(clearance 0)
		)
		(min_thickness 0.25)
		(keepout
			(tracks not_allowed)
			(vias allowed)
			(pads allowed)
			(copperpour not_allowed)
			(footprints allowed)
		)
		(placement
			(enabled no)
			(sheetname "")
		)
		(fill
			(thermal_gap 0.5)
			(thermal_bridge_width 0.5)
			(island_removal_mode 0)
		)
		(polygon
			(pts
				(arc
					(start 25.88514 -229.251256)
					(mid 25.273 -228.639116)
					(end 24.66086 -229.251256)
				)
				(xy 24.66086 -229.557326) (xy 24.825452 -229.557326)
				(arc
					(start 25.027382 -229.355396)
					(mid 25.461644 -229.062612)
					(end 25.16886 -229.496874)
				)
				(xy 24.908256 -229.757478) (xy 24.66086 -229.757478) (xy 24.66086 -229.86238) (xy 24.908002 -229.86238)
				(arc
					(start 25.16886 -230.123238)
					(mid 25.461644 -230.5575)
					(end 25.027382 -230.264716)
				)
				(xy 24.825198 -230.062532) (xy 24.66086 -230.062532)
				(arc
					(start 24.66086 -230.368602)
					(mid 25.272873 -230.980996)
					(end 25.88514 -230.368856)
				)
			)
		)
	)
	(zone
		(layer "F.Cu")
		(hatch none 0.5)
		(connect_pads
			(clearance 0)
		)
		(min_thickness 0.25)
		(keepout
			(tracks not_allowed)
			(vias allowed)
			(pads allowed)
			(copperpour not_allowed)
			(footprints allowed)
		)
		(placement
			(enabled no)
			(sheetname "")
		)
		(fill
			(thermal_gap 0.5)
			(thermal_bridge_width 0.5)
			(island_removal_mode 0)
		)
		(polygon
			(pts
				(arc
					(start 27.18054 -25.803352)
					(mid 26.67 -25.292812)
					(end 26.15946 -25.803352)
				)
				(xy 26.15946 -25.957276) (xy 26.374598 -25.957276)
				(arc
					(start 26.424382 -25.907492)
					(mid 26.858644 -25.614708)
					(end 26.56586 -26.04897)
				)
				(xy 26.457402 -26.157428) (xy 26.15946 -26.157428) (xy 26.15946 -26.26233) (xy 26.457656 -26.26233)
				(arc
					(start 26.56586 -26.370534)
					(mid 26.858644 -26.804796)
					(end 26.424382 -26.512012)
				)
				(xy 26.374852 -26.462482) (xy 26.15946 -26.462482)
				(arc
					(start 26.15946 -26.615898)
					(mid 26.669873 -27.126692)
					(end 27.18054 -26.616152)
				)
			)
		)
	)
	(zone
		(layer "F.Cu")
		(hatch none 0.5)
		(connect_pads
			(clearance 0)
		)
		(min_thickness 0.25)
		(keepout
			(tracks allowed)
			(vias allowed)
			(pads allowed)
			(copperpour allowed)
			(footprints allowed)
		)
		(placement
			(enabled no)
			(sheetname "")
		)
		(fill
			(thermal_gap 0.5)
			(thermal_bridge_width 0.5)
			(island_removal_mode 0)
		)
		(polygon
			(pts
				(xy 37.338 -494.919) (xy 37.338 -478.282) (xy 39.497 -478.282) (xy 39.497 -494.919)
			)
		)
	)
	(zone
		(layer "F.Cu")
		(hatch none 0.5)
		(connect_pads
			(clearance 0)
		)
		(min_thickness 0.25)
		(keepout
			(tracks not_allowed)
			(vias allowed)
			(pads allowed)
			(copperpour not_allowed)
			(footprints allowed)
		)
		(placement
			(enabled no)
			(sheetname "")
		)
		(fill
			(thermal_gap 0.5)
			(thermal_bridge_width 0.5)
			(island_removal_mode 0)
		)
		(polygon
			(pts
				(arc
					(start 7.502906 -318.735964)
					(mid 6.992366 -318.225424)
					(end 6.481826 -318.735964)
				)
				(xy 6.481826 -318.88938) (xy 6.697472 -318.88938)
				(arc
					(start 6.746748 -318.840104)
					(mid 7.18101 -318.54732)
					(end 6.888226 -318.981582)
				)
				(xy 6.780276 -319.089532) (xy 6.481826 -319.089532) (xy 6.481826 -319.194434) (xy 6.779514 -319.194434)
				(arc
					(start 6.888226 -319.303146)
					(mid 7.18101 -319.737408)
					(end 6.746748 -319.444624)
				)
				(xy 6.69671 -319.394586) (xy 6.481826 -319.394586)
				(arc
					(start 6.481826 -319.54851)
					(mid 6.992239 -320.059304)
					(end 7.502906 -319.548764)
				)
			)
		)
	)
	(zone
		(net "GND")
		(layer "F.Cu")
		(hatch none 0.5)
		(connect_pads
			(clearance 0.5)
		)
		(min_thickness 0.25)
		(fill yes
			(thermal_gap 0.5)
			(thermal_bridge_width 0.5)
			(island_removal_mode 0)
		)
		(polygon
			(pts
				(xy 8.9408 -461.899) (xy 8.89 -461.9498) (xy 8.89 -463.3722) (xy 8.9916 -463.4738) (xy 8.9916 -465.8614)
				(xy 9.4742 -466.344) (xy 9.4742 -479.0186) (xy 9.4996 -479.0186) (xy 9.906 -479.425) (xy 10.9474 -479.425)
				(xy 11.4046 -478.9678) (xy 11.4046 -476.3008) (xy 11.7348 -475.9706) (xy 11.7348 -462.3308) (xy 11.303 -461.899)
			)
		)
		(polygon
			(pts
				(xy 9.9568 -465.6836) (xy 9.7536 -465.6836) (xy 9.7536 -465.8868) (xy 9.9568 -465.8868)
			)
		)
		(polygon
			(pts
				(xy 9.9568 -464.82) (xy 9.7536 -464.82) (xy 9.7536 -465.0232) (xy 9.9568 -465.0232)
			)
		)
		(polygon
			(pts
				(xy 9.9568 -464.4644) (xy 9.7536 -464.4644) (xy 9.7536 -464.6676) (xy 9.9568 -464.6676)
			)
		)
		(polygon
			(pts
				(xy 9.9568 -463.6008) (xy 9.7536 -463.6008) (xy 9.7536 -463.804) (xy 9.9568 -463.804)
			)
		)
		(polygon
			(pts
				(xy 9.6012 -463.296) (xy 9.398 -463.296) (xy 9.398 -463.4992) (xy 9.6012 -463.4992)
			)
		)
		(polygon
			(pts
				(xy 9.6012 -462.407) (xy 9.398 -462.407) (xy 9.398 -462.8896) (xy 9.6012 -462.8896)
			)
		)
	)
	(zone
		(layer "F.Cu")
		(hatch none 0.5)
		(connect_pads
			(clearance 0)
		)
		(min_thickness 0.25)
		(keepout
			(tracks allowed)
			(vias allowed)
			(pads allowed)
			(copperpour allowed)
			(footprints allowed)
		)
		(placement
			(enabled no)
			(sheetname "")
		)
		(fill
			(thermal_gap 0.5)
			(thermal_bridge_width 0.5)
			(island_removal_mode 0)
		)
		(polygon
			(pts
				(xy 77.724 -364.2614) (xy 74.676 -364.2614) (xy 74.676 -362.458) (xy 77.724 -362.458)
			)
		)
	)
	(zone
		(layer "F.Cu")
		(hatch none 0.5)
		(connect_pads
			(clearance 0)
		)
		(min_thickness 0.25)
		(keepout
			(tracks not_allowed)
			(vias allowed)
			(pads allowed)
			(copperpour not_allowed)
			(footprints allowed)
		)
		(placement
			(enabled no)
			(sheetname "")
		)
		(fill
			(thermal_gap 0.5)
			(thermal_bridge_width 0.5)
			(island_removal_mode 0)
		)
		(polygon
			(pts
				(arc
					(start 37.33927 -79.23149)
					(mid 36.727257 -78.619096)
					(end 36.11499 -79.231236)
				)
				(arc
					(start 36.11499 -80.348836)
					(mid 36.72713 -80.960976)
					(end 37.33927 -80.348836)
				)
				(xy 37.33927 -80.042512) (xy 37.174932 -80.042512)
				(arc
					(start 36.972748 -80.244696)
					(mid 36.538486 -80.53748)
					(end 36.83127 -80.103218)
				)
				(xy 37.092128 -79.84236) (xy 37.33927 -79.84236) (xy 37.33927 -79.737458) (xy 37.091874 -79.737458)
				(arc
					(start 36.83127 -79.476854)
					(mid 36.538486 -79.042592)
					(end 36.972748 -79.335376)
				)
				(xy 37.174678 -79.537306) (xy 37.33927 -79.537306)
			)
		)
	)
	(zone
		(layer "F.Cu")
		(hatch none 0.5)
		(connect_pads
			(clearance 0)
		)
		(min_thickness 0.25)
		(keepout
			(tracks allowed)
			(vias allowed)
			(pads allowed)
			(copperpour allowed)
			(footprints allowed)
		)
		(placement
			(enabled no)
			(sheetname "")
		)
		(fill
			(thermal_gap 0.5)
			(thermal_bridge_width 0.5)
			(island_removal_mode 0)
		)
		(polygon
			(pts
				(xy 102.489 -209.677) (xy 100.584 -209.677) (xy 100.584 -210.185) (xy 98.044 -210.185) (xy 98.044 -206.883)
				(xy 99.695 -206.883) (xy 100.33 -206.248) (xy 100.33 -205.359) (xy 101.6 -204.089) (xy 102.489 -204.089)
			)
		)
	)
	(zone
		(layer "F.Cu")
		(hatch none 0.5)
		(connect_pads
			(clearance 0)
		)
		(min_thickness 0.25)
		(keepout
			(tracks not_allowed)
			(vias allowed)
			(pads allowed)
			(copperpour not_allowed)
			(footprints allowed)
		)
		(placement
			(enabled no)
			(sheetname "")
		)
		(fill
			(thermal_gap 0.5)
			(thermal_bridge_width 0.5)
			(island_removal_mode 0)
		)
		(polygon
			(pts
				(arc
					(start 27.18054 -124.003562)
					(mid 26.67 -123.493022)
					(end 26.15946 -124.003562)
				)
				(xy 26.15946 -124.157232) (xy 26.374852 -124.157232)
				(arc
					(start 26.424382 -124.107702)
					(mid 26.858644 -123.814918)
					(end 26.56586 -124.24918)
				)
				(xy 26.457656 -124.357384) (xy 26.15946 -124.357384) (xy 26.15946 -124.462286) (xy 26.457402 -124.462286)
				(arc
					(start 26.56586 -124.570744)
					(mid 26.858644 -125.005006)
					(end 26.424382 -124.712222)
				)
				(xy 26.374598 -124.662438) (xy 26.15946 -124.662438)
				(arc
					(start 26.15946 -124.816108)
					(mid 26.669873 -125.326902)
					(end 27.18054 -124.816362)
				)
			)
		)
	)
	(zone
		(layer "F.Cu")
		(hatch none 0.5)
		(connect_pads
			(clearance 0)
		)
		(min_thickness 0.25)
		(keepout
			(tracks not_allowed)
			(vias allowed)
			(pads allowed)
			(copperpour not_allowed)
			(footprints allowed)
		)
		(placement
			(enabled no)
			(sheetname "")
		)
		(fill
			(thermal_gap 0.5)
			(thermal_bridge_width 0.5)
			(island_removal_mode 0)
		)
		(polygon
			(pts
				(arc
					(start 7.502906 -349.9358)
					(mid 6.992366 -349.42526)
					(end 6.481826 -349.9358)
				)
				(xy 6.481826 -350.089216) (xy 6.697472 -350.089216)
				(arc
					(start 6.746748 -350.03994)
					(mid 7.18101 -349.747156)
					(end 6.888226 -350.181418)
				)
				(xy 6.780276 -350.289368) (xy 6.481826 -350.289368) (xy 6.481826 -350.39427) (xy 6.779514 -350.39427)
				(arc
					(start 6.888226 -350.502982)
					(mid 7.18101 -350.937244)
					(end 6.746748 -350.64446)
				)
				(xy 6.69671 -350.594422) (xy 6.481826 -350.594422)
				(arc
					(start 6.481826 -350.748346)
					(mid 6.992239 -351.25914)
					(end 7.502906 -350.7486)
				)
			)
		)
	)
	(zone
		(layer "F.Cu")
		(hatch none 0.5)
		(connect_pads
			(clearance 0)
		)
		(min_thickness 0.25)
		(keepout
			(tracks allowed)
			(vias allowed)
			(pads allowed)
			(copperpour allowed)
			(footprints allowed)
		)
		(placement
			(enabled no)
			(sheetname "")
		)
		(fill
			(thermal_gap 0.5)
			(thermal_bridge_width 0.5)
			(island_removal_mode 0)
		)
		(polygon
			(pts
				(xy 222.377 -390.398) (xy 222.377 -373.761) (xy 224.536 -373.761) (xy 224.536 -390.398)
			)
		)
	)
	(zone
		(layer "F.Cu")
		(hatch none 0.5)
		(connect_pads
			(clearance 0)
		)
		(min_thickness 0.25)
		(keepout
			(tracks allowed)
			(vias allowed)
			(pads allowed)
			(copperpour allowed)
			(footprints allowed)
		)
		(placement
			(enabled no)
			(sheetname "")
		)
		(fill
			(thermal_gap 0.5)
			(thermal_bridge_width 0.5)
			(island_removal_mode 0)
		)
		(polygon
			(pts
				(xy 91.821 -21.336) (xy 91.821 -22.86) (xy 89.916 -22.86) (xy 89.916 -21.336)
			)
		)
	)
	(zone
		(layer "F.Cu")
		(hatch none 0.5)
		(connect_pads
			(clearance 0)
		)
		(min_thickness 0.25)
		(keepout
			(tracks not_allowed)
			(vias allowed)
			(pads allowed)
			(copperpour not_allowed)
			(footprints allowed)
		)
		(placement
			(enabled no)
			(sheetname "")
		)
		(fill
			(thermal_gap 0.5)
			(thermal_bridge_width 0.5)
			(island_removal_mode 0)
		)
		(polygon
			(pts
				(xy 1.022096 -463.395822) (xy 3.758184 -463.395822) (xy 3.81 -463.447638) (xy 3.81 -463.639154)
				(xy 3.761232 -463.687922) (xy 1.025398 -463.687922) (xy 1.014984 -463.698336) (xy 1.010158 -463.698336)
				(xy 1.005332 -463.69351) (xy 1.005332 -463.390996) (xy 1.007872 -463.388456) (xy 1.01473 -463.388456)
			)
		)
	)
	(zone
		(layer "F.Cu")
		(hatch none 0.5)
		(connect_pads
			(clearance 0)
		)
		(min_thickness 0.25)
		(keepout
			(tracks not_allowed)
			(vias allowed)
			(pads allowed)
			(copperpour not_allowed)
			(footprints allowed)
		)
		(placement
			(enabled no)
			(sheetname "")
		)
		(fill
			(thermal_gap 0.5)
			(thermal_bridge_width 0.5)
			(island_removal_mode 0)
		)
		(polygon
			(pts
				(arc
					(start 27.18054 -334.803496)
					(mid 26.67 -334.292956)
					(end 26.15946 -334.803496)
				)
				(xy 26.15946 -334.95742) (xy 26.374598 -334.95742)
				(arc
					(start 26.424382 -334.907636)
					(mid 26.858644 -334.614852)
					(end 26.56586 -335.049114)
				)
				(xy 26.457402 -335.157572) (xy 26.15946 -335.157572) (xy 26.15946 -335.262474) (xy 26.457656 -335.262474)
				(arc
					(start 26.56586 -335.370678)
					(mid 26.858644 -335.80494)
					(end 26.424382 -335.512156)
				)
				(xy 26.374852 -335.462626) (xy 26.15946 -335.462626)
				(arc
					(start 26.15946 -335.616042)
					(mid 26.669873 -336.126836)
					(end 27.18054 -335.616296)
				)
			)
		)
	)
	(zone
		(net "GND")
		(layer "F.Cu")
		(hatch none 0.5)
		(connect_pads
			(clearance 0.5)
		)
		(min_thickness 0.25)
		(fill yes
			(thermal_gap 0.5)
			(thermal_bridge_width 0.5)
			(island_removal_mode 0)
		)
		(polygon
			(pts
				(xy 29.751528 -263.135872) (xy 28.2067 -264.6807) (xy 28.2067 -268.4145) (xy 23.2918 -273.3294)
				(xy 18.349722 -273.3294) (xy 15.5194 -276.159722) (xy 15.5194 -303.8094) (xy 16.129 -304.419) (xy 18.5674 -304.419)
				(xy 19.3294 -303.657) (xy 19.3294 -292.334188) (xy 24.770588 -286.893) (xy 32.004 -286.893) (xy 34.671 -284.226)
				(xy 34.671 -263.779) (xy 34.027872 -263.135872)
			)
		)
	)
	(zone
		(layer "F.Cu")
		(hatch none 0.5)
		(connect_pads
			(clearance 0)
		)
		(min_thickness 0.25)
		(keepout
			(tracks allowed)
			(vias allowed)
			(pads allowed)
			(copperpour allowed)
			(footprints allowed)
		)
		(placement
			(enabled no)
			(sheetname "")
		)
		(fill
			(thermal_gap 0.5)
			(thermal_bridge_width 0.5)
			(island_removal_mode 0)
		)
		(polygon
			(pts
				(xy 100.203 -99.187) (xy 100.203 -100.076) (xy 98.298 -100.076) (xy 98.298 -99.187)
			)
		)
	)
	(zone
		(layer "F.Cu")
		(hatch none 0.5)
		(connect_pads
			(clearance 0)
		)
		(min_thickness 0.25)
		(keepout
			(tracks not_allowed)
			(vias allowed)
			(pads allowed)
			(copperpour not_allowed)
			(footprints allowed)
		)
		(placement
			(enabled no)
			(sheetname "")
		)
		(fill
			(thermal_gap 0.5)
			(thermal_bridge_width 0.5)
			(island_removal_mode 0)
		)
		(polygon
			(pts
				(arc
					(start 7.502906 -346.735908)
					(mid 6.992366 -346.225368)
					(end 6.481826 -346.735908)
				)
				(xy 6.481826 -346.889324) (xy 6.697472 -346.889324)
				(arc
					(start 6.746748 -346.840048)
					(mid 7.18101 -346.547264)
					(end 6.888226 -346.981526)
				)
				(xy 6.780276 -347.089476) (xy 6.481826 -347.089476) (xy 6.481826 -347.194378) (xy 6.779514 -347.194378)
				(arc
					(start 6.888226 -347.30309)
					(mid 7.18101 -347.737352)
					(end 6.746748 -347.444568)
				)
				(xy 6.69671 -347.39453) (xy 6.481826 -347.39453)
				(arc
					(start 6.481826 -347.548454)
					(mid 6.992239 -348.059248)
					(end 7.502906 -347.548708)
				)
			)
		)
	)
	(zone
		(layer "F.Cu")
		(hatch none 0.5)
		(connect_pads
			(clearance 0)
		)
		(min_thickness 0.25)
		(keepout
			(tracks not_allowed)
			(vias allowed)
			(pads allowed)
			(copperpour not_allowed)
			(footprints allowed)
		)
		(placement
			(enabled no)
			(sheetname "")
		)
		(fill
			(thermal_gap 0.5)
			(thermal_bridge_width 0.5)
			(island_removal_mode 0)
		)
		(polygon
			(pts
				(arc
					(start 222.339154 -177.431446)
					(mid 221.727141 -176.819052)
					(end 221.114874 -177.431192)
				)
				(arc
					(start 221.114874 -178.548792)
					(mid 221.727014 -179.160932)
					(end 222.339154 -178.548792)
				)
				(xy 222.339154 -178.242722) (xy 222.174562 -178.242722)
				(arc
					(start 221.972632 -178.444652)
					(mid 221.53837 -178.737436)
					(end 221.831154 -178.303174)
				)
				(xy 222.091758 -178.04257) (xy 222.339154 -178.04257) (xy 222.339154 -177.937668) (xy 222.092012 -177.937668)
				(arc
					(start 221.831154 -177.67681)
					(mid 221.53837 -177.242548)
					(end 221.972632 -177.535332)
				)
				(xy 222.174816 -177.737516) (xy 222.339154 -177.737516)
			)
		)
	)
	(zone
		(layer "F.Cu")
		(hatch none 0.5)
		(connect_pads
			(clearance 0)
		)
		(min_thickness 0.25)
		(keepout
			(tracks not_allowed)
			(vias allowed)
			(pads allowed)
			(copperpour not_allowed)
			(footprints allowed)
		)
		(placement
			(enabled no)
			(sheetname "")
		)
		(fill
			(thermal_gap 0.5)
			(thermal_bridge_width 0.5)
			(island_removal_mode 0)
		)
		(polygon
			(pts
				(arc
					(start 220.840554 -363.583982)
					(mid 220.330141 -363.073188)
					(end 219.819474 -363.583728)
				)
				(arc
					(start 219.819474 -364.396528)
					(mid 220.330014 -364.907068)
					(end 220.840554 -364.396528)
				)
				(xy 220.840554 -364.242858) (xy 220.625162 -364.242858)
				(arc
					(start 220.575632 -364.292388)
					(mid 220.14137 -364.585172)
					(end 220.434154 -364.15091)
				)
				(xy 220.542358 -364.042706) (xy 220.840554 -364.042706) (xy 220.840554 -363.937804) (xy 220.542612 -363.937804)
				(arc
					(start 220.434154 -363.829346)
					(mid 220.14137 -363.395084)
					(end 220.575632 -363.687868)
				)
				(xy 220.625416 -363.737652) (xy 220.840554 -363.737652)
			)
		)
	)
	(zone
		(layer "F.Cu")
		(hatch none 0.5)
		(connect_pads
			(clearance 0)
		)
		(min_thickness 0.25)
		(keepout
			(tracks not_allowed)
			(vias allowed)
			(pads allowed)
			(copperpour not_allowed)
			(footprints allowed)
		)
		(placement
			(enabled no)
			(sheetname "")
		)
		(fill
			(thermal_gap 0.5)
			(thermal_bridge_width 0.5)
			(island_removal_mode 0)
		)
		(polygon
			(pts
				(arc
					(start 35.84067 -484.18369)
					(mid 35.33013 -483.67315)
					(end 34.81959 -484.18369)
				)
				(arc
					(start 34.81959 -484.996236)
					(mid 35.330003 -485.50703)
					(end 35.84067 -484.99649)
				)
				(xy 35.84067 -484.84282) (xy 35.625278 -484.84282)
				(arc
					(start 35.575748 -484.89235)
					(mid 35.141486 -485.185134)
					(end 35.43427 -484.750872)
				)
				(xy 35.542474 -484.642668) (xy 35.84067 -484.642668) (xy 35.84067 -484.537766) (xy 35.542728 -484.537766)
				(arc
					(start 35.43427 -484.429308)
					(mid 35.141486 -483.995046)
					(end 35.575748 -484.28783)
				)
				(xy 35.625532 -484.337614) (xy 35.84067 -484.337614)
			)
		)
	)
	(zone
		(layer "F.Cu")
		(hatch none 0.5)
		(connect_pads
			(clearance 0)
		)
		(min_thickness 0.25)
		(keepout
			(tracks allowed)
			(vias allowed)
			(pads allowed)
			(copperpour allowed)
			(footprints allowed)
		)
		(placement
			(enabled no)
			(sheetname "")
		)
		(fill
			(thermal_gap 0.5)
			(thermal_bridge_width 0.5)
			(island_removal_mode 0)
		)
		(polygon
			(pts
				(xy 100.584 -432.689) (xy 100.711 -432.816) (xy 102.489 -432.816) (xy 102.489 -438.531) (xy 101.219 -438.531)
				(xy 100.33 -437.642) (xy 100.33 -436.88) (xy 99.187 -435.737) (xy 98.044 -435.737) (xy 98.044 -430.911)
				(xy 100.584 -430.911)
			)
		)
	)
	(zone
		(net "GND")
		(layer "F.Cu")
		(hatch none 0.5)
		(connect_pads
			(clearance 0.5)
		)
		(min_thickness 0.25)
		(fill yes
			(thermal_gap 0.5)
			(thermal_bridge_width 0.5)
			(island_removal_mode 0)
		)
		(polygon
			(pts
				(arc
					(start 0.999998 -0.763016)
					(mid 0.832426 -0.832426)
					(end 0.763016 -0.999998)
				)
				(xy 0.763016 -141.135608) (xy 2.032 -141.135608) (xy 2.032 -141.097) (xy 6.985 -141.097) (xy 7.366 -140.716)
				(xy 7.366 -97.028) (xy 13.716 -90.678) (xy 13.716 -66.675) (xy 13.44803 -66.40703) (xy 13.44803 -24.65197)
				(xy 13.843 -24.257) (xy 13.843 -19.525996) (xy 15.753842 -17.615154) (xy 15.753842 -3.296158) (xy 17.018 -2.032)
				(xy 36.39947 -2.032) (xy 36.767516 -1.663954) (xy 37.762434 -1.663954) (xy 38.13048 -2.032) (xy 38.364414 -2.265934)
				(xy 39.78148 -3.683) (xy 40.894 -3.683) (xy 53.443378 -3.683) (xy 57.912 -8.151622) (xy 57.912 -17.653)
				(xy 56.896 -18.669) (xy 54.864 -18.669) (xy 52.2732 -16.0782) (xy 41.0464 -16.0782) (xy 40.3606 -15.3924)
				(xy 40.3606 -14.6558) (xy 39.6748 -13.97) (xy 32.639 -13.97) (xy 32.0548 -14.5542) (xy 32.0548 -18.4658)
				(xy 36.83 -23.241) (xy 60.96 -23.241) (xy 84.201 -46.482) (xy 86.614 -46.482) (xy 87.63 -45.466)
				(xy 87.63 -20.828) (xy 86.487 -19.685) (xy 86.487 -16.561054) (xy 90.195654 -12.8524) (xy 93.366082 -12.8524)
				(xy 100.0379 -19.524218) (xy 100.0379 -29.1211) (xy 90.932 -38.227) (xy 90.932 -50.673) (xy 113.051844 -72.792844)
				(xy 113.051844 -76.67371) (xy 107.205018 -82.520536) (xy 107.205018 -122.393964) (xy 89.154 -140.444982)
				(xy 89.154 -184.023) (xy 73.152 -200.025) (xy 73.152 -205.613) (xy 74.422 -206.883) (xy 79.883 -206.883)
				(xy 82.55 -204.216) (xy 84.074 -204.216) (xy 84.3026 -203.9874) (xy 84.3026 -203.5302) (xy 84.7598 -203.073)
				(xy 91.186 -203.073) (xy 91.6686 -203.5556) (xy 93.1672 -203.5556) (xy 93.2688 -203.454) (xy 93.2688 -201.9808)
				(xy 92.837 -201.549) (xy 92.837 -171.816014) (xy 211.447888 -53.205126) (xy 211.447888 -51.491134)
				(xy 210.775804 -50.81905) (xy 207.523588 -50.81905) (xy 206.717138 -51.6255) (xy 201.39533 -51.6255)
				(xy 200.152 -50.38217) (xy 200.152 -47.869856) (xy 200.804272 -47.217584) (xy 203.572618 -47.217584)
				(xy 205.749652 -45.04055) (xy 205.749652 -43.856148) (xy 205.7654 -43.8404) (xy 205.7654 -42.9514)
				(xy 206.7306 -41.9862) (xy 209.8294 -41.9862) (xy 215.3666 -36.449) (xy 215.392 -36.449) (xy 218.488006 -33.352994)
				(xy 229.98049 -33.352994) (xy 230.94823 -32.385254) (xy 236.270038 -32.385254) (xy 237.506256 -33.621472)
				(xy 237.506256 -42.782744) (xy 237.109 -43.18) (xy 237.109 -60.452) (xy 232.918 -64.643) (xy 232.918 -94.615)
				(xy 230.7336 -96.7994) (xy 222.8088 -96.7994) (xy 221.3356 -98.2726) (xy 217.043 -98.2726) (xy 215.961976 -97.191576)
				(xy 204.909674 -97.191576) (xy 204.195172 -96.477074) (xy 204.195172 -83.589876) (xy 203.420472 -82.815176)
				(xy 195.6562 -82.815176) (xy 142.493238 -135.978138) (xy 139.906248 -135.978138) (xy 139.61618 -135.68807)
				(xy 139.61618 -133.37794) (xy 140.760704 -132.233416) (xy 144.245838 -132.233416) (xy 196.362574 -80.11668)
				(xy 218.946984 -80.11668) (xy 219.59189 -79.471774) (xy 219.59189 -54.044342) (xy 219.24264 -53.695092)
				(xy 218.57081 -53.695092) (xy 125.39345 -146.872452) (xy 125.39345 -149.036786) (xy 125.7173 -149.360636)
				(xy 221.860364 -149.360636) (xy 223.9264 -147.2946) (xy 223.9264 -145.5928) (xy 223.52 -145.1864)
				(xy 220.853 -145.1864) (xy 219.9132 -144.2466) (xy 219.9132 -142.6464) (xy 219.1766 -141.9098) (xy 217.0684 -141.9098)
				(xy 215.265 -140.1064) (xy 215.265 -137.795) (xy 214.376 -136.906) (xy 167.68572 -136.906) (xy 167.404034 -136.624314)
				(xy 167.404034 -135.142986) (xy 167.606218 -134.940802) (xy 236.413802 -134.940802) (xy 238.165386 -136.692386)
				(xy 238.165386 -139.88796) (xy 236.474 -141.579346) (xy 236.474 -145.458434) (xy 235.570014 -146.36242)
				(xy 232.808272 -146.36242) (xy 231.240076 -147.930616) (xy 231.240076 -151.25446) (xy 236.474 -156.488384)
				(xy 236.474 -164.465) (xy 233.426 -167.513) (xy 233.426 -176.671986) (xy 233.2228 -176.875186) (xy 233.2228 -197.085712)
				(xy 230.308912 -199.9996) (xy 222.631 -199.9996) (xy 221.234 -201.3966) (xy 216.643204 -201.3966)
				(xy 215.4682 -200.221596) (xy 205.22692 -200.221596) (xy 204.629004 -200.819512) (xy 203.482448 -200.819512)
				(xy 203.1492 -200.486264) (xy 203.1492 -198.456042) (xy 204.851 -196.754242) (xy 204.851 -181.752494)
				(xy 194.0433 -170.944794) (xy 194.0433 -169.9133) (xy 207.5688 -183.4388) (xy 215.5952 -183.4388)
				(xy 217.551 -181.483) (xy 217.551 -167.767) (xy 217.17 -167.386) (xy 217.17 -160.622742) (xy 212.520276 -155.973018)
				(xy 126.601982 -155.973018) (xy 116.713 -165.862) (xy 116.713 -208.407) (xy 113.919 -211.201) (xy 107.442 -211.201)
				(xy 105.537 -213.106) (xy 105.537 -218.10472) (xy 101.854 -221.78772) (xy 101.854 -227.838) (xy 85.495892 -244.196108)
				(xy 66.953892 -244.196108) (xy 51.816 -259.334) (xy 51.816 -266.7) (xy 48.387 -270.129) (xy 48.387 -279.296114)
				(xy 44.778168 -282.904946) (xy 44.778168 -286.205168) (xy 48.4378 -289.8648) (xy 48.4378 -301.7774)
				(xy 49.4284 -302.768) (xy 64.75476 -302.768) (xy 67.645788 -299.876972) (xy 70.819772 -299.876972)
				(xy 71.12 -300.1772) (xy 71.12 -301.19193) (xy 69.629782 -302.682148) (xy 69.629782 -304.54219)
				(xy 70.014592 -304.927) (xy 74.964798 -304.927) (xy 76.319888 -303.57191) (xy 77.816456 -303.57191)
				(xy 77.8764 -303.511966) (xy 77.8764 -302.768) (xy 78.2066 -302.4378) (xy 79.887572 -302.4378) (xy 80.24749 -302.077882)
				(xy 80.24749 -301.23511) (xy 82.876898 -298.605702) (xy 84.076286 -298.605702) (xy 84.3026 -298.379388)
				(xy 84.3026 -297.9166) (xy 84.4804 -297.7388) (xy 94.615 -297.7388) (xy 94.742 -297.6118) (xy 94.742 -296.291)
				(xy 94.234 -295.783) (xy 94.234 -283.4132) (xy 124.079 -253.5682) (xy 220.56725 -253.5682) (xy 222.575628 -251.559822)
				(xy 222.575628 -249.477276) (xy 216.622122 -243.52377) (xy 216.622122 -240.452656) (xy 215.898984 -239.729518)
				(xy 168.228518 -239.729518) (xy 167.227758 -238.728758) (xy 167.227758 -236.72927) (xy 167.705024 -236.252004)
				(xy 215.930226 -236.252004) (xy 218.02725 -238.349028) (xy 235.860082 -238.349028) (xy 237.585504 -240.07445)
				(xy 237.585504 -247.230646) (xy 235.540042 -249.276108) (xy 231.973374 -249.276108) (xy 231.052624 -250.196858)
				(xy 231.052624 -253.22149) (xy 236.347 -258.515866) (xy 236.347 -268.597888) (xy 233.439208 -271.50568)
				(xy 233.439208 -281.188414) (xy 232.817924 -281.809698) (xy 232.817924 -289.784536) (xy 234.120182 -291.086794)
				(xy 234.120182 -302.417988) (xy 233.269028 -303.269142) (xy 220.8276 -303.269142) (xy 219.982542 -304.1142)
				(xy 217.024458 -304.1142) (xy 216.1794 -303.269142) (xy 167.887142 -303.269142) (xy 166.497 -301.879)
				(xy 166.497 -299.974) (xy 167.132 -299.339) (xy 203.2 -299.339) (xy 204.216 -298.323) (xy 204.216 -290.83)
				(xy 203.581 -290.195) (xy 103.5812 -290.195) (xy 102.1588 -291.6174) (xy 102.1588 -300.6598) (xy 106.553 -305.054)
				(xy 129.958084 -305.054) (xy 162.26282 -337.358736) (xy 215.045036 -337.358736) (xy 218.621102 -340.934802)
				(xy 235.778802 -340.934802) (xy 237.61573 -342.77173) (xy 237.61573 -350.519492) (xy 235.837222 -352.298)
				(xy 233.426 -352.298) (xy 232.283 -353.441) (xy 232.283 -356.997) (xy 235.204 -359.918) (xy 250.5964 -359.918)
				(xy 250.952 -360.2736) (xy 252.2982 -360.2736) (xy 252.3744 -360.3498) (xy 254.9652 -360.3498) (xy 259.969 -355.346)
				(xy 261.468108 -355.346) (xy 261.468108 -355.416104) (xy 262.737092 -355.416104)
				(arc
					(start 262.737092 -0.999998)
					(mid 262.667682 -0.832426)
					(end 262.50011 -0.763016)
				)
			)
		)
		(polygon
			(pts
				(xy 253.0348 -359.6386) (xy 252.8316 -359.6386) (xy 252.8316 -359.8418) (xy 253.0348 -359.8418)
			)
		)
		(polygon
			(pts
				(xy 252.4252 -359.6386) (xy 252.222 -359.6386) (xy 252.222 -359.8418) (xy 252.4252 -359.8418)
			)
		)
		(polygon
			(pts
				(xy 252.1204 -359.3084) (xy 251.9172 -359.3084) (xy 251.9172 -359.5116) (xy 252.1204 -359.5116)
			)
		)
		(polygon
			(pts
				(xy 251.2568 -359.3084) (xy 251.0536 -359.3084) (xy 251.0536 -359.5116) (xy 251.2568 -359.5116)
			)
		)
		(polygon
			(pts
				(xy 77.343 -302.9077) (xy 77.1398 -302.9077) (xy 77.1398 -303.1109) (xy 77.343 -303.1109)
			)
		)
		(polygon
			(pts
				(xy 83.8454 -297.942) (xy 83.6422 -297.942) (xy 83.6422 -298.1452) (xy 83.8454 -298.1452)
			)
		)
		(polygon
			(pts
				(xy 94.0308 -297.0784) (xy 93.5482 -297.0784) (xy 93.5482 -297.2816) (xy 94.0308 -297.2816)
			)
		)
		(polygon
			(pts
				(xy 93.1418 -297.0784) (xy 92.9386 -297.0784) (xy 92.9386 -297.2816) (xy 93.1418 -297.2816)
			)
		)
		(polygon
			(pts
				(xy 83.8454 -203.581) (xy 83.6422 -203.581) (xy 83.6422 -203.7842) (xy 83.8454 -203.7842)
			)
		)
		(polygon
			(pts
				(xy 92.6338 -202.8444) (xy 92.1512 -202.8444) (xy 92.1512 -203.0476) (xy 92.6338 -203.0476)
			)
		)
		(polygon
			(pts
				(xy 91.7448 -202.8444) (xy 91.5416 -202.8444) (xy 91.5416 -203.0476) (xy 91.7448 -203.0476)
			)
		)
		(polygon
			(pts
				(xy 210.9216 -51.7652) (xy 210.7184 -51.7652) (xy 210.7184 -51.9684) (xy 210.9216 -51.9684)
			)
		)
		(polygon
			(pts
				(xy 210.9216 -51.1556) (xy 210.7184 -51.1556) (xy 210.7184 -51.3588) (xy 210.9216 -51.3588)
			)
		)
		(polygon
			(pts
				(xy 33.8074 -14.7066) (xy 33.6042 -14.7066) (xy 33.6042 -14.9098) (xy 33.8074 -14.9098)
			)
		)
		(polygon
			(pts
				(xy 32.9438 -14.7066) (xy 32.7406 -14.7066) (xy 32.7406 -14.9098) (xy 32.9438 -14.9098)
			)
		)
	)
	(zone
		(net "GND")
		(layer "F.Cu")
		(hatch none 0.5)
		(connect_pads
			(clearance 0.5)
		)
		(min_thickness 0.25)
		(fill yes
			(thermal_gap 0.5)
			(thermal_bridge_width 0.5)
			(island_removal_mode 0)
		)
		(polygon
			(pts
				(xy 0.763016 -245.148608) (xy 0.763016 -267.13561) (xy 2.032 -267.13561) (xy 2.032 -245.148608)
			)
		)
	)
	(zone
		(layer "F.Cu")
		(hatch none 0.5)
		(connect_pads
			(clearance 0)
		)
		(min_thickness 0.25)
		(keepout
			(tracks not_allowed)
			(vias allowed)
			(pads allowed)
			(copperpour not_allowed)
			(footprints allowed)
		)
		(placement
			(enabled no)
			(sheetname "")
		)
		(fill
			(thermal_gap 0.5)
			(thermal_bridge_width 0.5)
			(island_removal_mode 0)
		)
		(polygon
			(pts
				(arc
					(start 220.840554 -72.183752)
					(mid 220.330141 -71.672958)
					(end 219.819474 -72.183498)
				)
				(arc
					(start 219.819474 -72.996298)
					(mid 220.330014 -73.506838)
					(end 220.840554 -72.996298)
				)
				(xy 220.840554 -72.842628) (xy 220.625162 -72.842628)
				(arc
					(start 220.575632 -72.892158)
					(mid 220.14137 -73.184942)
					(end 220.434154 -72.75068)
				)
				(xy 220.542358 -72.642476) (xy 220.840554 -72.642476) (xy 220.840554 -72.537574) (xy 220.542612 -72.537574)
				(arc
					(start 220.434154 -72.429116)
					(mid 220.14137 -71.994854)
					(end 220.575632 -72.287638)
				)
				(xy 220.625416 -72.337422) (xy 220.840554 -72.337422)
			)
		)
	)
	(zone
		(layer "F.Cu")
		(hatch none 0.5)
		(connect_pads
			(clearance 0)
		)
		(min_thickness 0.25)
		(keepout
			(tracks not_allowed)
			(vias allowed)
			(pads allowed)
			(copperpour not_allowed)
			(footprints allowed)
		)
		(placement
			(enabled no)
			(sheetname "")
		)
		(fill
			(thermal_gap 0.5)
			(thermal_bridge_width 0.5)
			(island_removal_mode 0)
		)
		(polygon
			(pts
				(xy 96.89465 -300.17339) (xy 97.06483 -300.17339) (xy 97.06483 -301.34179) (xy 96.89465 -301.34179)
			)
		)
	)
	(zone
		(layer "F.Cu")
		(hatch none 0.5)
		(connect_pads
			(clearance 0)
		)
		(min_thickness 0.25)
		(keepout
			(tracks allowed)
			(vias allowed)
			(pads allowed)
			(copperpour allowed)
			(footprints allowed)
		)
		(placement
			(enabled no)
			(sheetname "")
		)
		(fill
			(thermal_gap 0.5)
			(thermal_bridge_width 0.5)
			(island_removal_mode 0)
		)
		(polygon
			(pts
				(xy 37.338 -391.922) (xy 37.338 -375.285) (xy 39.497 -375.285) (xy 39.497 -391.922)
			)
		)
	)
	(zone
		(layer "F.Cu")
		(hatch none 0.5)
		(connect_pads
			(clearance 0)
		)
		(min_thickness 0.25)
		(keepout
			(tracks not_allowed)
			(vias allowed)
			(pads allowed)
			(copperpour not_allowed)
			(footprints allowed)
		)
		(placement
			(enabled no)
			(sheetname "")
		)
		(fill
			(thermal_gap 0.5)
			(thermal_bridge_width 0.5)
			(island_removal_mode 0)
		)
		(polygon
			(pts
				(arc
					(start 222.339154 -56.831484)
					(mid 221.727141 -56.21909)
					(end 221.114874 -56.83123)
				)
				(arc
					(start 221.114874 -57.94883)
					(mid 221.727014 -58.56097)
					(end 222.339154 -57.94883)
				)
				(xy 222.339154 -57.642506) (xy 222.174816 -57.642506)
				(arc
					(start 221.972632 -57.84469)
					(mid 221.53837 -58.137474)
					(end 221.831154 -57.703212)
				)
				(xy 222.092012 -57.442354) (xy 222.339154 -57.442354) (xy 222.339154 -57.337452) (xy 222.091758 -57.337452)
				(arc
					(start 221.831154 -57.076848)
					(mid 221.53837 -56.642586)
					(end 221.972632 -56.93537)
				)
				(xy 222.174562 -57.1373) (xy 222.339154 -57.1373)
			)
		)
	)
	(zone
		(layer "F.Cu")
		(hatch none 0.5)
		(connect_pads
			(clearance 0)
		)
		(min_thickness 0.25)
		(keepout
			(tracks not_allowed)
			(vias allowed)
			(pads allowed)
			(copperpour not_allowed)
			(footprints allowed)
		)
		(placement
			(enabled no)
			(sheetname "")
		)
		(fill
			(thermal_gap 0.5)
			(thermal_bridge_width 0.5)
			(island_removal_mode 0)
		)
		(polygon
			(pts
				(arc
					(start 25.88514 -332.251304)
					(mid 25.273 -331.639164)
					(end 24.66086 -332.251304)
				)
				(xy 24.66086 -332.557374) (xy 24.825452 -332.557374)
				(arc
					(start 25.027382 -332.355444)
					(mid 25.461644 -332.06266)
					(end 25.16886 -332.496922)
				)
				(xy 24.908256 -332.757526) (xy 24.66086 -332.757526) (xy 24.66086 -332.862428) (xy 24.908002 -332.862428)
				(arc
					(start 25.16886 -333.123286)
					(mid 25.461644 -333.557548)
					(end 25.027382 -333.264764)
				)
				(xy 24.825198 -333.06258) (xy 24.66086 -333.06258)
				(arc
					(start 24.66086 -333.36865)
					(mid 25.272873 -333.981044)
					(end 25.88514 -333.368904)
				)
			)
		)
	)
	(zone
		(layer "F.Cu")
		(hatch none 0.5)
		(connect_pads
			(clearance 0)
		)
		(min_thickness 0.25)
		(keepout
			(tracks not_allowed)
			(vias allowed)
			(pads allowed)
			(copperpour not_allowed)
			(footprints allowed)
		)
		(placement
			(enabled no)
			(sheetname "")
		)
		(fill
			(thermal_gap 0.5)
			(thermal_bridge_width 0.5)
			(island_removal_mode 0)
		)
		(polygon
			(pts
				(arc
					(start 25.88514 -430.451514)
					(mid 25.273127 -429.83912)
					(end 24.66086 -430.45126)
				)
				(xy 24.66086 -430.78273) (xy 24.800052 -430.78273)
				(arc
					(start 25.027382 -430.5554)
					(mid 25.461644 -430.262616)
					(end 25.16886 -430.696878)
				)
				(xy 24.882856 -430.982882) (xy 24.66086 -430.982882) (xy 24.66086 -431.087784) (xy 24.933402 -431.087784)
				(arc
					(start 25.16886 -431.323242)
					(mid 25.461644 -431.757504)
					(end 25.027382 -431.46472)
				)
				(xy 24.850598 -431.287936) (xy 24.66086 -431.287936)
				(arc
					(start 24.66086 -431.56886)
					(mid 25.273 -432.181)
					(end 25.88514 -431.56886)
				)
			)
		)
	)
	(zone
		(layer "F.Cu")
		(hatch none 0.5)
		(connect_pads
			(clearance 0)
		)
		(min_thickness 0.25)
		(keepout
			(tracks not_allowed)
			(vias allowed)
			(pads allowed)
			(copperpour not_allowed)
			(footprints allowed)
		)
		(placement
			(enabled no)
			(sheetname "")
		)
		(fill
			(thermal_gap 0.5)
			(thermal_bridge_width 0.5)
			(island_removal_mode 0)
		)
		(polygon
			(pts
				(arc
					(start 220.840554 -466.58403)
					(mid 220.330141 -466.073236)
					(end 219.819474 -466.583776)
				)
				(arc
					(start 219.819474 -467.396576)
					(mid 220.330014 -467.907116)
					(end 220.840554 -467.396576)
				)
				(xy 220.840554 -467.242906) (xy 220.625162 -467.242906)
				(arc
					(start 220.575632 -467.292436)
					(mid 220.14137 -467.58522)
					(end 220.434154 -467.150958)
				)
				(xy 220.542358 -467.042754) (xy 220.840554 -467.042754) (xy 220.840554 -466.937852) (xy 220.542612 -466.937852)
				(arc
					(start 220.434154 -466.829394)
					(mid 220.14137 -466.395132)
					(end 220.575632 -466.687916)
				)
				(xy 220.625416 -466.7377) (xy 220.840554 -466.7377)
			)
		)
	)
	(zone
		(layer "F.Cu")
		(hatch none 0.5)
		(connect_pads
			(clearance 0)
		)
		(min_thickness 0.25)
		(keepout
			(tracks allowed)
			(vias allowed)
			(pads allowed)
			(copperpour allowed)
			(footprints not_allowed)
		)
		(placement
			(enabled no)
			(sheetname "")
		)
		(fill
			(thermal_gap 0.5)
			(thermal_bridge_width 0.5)
			(island_removal_mode 0)
		)
		(polygon
			(pts
				(xy 213.089998 -442.170058) (xy 223.089978 -442.170058) (xy 223.089978 -432.170078) (xy 213.089998 -432.170078)
			)
		)
	)
	(zone
		(layer "F.Cu")
		(hatch none 0.5)
		(connect_pads
			(clearance 0)
		)
		(min_thickness 0.25)
		(keepout
			(tracks not_allowed)
			(vias allowed)
			(pads allowed)
			(copperpour not_allowed)
			(footprints allowed)
		)
		(placement
			(enabled no)
			(sheetname "")
		)
		(fill
			(thermal_gap 0.5)
			(thermal_bridge_width 0.5)
			(island_removal_mode 0)
		)
		(polygon
			(pts
				(arc
					(start 7.502906 -337.187032)
					(mid 6.992493 -336.676238)
					(end 6.481826 -337.186778)
				)
				(xy 6.481826 -337.340194) (xy 6.697472 -337.340194)
				(arc
					(start 6.746748 -337.290918)
					(mid 7.18101 -336.998134)
					(end 6.888226 -337.432396)
				)
				(xy 6.780276 -337.540346) (xy 6.481826 -337.540346) (xy 6.481826 -337.645248) (xy 6.779514 -337.645248)
				(arc
					(start 6.888226 -337.75396)
					(mid 7.18101 -338.188222)
					(end 6.746748 -337.895438)
				)
				(xy 6.69671 -337.8454) (xy 6.481826 -337.8454)
				(arc
					(start 6.481826 -337.999578)
					(mid 6.992366 -338.510118)
					(end 7.502906 -337.999578)
				)
			)
		)
	)
	(zone
		(layer "F.Cu")
		(hatch none 0.5)
		(connect_pads
			(clearance 0)
		)
		(min_thickness 0.25)
		(keepout
			(tracks not_allowed)
			(vias allowed)
			(pads allowed)
			(copperpour not_allowed)
			(footprints allowed)
		)
		(placement
			(enabled no)
			(sheetname "")
		)
		(fill
			(thermal_gap 0.5)
			(thermal_bridge_width 0.5)
			(island_removal_mode 0)
		)
		(polygon
			(pts
				(xy 92.89542 -435.63921) (xy 92.98432 -435.63921) (xy 92.98432 -436.80761) (xy 92.89542 -436.80761)
			)
		)
	)
	(zone
		(layer "F.Cu")
		(hatch none 0.5)
		(connect_pads
			(clearance 0)
		)
		(min_thickness 0.25)
		(keepout
			(tracks allowed)
			(vias allowed)
			(pads allowed)
			(copperpour allowed)
			(footprints allowed)
		)
		(placement
			(enabled no)
			(sheetname "")
		)
		(fill
			(thermal_gap 0.5)
			(thermal_bridge_width 0.5)
			(island_removal_mode 0)
		)
		(polygon
			(pts
				(xy 225.933 -437.134) (xy 225.933 -434.3654) (xy 222.2754 -434.3654) (xy 222.2754 -431.4952) (xy 226.949 -431.4952)
				(xy 226.949 -430.784) (xy 227.965 -430.784) (xy 227.965 -435.356) (xy 226.949 -435.356) (xy 226.949 -437.134)
			)
		)
	)
	(zone
		(layer "F.Cu")
		(hatch none 0.5)
		(connect_pads
			(clearance 0)
		)
		(min_thickness 0.25)
		(keepout
			(tracks allowed)
			(vias allowed)
			(pads allowed)
			(copperpour allowed)
			(footprints allowed)
		)
		(placement
			(enabled no)
			(sheetname "")
		)
		(fill
			(thermal_gap 0.5)
			(thermal_bridge_width 0.5)
			(island_removal_mode 0)
		)
		(polygon
			(pts
				(xy 94.869 -298.577) (xy 94.996 -298.45) (xy 94.996 -296.672) (xy 100.711 -296.672) (xy 100.711 -297.942)
				(xy 99.822 -298.831) (xy 99.06 -298.831) (xy 97.917 -299.974) (xy 97.917 -301.117) (xy 93.091 -301.117)
				(xy 93.091 -298.577)
			)
		)
	)
	(zone
		(net "GND")
		(layer "F.Cu")
		(hatch none 0.5)
		(connect_pads
			(clearance 0.5)
		)
		(min_thickness 0.25)
		(fill yes
			(thermal_gap 0.5)
			(thermal_bridge_width 0.5)
			(island_removal_mode 0)
		)
		(polygon
			(pts
				(xy 15.696184 -374.845072) (xy 15.150338 -375.390918) (xy 15.150338 -402.006308) (xy 21.680424 -408.536394)
				(xy 39.883588 -408.536394) (xy 41.684194 -410.337) (xy 43.434 -410.337) (xy 44.958 -408.813) (xy 44.958 -405.765)
				(xy 44.069 -404.876) (xy 19.80692 -404.876) (xy 18.496788 -403.565868) (xy 18.496788 -397.833596)
				(xy 19.842988 -396.487396) (xy 19.842988 -380.334012) (xy 23.882858 -376.294142) (xy 23.882858 -375.905268)
				(xy 23.69058 -375.71299) (xy 17.797018 -375.71299) (xy 16.9291 -374.845072)
			)
		)
	)
	(zone
		(layer "F.Cu")
		(hatch none 0.5)
		(connect_pads
			(clearance 0)
		)
		(min_thickness 0.25)
		(keepout
			(tracks not_allowed)
			(vias allowed)
			(pads allowed)
			(copperpour not_allowed)
			(footprints allowed)
		)
		(placement
			(enabled no)
			(sheetname "")
		)
		(fill
			(thermal_gap 0.5)
			(thermal_bridge_width 0.5)
			(island_removal_mode 0)
		)
		(polygon
			(pts
				(arc
					(start 25.88514 -13.67663)
					(mid 25.273127 -13.064236)
					(end 24.66086 -13.676376)
				)
				(xy 24.66086 -13.982446) (xy 24.825452 -13.982446)
				(arc
					(start 25.027382 -13.780516)
					(mid 25.461644 -13.487732)
					(end 25.16886 -13.921994)
				)
				(xy 24.908256 -14.182598) (xy 24.66086 -14.182598) (xy 24.66086 -14.2875) (xy 24.908002 -14.2875)
				(arc
					(start 25.16886 -14.548358)
					(mid 25.461644 -14.98262)
					(end 25.027382 -14.689836)
				)
				(xy 24.825198 -14.487652) (xy 24.66086 -14.487652)
				(arc
					(start 24.66086 -14.793976)
					(mid 25.273 -15.406116)
					(end 25.88514 -14.793976)
				)
			)
		)
	)
	(zone
		(layer "F.Cu")
		(hatch none 0.5)
		(connect_pads
			(clearance 0)
		)
		(min_thickness 0.25)
		(keepout
			(tracks not_allowed)
			(vias allowed)
			(pads allowed)
			(copperpour not_allowed)
			(footprints allowed)
		)
		(placement
			(enabled no)
			(sheetname "")
		)
		(fill
			(thermal_gap 0.5)
			(thermal_bridge_width 0.5)
			(island_removal_mode 0)
		)
		(polygon
			(pts
				(arc
					(start 25.88514 -116.651278)
					(mid 25.273127 -116.038884)
					(end 24.66086 -116.651024)
				)
				(xy 24.66086 -116.957348) (xy 24.825198 -116.957348)
				(arc
					(start 25.027382 -116.755164)
					(mid 25.461644 -116.46238)
					(end 25.16886 -116.896642)
				)
				(xy 24.908002 -117.1575) (xy 24.66086 -117.1575) (xy 24.66086 -117.262402) (xy 24.908256 -117.262402)
				(arc
					(start 25.16886 -117.523006)
					(mid 25.461644 -117.957268)
					(end 25.027382 -117.664484)
				)
				(xy 24.825452 -117.462554) (xy 24.66086 -117.462554)
				(arc
					(start 24.66086 -117.768624)
					(mid 25.273 -118.380764)
					(end 25.88514 -117.768624)
				)
			)
		)
	)
	(zone
		(layer "F.Cu")
		(hatch none 0.5)
		(connect_pads
			(clearance 0)
		)
		(min_thickness 0.25)
		(keepout
			(tracks not_allowed)
			(vias allowed)
			(pads allowed)
			(copperpour not_allowed)
			(footprints allowed)
		)
		(placement
			(enabled no)
			(sheetname "")
		)
		(fill
			(thermal_gap 0.5)
			(thermal_bridge_width 0.5)
			(island_removal_mode 0)
		)
		(polygon
			(pts
				(arc
					(start 220.840554 -260.583934)
					(mid 220.330141 -260.07314)
					(end 219.819474 -260.58368)
				)
				(arc
					(start 219.819474 -261.39648)
					(mid 220.330014 -261.90702)
					(end 220.840554 -261.39648)
				)
				(xy 220.840554 -261.24281) (xy 220.625162 -261.24281)
				(arc
					(start 220.575632 -261.29234)
					(mid 220.14137 -261.585124)
					(end 220.434154 -261.150862)
				)
				(xy 220.542358 -261.042658) (xy 220.840554 -261.042658) (xy 220.840554 -260.937756) (xy 220.542612 -260.937756)
				(arc
					(start 220.434154 -260.829298)
					(mid 220.14137 -260.395036)
					(end 220.575632 -260.68782)
				)
				(xy 220.625416 -260.737604) (xy 220.840554 -260.737604)
			)
		)
	)
	(zone
		(net "GND")
		(layer "F.Cu")
		(hatch none 0.5)
		(connect_pads
			(clearance 0.5)
		)
		(min_thickness 0.25)
		(fill yes
			(thermal_gap 0.5)
			(thermal_bridge_width 0.5)
			(island_removal_mode 0)
		)
		(polygon
			(pts
				(xy 31.013654 -154.305) (xy 27.227784 -158.09087) (xy 27.227784 -159.436816) (xy 26.3906 -160.274)
				(xy 25.496774 -160.274) (xy 25.221184 -160.54959) (xy 25.221184 -161.728912) (xy 25.821386 -162.329114)
				(xy 25.821386 -165.51275) (xy 25.740868 -165.593268) (xy 24.196548 -165.593268) (xy 24.119332 -165.670484)
				(xy 24.119332 -166.658036) (xy 22.670008 -168.10736) (xy 17.151858 -168.10736) (xy 15.367 -169.892218)
				(xy 15.367 -197.231) (xy 10.922508 -201.675492) (xy 10.922508 -204.216508) (xy 11.811 -205.105)
				(xy 12.954 -205.105) (xy 18.746978 -199.312022) (xy 18.746978 -190.310008) (xy 25.242012 -183.814974)
				(xy 32.99841 -183.814974) (xy 34.671 -182.142384) (xy 34.671 -155.702) (xy 33.274 -154.305)
			)
		)
	)
	(zone
		(net "GND")
		(layer "F.Cu")
		(hatch none 0.5)
		(connect_pads
			(clearance 0.5)
		)
		(min_thickness 0.25)
		(fill yes
			(thermal_gap 0.5)
			(thermal_bridge_width 0.5)
			(island_removal_mode 0)
		)
		(polygon
			(pts
				(xy 218.9734 -91.7194) (xy 218.7448 -91.948) (xy 218.7448 -94.2848) (xy 218.9734 -94.5134) (xy 222.758 -94.5134)
				(xy 223.2152 -94.0562) (xy 223.2152 -92.1258) (xy 222.8088 -91.7194)
			)
		)
		(polygon
			(pts
				(xy 220.3704 -92.4814) (xy 220.1672 -92.4814) (xy 220.1672 -92.6846) (xy 220.3704 -92.6846)
			)
		)
		(polygon
			(pts
				(xy 219.5068 -92.4814) (xy 219.3036 -92.4814) (xy 219.3036 -92.6846) (xy 219.5068 -92.6846)
			)
		)
	)
	(zone
		(layer "F.Cu")
		(hatch none 0.5)
		(connect_pads
			(clearance 0)
		)
		(min_thickness 0.25)
		(keepout
			(tracks not_allowed)
			(vias allowed)
			(pads allowed)
			(copperpour not_allowed)
			(footprints allowed)
		)
		(placement
			(enabled no)
			(sheetname "")
		)
		(fill
			(thermal_gap 0.5)
			(thermal_bridge_width 0.5)
			(island_removal_mode 0)
		)
		(polygon
			(pts
				(arc
					(start 7.502906 -387.135878)
					(mid 6.992493 -386.625084)
					(end 6.481826 -387.135624)
				)
				(xy 6.481826 -387.289294) (xy 6.697218 -387.289294)
				(arc
					(start 6.746748 -387.239764)
					(mid 7.18101 -386.94698)
					(end 6.888226 -387.381242)
				)
				(xy 6.780022 -387.489446) (xy 6.481826 -387.489446) (xy 6.481826 -387.594348) (xy 6.779768 -387.594348)
				(arc
					(start 6.888226 -387.702806)
					(mid 7.18101 -388.137068)
					(end 6.746748 -387.844284)
				)
				(xy 6.696964 -387.7945) (xy 6.481826 -387.7945)
				(arc
					(start 6.481826 -387.948424)
					(mid 6.992366 -388.458964)
					(end 7.502906 -387.948424)
				)
			)
		)
	)
	(zone
		(layer "F.Cu")
		(hatch none 0.5)
		(connect_pads
			(clearance 0)
		)
		(min_thickness 0.25)
		(keepout
			(tracks not_allowed)
			(vias allowed)
			(pads allowed)
			(copperpour not_allowed)
			(footprints allowed)
		)
		(placement
			(enabled no)
			(sheetname "")
		)
		(fill
			(thermal_gap 0.5)
			(thermal_bridge_width 0.5)
			(island_removal_mode 0)
		)
		(polygon
			(pts
				(arc
					(start 7.502906 -278.786844)
					(mid 6.992493 -278.27605)
					(end 6.481826 -278.78659)
				)
				(xy 6.481826 -278.94026) (xy 6.697218 -278.94026)
				(arc
					(start 6.746748 -278.89073)
					(mid 7.18101 -278.597946)
					(end 6.888226 -279.032208)
				)
				(xy 6.780022 -279.140412) (xy 6.481826 -279.140412) (xy 6.481826 -279.245314) (xy 6.779768 -279.245314)
				(arc
					(start 6.888226 -279.353772)
					(mid 7.18101 -279.788034)
					(end 6.746748 -279.49525)
				)
				(xy 6.696964 -279.445466) (xy 6.481826 -279.445466)
				(arc
					(start 6.481826 -279.59939)
					(mid 6.992366 -280.10993)
					(end 7.502906 -279.59939)
				)
			)
		)
	)
	(zone
		(layer "F.Cu")
		(hatch none 0.5)
		(connect_pads
			(clearance 0)
		)
		(min_thickness 0.25)
		(keepout
			(tracks not_allowed)
			(vias allowed)
			(pads allowed)
			(copperpour not_allowed)
			(footprints allowed)
		)
		(placement
			(enabled no)
			(sheetname "")
		)
		(fill
			(thermal_gap 0.5)
			(thermal_bridge_width 0.5)
			(island_removal_mode 0)
		)
		(polygon
			(pts
				(arc
					(start 7.502906 -217.485468)
					(mid 6.992493 -216.974674)
					(end 6.481826 -217.485214)
				)
				(xy 6.481826 -217.63863) (xy 6.697472 -217.63863)
				(arc
					(start 6.746748 -217.589354)
					(mid 7.18101 -217.29657)
					(end 6.888226 -217.730832)
				)
				(xy 6.780276 -217.838782) (xy 6.481826 -217.838782) (xy 6.481826 -217.943684) (xy 6.779514 -217.943684)
				(arc
					(start 6.888226 -218.052396)
					(mid 7.18101 -218.486658)
					(end 6.746748 -218.193874)
				)
				(xy 6.69671 -218.143836) (xy 6.481826 -218.143836)
				(arc
					(start 6.481826 -218.298014)
					(mid 6.992366 -218.808554)
					(end 7.502906 -218.298014)
				)
			)
		)
	)
	(zone
		(layer "F.Cu")
		(hatch none 0.5)
		(connect_pads
			(clearance 0)
		)
		(min_thickness 0.25)
		(keepout
			(tracks not_allowed)
			(vias allowed)
			(pads allowed)
			(copperpour not_allowed)
			(footprints allowed)
		)
		(placement
			(enabled no)
			(sheetname "")
		)
		(fill
			(thermal_gap 0.5)
			(thermal_bridge_width 0.5)
			(island_removal_mode 0)
		)
		(polygon
			(pts
				(xy 88.97239 -431.71491) (xy 90.14079 -431.71491) (xy 90.14079 -431.80381) (xy 88.97239 -431.80381)
			)
		)
	)
	(zone
		(layer "F.Cu")
		(hatch none 0.5)
		(connect_pads
			(clearance 0)
		)
		(min_thickness 0.25)
		(keepout
			(tracks not_allowed)
			(vias allowed)
			(pads allowed)
			(copperpour not_allowed)
			(footprints allowed)
		)
		(placement
			(enabled no)
			(sheetname "")
		)
		(fill
			(thermal_gap 0.5)
			(thermal_bridge_width 0.5)
			(island_removal_mode 0)
		)
		(polygon
			(pts
				(xy 97.39503 -309.02021) (xy 97.48393 -309.02021) (xy 97.48393 -310.18861) (xy 97.39503 -310.18861)
			)
		)
	)
	(zone
		(layer "F.Cu")
		(hatch none 0.5)
		(connect_pads
			(clearance 0)
		)
		(min_thickness 0.25)
		(keepout
			(tracks not_allowed)
			(vias allowed)
			(pads allowed)
			(copperpour not_allowed)
			(footprints allowed)
		)
		(placement
			(enabled no)
			(sheetname "")
		)
		(fill
			(thermal_gap 0.5)
			(thermal_bridge_width 0.5)
			(island_removal_mode 0)
		)
		(polygon
			(pts
				(arc
					(start 37.33927 -56.831484)
					(mid 36.727257 -56.21909)
					(end 36.11499 -56.83123)
				)
				(arc
					(start 36.11499 -57.94883)
					(mid 36.72713 -58.56097)
					(end 37.33927 -57.94883)
				)
				(xy 37.33927 -57.642506) (xy 37.174932 -57.642506)
				(arc
					(start 36.972748 -57.84469)
					(mid 36.538486 -58.137474)
					(end 36.83127 -57.703212)
				)
				(xy 37.092128 -57.442354) (xy 37.33927 -57.442354) (xy 37.33927 -57.337452) (xy 37.091874 -57.337452)
				(arc
					(start 36.83127 -57.076848)
					(mid 36.538486 -56.642586)
					(end 36.972748 -56.93537)
				)
				(xy 37.174678 -57.1373) (xy 37.33927 -57.1373)
			)
		)
	)
	(zone
		(layer "F.Cu")
		(hatch none 0.5)
		(connect_pads
			(clearance 0)
		)
		(min_thickness 0.25)
		(keepout
			(tracks not_allowed)
			(vias allowed)
			(pads allowed)
			(copperpour not_allowed)
			(footprints allowed)
		)
		(placement
			(enabled no)
			(sheetname "")
		)
		(fill
			(thermal_gap 0.5)
			(thermal_bridge_width 0.5)
			(island_removal_mode 0)
		)
		(polygon
			(pts
				(arc
					(start 7.502906 -415.136076)
					(mid 6.992493 -414.625282)
					(end 6.481826 -415.135822)
				)
				(xy 6.481826 -415.289238) (xy 6.697472 -415.289238)
				(arc
					(start 6.746748 -415.239962)
					(mid 7.18101 -414.947178)
					(end 6.888226 -415.38144)
				)
				(xy 6.780276 -415.48939) (xy 6.481826 -415.48939) (xy 6.481826 -415.594292) (xy 6.779514 -415.594292)
				(arc
					(start 6.888226 -415.703004)
					(mid 7.18101 -416.137266)
					(end 6.746748 -415.844482)
				)
				(xy 6.69671 -415.794444) (xy 6.481826 -415.794444)
				(arc
					(start 6.481826 -415.948622)
					(mid 6.992366 -416.459162)
					(end 7.502906 -415.948622)
				)
			)
		)
	)
	(zone
		(layer "F.Cu")
		(hatch none 0.5)
		(connect_pads
			(clearance 0)
		)
		(min_thickness 0.25)
		(keepout
			(tracks not_allowed)
			(vias allowed)
			(pads allowed)
			(copperpour not_allowed)
			(footprints allowed)
		)
		(placement
			(enabled no)
			(sheetname "")
		)
		(fill
			(thermal_gap 0.5)
			(thermal_bridge_width 0.5)
			(island_removal_mode 0)
		)
		(polygon
			(pts
				(arc
					(start 222.339154 -74.431398)
					(mid 221.727141 -73.819004)
					(end 221.114874 -74.431144)
				)
				(arc
					(start 221.114874 -75.548744)
					(mid 221.727014 -76.160884)
					(end 222.339154 -75.548744)
				)
				(xy 222.339154 -75.242674) (xy 222.174562 -75.242674)
				(arc
					(start 221.972632 -75.444604)
					(mid 221.53837 -75.737388)
					(end 221.831154 -75.303126)
				)
				(xy 222.091758 -75.042522) (xy 222.339154 -75.042522) (xy 222.339154 -74.93762) (xy 222.092012 -74.93762)
				(arc
					(start 221.831154 -74.676762)
					(mid 221.53837 -74.2425)
					(end 221.972632 -74.535284)
				)
				(xy 222.174816 -74.737468) (xy 222.339154 -74.737468)
			)
		)
	)
	(zone
		(layer "F.Cu")
		(hatch none 0.5)
		(connect_pads
			(clearance 0)
		)
		(min_thickness 0.25)
		(keepout
			(tracks allowed)
			(vias allowed)
			(pads allowed)
			(copperpour allowed)
			(footprints allowed)
		)
		(placement
			(enabled no)
			(sheetname "")
		)
		(fill
			(thermal_gap 0.5)
			(thermal_bridge_width 0.5)
			(island_removal_mode 0)
		)
		(polygon
			(pts
				(xy 95.123 -219.329) (xy 95.123 -217.424) (xy 92.075 -217.424) (xy 91.694 -217.805) (xy 91.694 -219.329)
				(xy 86.233 -219.329) (xy 86.233 -218.567) (xy 87.63 -217.17) (xy 88.9 -217.17) (xy 90.043 -216.027)
				(xy 90.043 -214.884) (xy 97.917 -214.884) (xy 97.917 -216.535) (xy 98.552 -217.17) (xy 99.441 -217.17)
				(xy 100.711 -218.44) (xy 100.711 -219.329)
			)
		)
	)
	(zone
		(layer "F.Cu")
		(hatch none 0.5)
		(connect_pads
			(clearance 0)
		)
		(min_thickness 0.25)
		(keepout
			(tracks allowed)
			(vias allowed)
			(pads allowed)
			(copperpour allowed)
			(footprints allowed)
		)
		(placement
			(enabled no)
			(sheetname "")
		)
		(fill
			(thermal_gap 0.5)
			(thermal_bridge_width 0.5)
			(island_removal_mode 0)
		)
		(polygon
			(pts
				(xy 77.9272 -212.1154) (xy 77.9272 -210.6168) (xy 78.8416 -210.6168) (xy 78.8416 -212.1154)
			)
		)
	)
	(zone
		(layer "F.Cu")
		(hatch none 0.5)
		(connect_pads
			(clearance 0)
		)
		(min_thickness 0.25)
		(keepout
			(tracks allowed)
			(vias allowed)
			(pads allowed)
			(copperpour allowed)
			(footprints allowed)
		)
		(placement
			(enabled no)
			(sheetname "")
		)
		(fill
			(thermal_gap 0.5)
			(thermal_bridge_width 0.5)
			(island_removal_mode 0)
		)
		(polygon
			(pts
				(xy 222.377 -185.928) (xy 222.377 -169.291) (xy 224.536 -169.291) (xy 224.536 -185.928)
			)
		)
	)
	(zone
		(net "GND")
		(layer "F.Cu")
		(hatch none 0.5)
		(connect_pads
			(clearance 0.5)
		)
		(min_thickness 0.25)
		(fill yes
			(thermal_gap 0.5)
			(thermal_bridge_width 0.5)
			(island_removal_mode 0)
		)
		(polygon
			(pts
				(xy 93.20911 -91.313) (xy 92.929964 -91.592146) (xy 92.929964 -93.437964) (xy 93.1926 -93.7006)
				(xy 94.7674 -93.7006) (xy 94.869 -93.599) (xy 94.869 -91.621864) (xy 94.560136 -91.313)
			)
		)
		(polygon
			(pts
				(xy 94.2848 -92.9894) (xy 93.8022 -92.9894) (xy 93.8022 -93.1926) (xy 94.2848 -93.1926)
			)
		)
		(polygon
			(pts
				(xy 93.3958 -92.9894) (xy 93.1926 -92.9894) (xy 93.1926 -93.1926) (xy 93.3958 -93.1926)
			)
		)
	)
	(zone
		(layer "F.Cu")
		(hatch none 0.5)
		(connect_pads
			(clearance 0)
		)
		(min_thickness 0.25)
		(keepout
			(tracks allowed)
			(vias allowed)
			(pads allowed)
			(copperpour allowed)
			(footprints allowed)
		)
		(placement
			(enabled no)
			(sheetname "")
		)
		(fill
			(thermal_gap 0.5)
			(thermal_bridge_width 0.5)
			(island_removal_mode 0)
		)
		(polygon
			(pts
				(xy 95.123 -313.69) (xy 95.123 -311.785) (xy 92.075 -311.785) (xy 91.694 -312.166) (xy 91.694 -313.69)
				(xy 86.233 -313.69) (xy 86.233 -312.928) (xy 87.63 -311.531) (xy 88.9 -311.531) (xy 90.043 -310.388)
				(xy 90.043 -309.245) (xy 97.917 -309.245) (xy 97.917 -310.896) (xy 98.552 -311.531) (xy 99.441 -311.531)
				(xy 100.711 -312.801) (xy 100.711 -313.69)
			)
		)
	)
	(zone
		(layer "F.Cu")
		(hatch none 0.5)
		(connect_pads
			(clearance 0)
		)
		(min_thickness 0.25)
		(keepout
			(tracks allowed)
			(vias allowed)
			(pads allowed)
			(copperpour allowed)
			(footprints allowed)
		)
		(placement
			(enabled no)
			(sheetname "")
		)
		(fill
			(thermal_gap 0.5)
			(thermal_bridge_width 0.5)
			(island_removal_mode 0)
		)
		(polygon
			(pts
				(xy 37.338 -264.922) (xy 37.338 -257.81) (xy 39.497 -257.81) (xy 39.497 -264.922)
			)
		)
	)
	(zone
		(net "GND")
		(layer "F.Cu")
		(hatch none 0.5)
		(connect_pads
			(clearance 0.5)
		)
		(min_thickness 0.25)
		(fill yes
			(thermal_gap 0.5)
			(thermal_bridge_width 0.5)
			(island_removal_mode 0)
		)
		(polygon
			(pts
				(xy 36.195 -83.4136) (xy 35.4838 -84.1248) (xy 33.2994 -84.1248) (xy 33.02 -84.4042) (xy 33.02 -85.4964)
				(xy 33.3248 -85.8012) (xy 37.3888 -85.8012) (xy 37.846 -85.344) (xy 37.846 -83.6168) (xy 37.6428 -83.4136)
			)
		)
		(polygon
			(pts
				(xy 37.4142 -85.09) (xy 37.211 -85.09) (xy 37.211 -85.2932) (xy 37.4142 -85.2932)
			)
		)
		(polygon
			(pts
				(xy 36.8046 -85.09) (xy 36.6014 -85.09) (xy 36.6014 -85.2932) (xy 36.8046 -85.2932)
			)
		)
	)
	(zone
		(layer "F.Cu")
		(hatch none 0.5)
		(connect_pads
			(clearance 0)
		)
		(min_thickness 0.25)
		(keepout
			(tracks allowed)
			(vias allowed)
			(pads allowed)
			(copperpour allowed)
			(footprints allowed)
		)
		(placement
			(enabled no)
			(sheetname "")
		)
		(fill
			(thermal_gap 0.5)
			(thermal_bridge_width 0.5)
			(island_removal_mode 0)
		)
		(polygon
			(pts
				(xy 24.638 -241.046) (xy 24.638 -248.158) (xy 22.479 -248.158) (xy 22.479 -241.046)
			)
		)
	)
	(zone
		(layer "F.Cu")
		(hatch none 0.5)
		(connect_pads
			(clearance 0)
		)
		(min_thickness 0.25)
		(keepout
			(tracks not_allowed)
			(vias allowed)
			(pads allowed)
			(copperpour not_allowed)
			(footprints allowed)
		)
		(placement
			(enabled no)
			(sheetname "")
		)
		(fill
			(thermal_gap 0.5)
			(thermal_bridge_width 0.5)
			(island_removal_mode 0)
		)
		(polygon
			(pts
				(xy 92.39504 -426.79239) (xy 92.56522 -426.79239) (xy 92.56522 -427.96079) (xy 92.39504 -427.96079)
			)
		)
	)
	(zone
		(layer "F.Cu")
		(hatch none 0.5)
		(connect_pads
			(clearance 0)
		)
		(min_thickness 0.25)
		(keepout
			(tracks allowed)
			(vias allowed)
			(pads allowed)
			(copperpour allowed)
			(footprints allowed)
		)
		(placement
			(enabled no)
			(sheetname "")
		)
		(fill
			(thermal_gap 0.5)
			(thermal_bridge_width 0.5)
			(island_removal_mode 0)
		)
		(polygon
			(pts
				(xy 227.2284 -34.1376) (xy 227.2284 -35.0012) (xy 226.0346 -35.0012) (xy 226.0346 -34.1376)
			)
		)
	)
	(zone
		(net "GND")
		(layer "F.Cu")
		(hatch none 0.5)
		(connect_pads
			(clearance 0.5)
		)
		(min_thickness 0.25)
		(fill yes
			(thermal_gap 0.5)
			(thermal_bridge_width 0.5)
			(island_removal_mode 0)
		)
		(polygon
			(pts
				(xy 44.19854 -306.16271) (xy 41.368726 -308.992524) (xy 41.368726 -317.686436) (xy 42.71518 -319.03289)
				(xy 62.558422 -319.03289) (xy 63.119 -319.593468) (xy 63.119 -321.945) (xy 62.544706 -322.519294)
				(xy 28.480512 -322.519294) (xy 27.325574 -323.674232) (xy 27.325574 -336.717386) (xy 27.728672 -337.120484)
				(xy 29.224732 -337.120484) (xy 32.589216 -333.756) (xy 73.025 -333.756) (xy 84.455 -322.326) (xy 84.455 -318.4398)
				(xy 78.232 -312.2168) (xy 76.6826 -312.2168) (xy 70.62851 -306.16271)
			)
		)
	)
	(zone
		(layer "F.Cu")
		(hatch none 0.5)
		(connect_pads
			(clearance 0)
		)
		(min_thickness 0.25)
		(keepout
			(tracks not_allowed)
			(vias allowed)
			(pads allowed)
			(copperpour not_allowed)
			(footprints allowed)
		)
		(placement
			(enabled no)
			(sheetname "")
		)
		(fill
			(thermal_gap 0.5)
			(thermal_bridge_width 0.5)
			(island_removal_mode 0)
		)
		(polygon
			(pts
				(arc
					(start 37.33927 -182.231538)
					(mid 36.727257 -181.619144)
					(end 36.11499 -182.231284)
				)
				(arc
					(start 36.11499 -183.348884)
					(mid 36.72713 -183.961024)
					(end 37.33927 -183.348884)
				)
				(xy 37.33927 -183.04256) (xy 37.174932 -183.04256)
				(arc
					(start 36.972748 -183.244744)
					(mid 36.538486 -183.537528)
					(end 36.83127 -183.103266)
				)
				(xy 37.092128 -182.842408) (xy 37.33927 -182.842408) (xy 37.33927 -182.737506) (xy 37.091874 -182.737506)
				(arc
					(start 36.83127 -182.476902)
					(mid 36.538486 -182.04264)
					(end 36.972748 -182.335424)
				)
				(xy 37.174678 -182.537354) (xy 37.33927 -182.537354)
			)
		)
	)
	(zone
		(layer "F.Cu")
		(hatch none 0.5)
		(connect_pads
			(clearance 0)
		)
		(min_thickness 0.25)
		(keepout
			(tracks allowed)
			(vias allowed)
			(pads allowed)
			(copperpour allowed)
			(footprints allowed)
		)
		(placement
			(enabled no)
			(sheetname "")
		)
		(fill
			(thermal_gap 0.5)
			(thermal_bridge_width 0.5)
			(island_removal_mode 0)
		)
		(polygon
			(pts
				(xy 91.821 -93.091) (xy 91.821 -94.615) (xy 92.202 -94.996) (xy 94.869 -94.996) (xy 94.996 -94.869)
				(xy 94.996 -93.091) (xy 100.711 -93.091) (xy 100.711 -94.361) (xy 99.822 -95.25) (xy 99.06 -95.25)
				(xy 97.917 -96.393) (xy 97.917 -97.536) (xy 90.043 -97.536) (xy 90.043 -96.139) (xy 89.154 -95.25)
				(xy 87.757 -95.25) (xy 86.106 -93.599) (xy 86.106 -93.091)
			)
		)
	)
	(zone
		(layer "F.Cu")
		(hatch none 0.5)
		(connect_pads
			(clearance 0)
		)
		(min_thickness 0.25)
		(keepout
			(tracks not_allowed)
			(vias allowed)
			(pads allowed)
			(copperpour not_allowed)
			(footprints allowed)
		)
		(placement
			(enabled no)
			(sheetname "")
		)
		(fill
			(thermal_gap 0.5)
			(thermal_bridge_width 0.5)
			(island_removal_mode 0)
		)
		(polygon
			(pts
				(xy 1.022096 -460.195676) (xy 3.758184 -460.195676) (xy 3.81 -460.247492) (xy 3.81 -460.439008)
				(xy 3.761232 -460.487776) (xy 1.025398 -460.487776) (xy 1.014984 -460.49819) (xy 1.010158 -460.49819)
				(xy 1.005332 -460.493364) (xy 1.005332 -460.19085) (xy 1.007872 -460.18831) (xy 1.01473 -460.18831)
			)
		)
	)
	(zone
		(layer "F.Cu")
		(hatch none 0.5)
		(connect_pads
			(clearance 0)
		)
		(min_thickness 0.25)
		(keepout
			(tracks not_allowed)
			(vias allowed)
			(pads allowed)
			(copperpour not_allowed)
			(footprints allowed)
		)
		(placement
			(enabled no)
			(sheetname "")
		)
		(fill
			(thermal_gap 0.5)
			(thermal_bridge_width 0.5)
			(island_removal_mode 0)
		)
		(polygon
			(pts
				(arc
					(start 27.18054 -141.603476)
					(mid 26.67 -141.092936)
					(end 26.15946 -141.603476)
				)
				(xy 26.15946 -141.757146) (xy 26.374852 -141.757146)
				(arc
					(start 26.424382 -141.707616)
					(mid 26.858644 -141.414832)
					(end 26.56586 -141.849094)
				)
				(xy 26.457656 -141.957298) (xy 26.15946 -141.957298) (xy 26.15946 -142.0622) (xy 26.457402 -142.0622)
				(arc
					(start 26.56586 -142.170658)
					(mid 26.858644 -142.60492)
					(end 26.424382 -142.312136)
				)
				(xy 26.374598 -142.262352) (xy 26.15946 -142.262352)
				(arc
					(start 26.15946 -142.416022)
					(mid 26.669873 -142.926816)
					(end 27.18054 -142.416276)
				)
			)
		)
	)
	(zone
		(layer "F.Cu")
		(hatch none 0.5)
		(connect_pads
			(clearance 0)
		)
		(min_thickness 0.25)
		(keepout
			(tracks not_allowed)
			(vias allowed)
			(pads allowed)
			(copperpour not_allowed)
			(footprints allowed)
		)
		(placement
			(enabled no)
			(sheetname "")
		)
		(fill
			(thermal_gap 0.5)
			(thermal_bridge_width 0.5)
			(island_removal_mode 0)
		)
		(polygon
			(pts
				(arc
					(start 25.88514 -139.051284)
					(mid 25.273127 -138.43889)
					(end 24.66086 -139.05103)
				)
				(xy 24.66086 -139.32027) (xy 24.862282 -139.32027)
				(arc
					(start 25.027382 -139.15517)
					(mid 25.461644 -138.862386)
					(end 25.16886 -139.296648)
				)
				(xy 24.945086 -139.520422) (xy 24.66086 -139.520422) (xy 24.66086 -139.625324) (xy 24.871172 -139.625324)
				(arc
					(start 25.16886 -139.923012)
					(mid 25.461644 -140.357274)
					(end 25.027382 -140.06449)
				)
				(xy 24.788368 -139.825476) (xy 24.66086 -139.825476)
				(arc
					(start 24.66086 -140.16863)
					(mid 25.273 -140.78077)
					(end 25.88514 -140.16863)
				)
			)
		)
	)
	(zone
		(layer "F.Cu")
		(hatch none 0.5)
		(connect_pads
			(clearance 0)
		)
		(min_thickness 0.25)
		(keepout
			(tracks allowed)
			(vias allowed)
			(pads allowed)
			(copperpour allowed)
			(footprints allowed)
		)
		(placement
			(enabled no)
			(sheetname "")
		)
		(fill
			(thermal_gap 0.5)
			(thermal_bridge_width 0.5)
			(island_removal_mode 0)
		)
		(polygon
			(pts
				(xy 7.239 -234.696) (xy 1.905 -234.696) (xy 1.905 -189.992) (xy 7.239 -189.992)
			)
		)
	)
	(zone
		(layers "F.Cu" "B.Cu")
		(hatch none 0.5)
		(connect_pads
			(clearance 0)
		)
		(min_thickness 0.25)
		(keepout
			(tracks not_allowed)
			(vias allowed)
			(pads allowed)
			(copperpour not_allowed)
			(footprints allowed)
		)
		(placement
			(enabled no)
			(sheetname "")
		)
		(fill yes
			(thermal_gap 0.5)
			(thermal_bridge_width 0.5)
			(island_removal_mode 0)
		)
		(polygon
			(pts
				(arc
					(start 229.907084 -265.279632)
					(mid 229.396544 -265.790172)
					(end 229.907084 -266.300712)
				)
				(xy 230.060754 -266.300712) (xy 230.060754 -266.08532)
				(arc
					(start 230.011224 -266.03579)
					(mid 229.71844 -265.601528)
					(end 230.152702 -265.894312)
				)
				(xy 230.260906 -266.002516) (xy 230.260906 -266.300712) (xy 230.365808 -266.300712) (xy 230.365808 -266.00277)
				(arc
					(start 230.474266 -265.894312)
					(mid 230.908528 -265.601528)
					(end 230.615744 -266.03579)
				)
				(xy 230.56596 -266.085574) (xy 230.56596 -266.300712)
				(arc
					(start 230.71963 -266.300712)
					(mid 231.230424 -265.790299)
					(end 230.719884 -265.279632)
				)
			)
		)
	)
	(zone
		(layers "F.Cu" "B.Cu")
		(hatch none 0.5)
		(connect_pads
			(clearance 0)
		)
		(min_thickness 0.25)
		(keepout
			(tracks not_allowed)
			(vias allowed)
			(pads allowed)
			(copperpour not_allowed)
			(footprints allowed)
		)
		(placement
			(enabled no)
			(sheetname "")
		)
		(fill yes
			(thermal_gap 0.5)
			(thermal_bridge_width 0.5)
			(island_removal_mode 0)
		)
		(polygon
			(pts
				(xy 230.366062 -60.00242)
				(arc
					(start 230.474266 -59.894216)
					(mid 230.908528 -59.601432)
					(end 230.615744 -60.035694)
				)
				(xy 230.56596 -60.085478) (xy 230.56596 -60.300616)
				(arc
					(start 230.71963 -60.300616)
					(mid 231.230424 -59.790203)
					(end 230.719884 -59.279536)
				)
				(arc
					(start 229.907084 -59.279536)
					(mid 229.396544 -59.790076)
					(end 229.907084 -60.300616)
				)
				(xy 230.060754 -60.300616) (xy 230.060754 -60.085224)
				(arc
					(start 230.011224 -60.035694)
					(mid 229.71844 -59.601432)
					(end 230.152702 -59.894216)
				)
				(xy 230.260906 -60.00242) (xy 230.260906 -60.300616) (xy 230.365808 -60.300616) (xy 230.365808 -60.002674)
			)
		)
	)
	(zone
		(layers "F.Cu" "B.Cu")
		(hatch none 0.5)
		(connect_pads
			(clearance 0)
		)
		(min_thickness 0.25)
		(keepout
			(tracks not_allowed)
			(vias allowed)
			(pads allowed)
			(copperpour not_allowed)
			(footprints allowed)
		)
		(placement
			(enabled no)
			(sheetname "")
		)
		(fill yes
			(thermal_gap 0.5)
			(thermal_bridge_width 0.5)
			(island_removal_mode 0)
		)
		(polygon
			(pts
				(arc
					(start 44.907454 -59.279536)
					(mid 44.39666 -59.789949)
					(end 44.9072 -60.300616)
				)
				(xy 45.06087 -60.300616) (xy 45.06087 -60.085224)
				(arc
					(start 45.01134 -60.035694)
					(mid 44.718556 -59.601432)
					(end 45.152818 -59.894216)
				)
				(xy 45.261022 -60.00242) (xy 45.261022 -60.300616) (xy 45.365924 -60.300616) (xy 45.365924 -60.002674)
				(arc
					(start 45.474382 -59.894216)
					(mid 45.908644 -59.601432)
					(end 45.61586 -60.035694)
				)
				(xy 45.566076 -60.085478) (xy 45.566076 -60.300616)
				(arc
					(start 45.72 -60.300616)
					(mid 46.23054 -59.790076)
					(end 45.72 -59.279536)
				)
			)
		)
	)
	(zone
		(layers "F.Cu" "B.Cu")
		(hatch none 0.5)
		(connect_pads
			(clearance 0)
		)
		(min_thickness 0.25)
		(keepout
			(tracks not_allowed)
			(vias allowed)
			(pads allowed)
			(copperpour not_allowed)
			(footprints allowed)
		)
		(placement
			(enabled no)
			(sheetname "")
		)
		(fill yes
			(thermal_gap 0.5)
			(thermal_bridge_width 0.5)
			(island_removal_mode 0)
		)
		(polygon
			(pts
				(arc
					(start 17.78254 -32.60344)
					(mid 17.272127 -32.092646)
					(end 16.76146 -32.603186)
				)
				(arc
					(start 16.76146 -33.415986)
					(mid 17.272 -33.926526)
					(end 17.78254 -33.415986)
				)
				(xy 17.78254 -33.262062) (xy 17.567402 -33.262062)
				(arc
					(start 17.517618 -33.311846)
					(mid 17.083356 -33.60463)
					(end 17.37614 -33.170368)
				)
				(xy 17.484598 -33.06191) (xy 17.78254 -33.06191) (xy 17.78254 -32.957008) (xy 17.484344 -32.957008)
				(arc
					(start 17.37614 -32.848804)
					(mid 17.083356 -32.414542)
					(end 17.517618 -32.707326)
				)
				(xy 17.567148 -32.756856) (xy 17.78254 -32.756856)
			)
		)
	)
	(zone
		(layers "F.Cu" "B.Cu")
		(hatch none 0.5)
		(connect_pads
			(clearance 0)
		)
		(min_thickness 0.25)
		(keepout
			(tracks not_allowed)
			(vias allowed)
			(pads allowed)
			(copperpour not_allowed)
			(footprints allowed)
		)
		(placement
			(enabled no)
			(sheetname "")
		)
		(fill yes
			(thermal_gap 0.5)
			(thermal_bridge_width 0.5)
			(island_removal_mode 0)
		)
		(polygon
			(pts
				(arc
					(start 44.907454 -265.279632)
					(mid 44.39666 -265.790045)
					(end 44.9072 -266.300712)
				)
				(xy 45.06087 -266.300712) (xy 45.06087 -266.08532)
				(arc
					(start 45.01134 -266.03579)
					(mid 44.718556 -265.601528)
					(end 45.152818 -265.894312)
				)
				(xy 45.261022 -266.002516) (xy 45.261022 -266.300712) (xy 45.365924 -266.300712) (xy 45.365924 -266.00277)
				(arc
					(start 45.474382 -265.894312)
					(mid 45.908644 -265.601528)
					(end 45.61586 -266.03579)
				)
				(xy 45.566076 -266.085574) (xy 45.566076 -266.300712)
				(arc
					(start 45.72 -266.300712)
					(mid 46.23054 -265.790172)
					(end 45.72 -265.279632)
				)
			)
		)
	)
	(zone
		(layers "F.Cu" "B.Cu")
		(hatch none 0.5)
		(connect_pads
			(clearance 0)
		)
		(min_thickness 0.25)
		(keepout
			(tracks not_allowed)
			(vias allowed)
			(pads allowed)
			(copperpour not_allowed)
			(footprints allowed)
		)
		(placement
			(enabled no)
			(sheetname "")
		)
		(fill yes
			(thermal_gap 0.5)
			(thermal_bridge_width 0.5)
			(island_removal_mode 0)
		)
		(polygon
			(pts
				(arc
					(start 229.907084 -368.27968)
					(mid 229.396544 -368.79022)
					(end 229.907084 -369.30076)
				)
				(xy 230.060754 -369.30076) (xy 230.060754 -369.085368)
				(arc
					(start 230.011224 -369.035838)
					(mid 229.71844 -368.601576)
					(end 230.152702 -368.89436)
				)
				(xy 230.260906 -369.002564) (xy 230.260906 -369.30076) (xy 230.365808 -369.30076) (xy 230.365808 -369.002818)
				(arc
					(start 230.474266 -368.89436)
					(mid 230.908528 -368.601576)
					(end 230.615744 -369.035838)
				)
				(xy 230.56596 -369.085622) (xy 230.56596 -369.30076)
				(arc
					(start 230.71963 -369.30076)
					(mid 231.230424 -368.790347)
					(end 230.719884 -368.27968)
				)
			)
		)
	)
	(zone
		(layers "F.Cu" "B.Cu")
		(hatch none 0.5)
		(connect_pads
			(clearance 0)
		)
		(min_thickness 0.25)
		(keepout
			(tracks not_allowed)
			(vias allowed)
			(pads allowed)
			(copperpour not_allowed)
			(footprints allowed)
		)
		(placement
			(enabled no)
			(sheetname "")
		)
		(fill yes
			(thermal_gap 0.5)
			(thermal_bridge_width 0.5)
			(island_removal_mode 0)
		)
		(polygon
			(pts
				(arc
					(start 229.907084 -471.279728)
					(mid 229.396544 -471.790268)
					(end 229.907084 -472.300808)
				)
				(xy 230.060754 -472.300808) (xy 230.060754 -472.085416)
				(arc
					(start 230.011224 -472.035886)
					(mid 229.71844 -471.601624)
					(end 230.152702 -471.894408)
				)
				(xy 230.260906 -472.002612) (xy 230.260906 -472.300808) (xy 230.365808 -472.300808) (xy 230.365808 -472.002866)
				(arc
					(start 230.474266 -471.894408)
					(mid 230.908528 -471.601624)
					(end 230.615744 -472.035886)
				)
				(xy 230.56596 -472.08567) (xy 230.56596 -472.300808)
				(arc
					(start 230.71963 -472.300808)
					(mid 231.230424 -471.790395)
					(end 230.719884 -471.279728)
				)
			)
		)
	)
	(zone
		(layers "F.Cu" "B.Cu")
		(hatch none 0.5)
		(connect_pads
			(clearance 0)
		)
		(min_thickness 0.25)
		(keepout
			(tracks not_allowed)
			(vias allowed)
			(pads allowed)
			(copperpour not_allowed)
			(footprints allowed)
		)
		(placement
			(enabled no)
			(sheetname "")
		)
		(fill yes
			(thermal_gap 0.5)
			(thermal_bridge_width 0.5)
			(island_removal_mode 0)
		)
		(polygon
			(pts
				(arc
					(start 44.9072 -471.279728)
					(mid 44.39666 -471.790268)
					(end 44.9072 -472.300808)
				)
				(xy 45.06087 -472.300808) (xy 45.06087 -472.085416)
				(arc
					(start 45.01134 -472.035886)
					(mid 44.718556 -471.601624)
					(end 45.152818 -471.894408)
				)
				(xy 45.261022 -472.002612) (xy 45.261022 -472.300808) (xy 45.365924 -472.300808) (xy 45.365924 -472.002866)
				(arc
					(start 45.474382 -471.894408)
					(mid 45.908644 -471.601624)
					(end 45.61586 -472.035886)
				)
				(xy 45.566076 -472.08567) (xy 45.566076 -472.300808)
				(arc
					(start 45.719746 -472.300808)
					(mid 46.23054 -471.790395)
					(end 45.72 -471.279728)
				)
			)
		)
	)
	(zone
		(layers "F.Cu" "B.Cu")
		(hatch none 0.5)
		(connect_pads
			(clearance 0)
		)
		(min_thickness 0.25)
		(keepout
			(tracks not_allowed)
			(vias allowed)
			(pads allowed)
			(copperpour not_allowed)
			(footprints allowed)
		)
		(placement
			(enabled no)
			(sheetname "")
		)
		(fill yes
			(thermal_gap 0.5)
			(thermal_bridge_width 0.5)
			(island_removal_mode 0)
		)
		(polygon
			(pts
				(arc
					(start 229.907084 -162.279584)
					(mid 229.396544 -162.790124)
					(end 229.907084 -163.300664)
				)
				(xy 230.060754 -163.300664) (xy 230.060754 -163.085272)
				(arc
					(start 230.011224 -163.035742)
					(mid 229.71844 -162.60148)
					(end 230.152702 -162.894264)
				)
				(xy 230.260906 -163.002468) (xy 230.260906 -163.300664) (xy 230.365808 -163.300664) (xy 230.365808 -163.002722)
				(arc
					(start 230.474266 -162.894264)
					(mid 230.908528 -162.60148)
					(end 230.615744 -163.035742)
				)
				(xy 230.56596 -163.085526) (xy 230.56596 -163.300664)
				(arc
					(start 230.71963 -163.300664)
					(mid 231.230424 -162.790251)
					(end 230.719884 -162.279584)
				)
			)
		)
	)
	(zone
		(layers "F.Cu" "B.Cu")
		(hatch none 0.5)
		(connect_pads
			(clearance 0)
		)
		(min_thickness 0.25)
		(keepout
			(tracks not_allowed)
			(vias allowed)
			(pads allowed)
			(copperpour not_allowed)
			(footprints allowed)
		)
		(placement
			(enabled no)
			(sheetname "")
		)
		(fill yes
			(thermal_gap 0.5)
			(thermal_bridge_width 0.5)
			(island_removal_mode 0)
		)
		(polygon
			(pts
				(arc
					(start 44.907454 -162.279584)
					(mid 44.39666 -162.789997)
					(end 44.9072 -163.300664)
				)
				(xy 45.06087 -163.300664) (xy 45.06087 -163.085272)
				(arc
					(start 45.01134 -163.035742)
					(mid 44.718556 -162.60148)
					(end 45.152818 -162.894264)
				)
				(xy 45.261022 -163.002468) (xy 45.261022 -163.300664) (xy 45.365924 -163.300664) (xy 45.365924 -163.002722)
				(arc
					(start 45.474382 -162.894264)
					(mid 45.908644 -162.60148)
					(end 45.61586 -163.035742)
				)
				(xy 45.566076 -163.085526) (xy 45.566076 -163.300664)
				(arc
					(start 45.72 -163.300664)
					(mid 46.23054 -162.790124)
					(end 45.72 -162.279584)
				)
			)
		)
	)
	(zone
		(layers "F.Cu" "B.Cu")
		(hatch none 0.5)
		(connect_pads
			(clearance 0)
		)
		(min_thickness 0.25)
		(keepout
			(tracks not_allowed)
			(vias allowed)
			(pads allowed)
			(copperpour not_allowed)
			(footprints allowed)
		)
		(placement
			(enabled no)
			(sheetname "")
		)
		(fill yes
			(thermal_gap 0.5)
			(thermal_bridge_width 0.5)
			(island_removal_mode 0)
		)
		(polygon
			(pts
				(arc
					(start 44.907454 -368.27968)
					(mid 44.39666 -368.790093)
					(end 44.9072 -369.30076)
				)
				(xy 45.06087 -369.30076) (xy 45.06087 -369.085368)
				(arc
					(start 45.01134 -369.035838)
					(mid 44.718556 -368.601576)
					(end 45.152818 -368.89436)
				)
				(xy 45.261022 -369.002564) (xy 45.261022 -369.30076) (xy 45.365924 -369.30076) (xy 45.365924 -369.002818)
				(arc
					(start 45.474382 -368.89436)
					(mid 45.908644 -368.601576)
					(end 45.61586 -369.035838)
				)
				(xy 45.566076 -369.085622) (xy 45.566076 -369.30076)
				(arc
					(start 45.72 -369.30076)
					(mid 46.23054 -368.79022)
					(end 45.72 -368.27968)
				)
			)
		)
	)
	(zone
		(layers "F.Cu" "B.Cu" "In1.Cu" "In2.Cu" "In3.Cu" "In4.Cu" "In5.Cu" "In6.Cu")
		(name "Package Keepin")
		(hatch none 0.5)
		(connect_pads
			(clearance 0)
		)
		(min_thickness 0.25)
		(keepout
			(tracks allowed)
			(vias allowed)
			(pads allowed)
			(copperpour allowed)
			(footprints allowed)
		)
		(placement
			(enabled no)
			(sheetname "")
		)
		(fill
			(thermal_gap 0.5)
			(thermal_bridge_width 0.5)
			(island_removal_mode 0)
		)
		(polygon
			(pts
				(arc
					(start 258.496308 -431.492914)
					(mid 255.872311 -429.185229)
					(end 254.896112 -425.829984)
				)
				(xy 254.896112 -415.488882)
				(arc
					(start 252.394974 -415.488882)
					(mid 246.85625 -409.950158)
					(end 252.394974 -404.41118)
				)
				(xy 254.896112 -404.41118)
				(arc
					(start 254.896112 -364.16996)
					(mid 255.872369 -360.814751)
					(end 258.496308 -358.50703)
				)
				(xy 258.496308 -5.0038) (xy 5.0038 -5.0038)
				(arc
					(start 5.0038 -182.268114)
					(mid 10.503878 -188.342016)
					(end 5.0038 -194.415918)
				)
				(arc
					(start 5.0038 -308.268116)
					(mid 10.503878 -314.342018)
					(end 5.0038 -320.41592)
				)
				(arc
					(start 5.0038 -414.268158)
					(mid 10.503878 -420.342047)
					(end 5.0038 -426.415708)
				)
				(xy 5.0038 -500.996204) (xy 258.496308 -500.996204)
			)
		)
	)
	(zone
		(layers "F.Cu" "B.Cu" "In1.Cu" "In2.Cu" "In3.Cu" "In4.Cu" "In5.Cu" "In6.Cu")
		(name "Route Keepin")
		(hatch none 0.5)
		(connect_pads
			(clearance 0)
		)
		(min_thickness 0.25)
		(keepout
			(tracks allowed)
			(vias allowed)
			(pads allowed)
			(copperpour allowed)
			(footprints allowed)
		)
		(placement
			(enabled no)
			(sheetname "")
		)
		(fill
			(thermal_gap 0.5)
			(thermal_bridge_width 0.5)
			(island_removal_mode 0)
		)
		(polygon
			(pts
				(arc
					(start 36.34232 -3.365246)
					(mid 36.282429 -3.527636)
					(end 36.262056 -3.69951)
				)
				(arc
					(start 36.262056 -4.500118)
					(mid 34.000186 -6.761988)
					(end 31.738062 -4.500118)
				)
				(arc
					(start 31.738062 -3.700018)
					(mid 31.717712 -3.52789)
					(end 31.657798 -3.365246)
				)
				(xy 31.657544 -3.365246) (xy 30.332934 -0.762)
				(arc
					(start 0.999998 -0.762)
					(mid 0.831708 -0.831708)
					(end 0.762 -0.999998)
				)
				(xy 0.762 -186.426348) (xy 0.815594 -186.479942)
				(arc
					(start 4.400042 -186.479942)
					(mid 6.262116 -188.342016)
					(end 4.400042 -190.20409)
				)
				(xy 0.815594 -190.20409) (xy 0.762 -190.257684) (xy 0.762 -312.42635) (xy 0.815594 -312.479944)
				(arc
					(start 4.400042 -312.479944)
					(mid 6.262116 -314.342018)
					(end 4.400042 -316.204092)
				)
				(xy 0.815594 -316.204092) (xy 0.762 -316.257686) (xy 0.762 -418.426392) (xy 0.815594 -418.479986)
				(arc
					(start 4.400042 -418.479986)
					(mid 6.262116 -420.34206)
					(end 4.400042 -422.20388)
				)
				(xy 0.815848 -422.20388) (xy 0.762 -422.257728)
				(arc
					(start 0.762 -505.000006)
					(mid 0.831708 -505.168296)
					(end 0.999998 -505.238004)
				)
				(arc
					(start 262.50011 -505.238004)
					(mid 262.6684 -505.168296)
					(end 262.738108 -505.000006)
				)
				(xy 262.738108 -428.395638) (xy 262.184388 -427.841918)
				(arc
					(start 261.2898 -427.841918)
					(mid 259.768185 -427.211645)
					(end 259.137912 -425.69003)
				)
				(xy 259.137912 -411.800802) (xy 258.584192 -411.247082)
				(arc
					(start 252.394974 -411.247082)
					(mid 251.09805 -409.950158)
					(end 252.394974 -408.65298)
				)
				(xy 258.584192 -408.65298) (xy 259.137912 -408.09926)
				(arc
					(start 259.137912 -364.309914)
					(mid 259.76826 -362.788374)
					(end 261.2898 -362.158026)
				)
				(xy 262.184388 -362.158026) (xy 262.738108 -361.604306)
				(arc
					(start 262.738108 -0.999998)
					(mid 262.6684 -0.831708)
					(end 262.50011 -0.762)
				)
				(xy 37.667184 -0.762)
			)
		)
	)
	(zone
		(layers "F.Cu" "B.Cu" "In2.Cu" "In5.Cu")
		(hatch none 0.5)
		(connect_pads
			(clearance 0)
		)
		(min_thickness 0.25)
		(keepout
			(tracks not_allowed)
			(vias allowed)
			(pads allowed)
			(copperpour not_allowed)
			(footprints allowed)
		)
		(placement
			(enabled no)
			(sheetname "")
		)
		(fill yes
			(thermal_gap 0.5)
			(thermal_bridge_width 0.5)
			(island_removal_mode 0)
		)
		(polygon
			(pts
				(xy 30.293056 -2.122678) (xy 30.293056 -0.542798) (xy 37.789866 -0.542798) (xy 37.789866 -2.122678)
			)
		)
	)
	(zone
		(layers "F.Cu" "In4.Cu")
		(hatch none 0.5)
		(connect_pads
			(clearance 0)
		)
		(min_thickness 0.25)
		(keepout
			(tracks not_allowed)
			(vias allowed)
			(pads allowed)
			(copperpour not_allowed)
			(footprints allowed)
		)
		(placement
			(enabled no)
			(sheetname "")
		)
		(fill yes
			(thermal_gap 0.5)
			(thermal_bridge_width 0.5)
			(island_removal_mode 0)
		)
		(polygon
			(pts
				(arc
					(start 249.499882 -170.997626)
					(mid 253.500128 -166.99738)
					(end 257.50012 -170.997626)
				)
				(arc
					(start 257.50012 -174.497492)
					(mid 253.500128 -178.497484)
					(end 249.499882 -174.497492)
				)
			)
		)
	)
	(zone
		(layers "F.Cu" "In4.Cu")
		(hatch none 0.5)
		(connect_pads
			(clearance 0)
		)
		(min_thickness 0.25)
		(keepout
			(tracks not_allowed)
			(vias allowed)
			(pads allowed)
			(copperpour not_allowed)
			(footprints allowed)
		)
		(placement
			(enabled no)
			(sheetname "")
		)
		(fill yes
			(thermal_gap 0.5)
			(thermal_bridge_width 0.5)
			(island_removal_mode 0)
		)
		(polygon
			(pts
				(arc
					(start 249.499882 -479.997516)
					(mid 253.500128 -475.99727)
					(end 257.50012 -479.997516)
				)
				(arc
					(start 257.50012 -483.497636)
					(mid 253.500128 -487.497628)
					(end 249.499882 -483.497636)
				)
			)
		)
	)
	(zone
		(layers "F.Cu" "In4.Cu")
		(hatch none 0.5)
		(connect_pads
			(clearance 0)
		)
		(min_thickness 0.25)
		(keepout
			(tracks not_allowed)
			(vias allowed)
			(pads allowed)
			(copperpour not_allowed)
			(footprints allowed)
		)
		(placement
			(enabled no)
			(sheetname "")
		)
		(fill yes
			(thermal_gap 0.5)
			(thermal_bridge_width 0.5)
			(island_removal_mode 0)
		)
		(polygon
			(pts
				(arc
					(start 66.000122 -170.4975)
					(mid 70.000114 -166.497508)
					(end 74.000106 -170.4975)
				)
				(arc
					(start 74.000106 -173.99762)
					(mid 70.000114 -177.997612)
					(end 66.000122 -173.99762)
				)
			)
		)
	)
	(zone
		(layers "F.Cu" "In4.Cu")
		(hatch none 0.5)
		(connect_pads
			(clearance 0)
		)
		(min_thickness 0.25)
		(keepout
			(tracks not_allowed)
			(vias allowed)
			(pads allowed)
			(copperpour not_allowed)
			(footprints allowed)
		)
		(placement
			(enabled no)
			(sheetname "")
		)
		(fill yes
			(thermal_gap 0.5)
			(thermal_bridge_width 0.5)
			(island_removal_mode 0)
		)
		(polygon
			(pts
				(arc
					(start 66.000122 -67.499992)
					(mid 70.000114 -63.5)
					(end 74.000106 -67.499992)
				)
				(arc
					(start 74.000106 -71.000112)
					(mid 70.000114 -75.000104)
					(end 66.000122 -71.000112)
				)
			)
		)
	)
	(zone
		(layers "F.Cu" "In4.Cu")
		(hatch none 0.5)
		(connect_pads
			(clearance 0)
		)
		(min_thickness 0.25)
		(keepout
			(tracks not_allowed)
			(vias allowed)
			(pads allowed)
			(copperpour not_allowed)
			(footprints allowed)
		)
		(placement
			(enabled no)
			(sheetname "")
		)
		(fill yes
			(thermal_gap 0.5)
			(thermal_bridge_width 0.5)
			(island_removal_mode 0)
		)
		(polygon
			(pts
				(arc
					(start 66.000122 -479.997516)
					(mid 70.000114 -475.997524)
					(end 74.000106 -479.997516)
				)
				(arc
					(start 74.000106 -483.497636)
					(mid 70.000114 -487.497628)
					(end 66.000122 -483.497636)
				)
			)
		)
	)
	(zone
		(layers "F.Cu" "In4.Cu")
		(hatch none 0.5)
		(connect_pads
			(clearance 0)
		)
		(min_thickness 0.25)
		(keepout
			(tracks not_allowed)
			(vias allowed)
			(pads allowed)
			(copperpour not_allowed)
			(footprints allowed)
		)
		(placement
			(enabled no)
			(sheetname "")
		)
		(fill yes
			(thermal_gap 0.5)
			(thermal_bridge_width 0.5)
			(island_removal_mode 0)
		)
		(polygon
			(pts
				(arc
					(start 249.499882 -271.497552)
					(mid 253.500128 -267.497306)
					(end 257.50012 -271.497552)
				)
				(arc
					(start 257.50012 -274.997418)
					(mid 253.500128 -278.99741)
					(end 249.499882 -274.997418)
				)
			)
		)
	)
	(zone
		(layers "F.Cu" "In4.Cu")
		(hatch none 0.5)
		(connect_pads
			(clearance 0)
		)
		(min_thickness 0.25)
		(keepout
			(tracks not_allowed)
			(vias allowed)
			(pads allowed)
			(copperpour not_allowed)
			(footprints allowed)
		)
		(placement
			(enabled no)
			(sheetname "")
		)
		(fill yes
			(thermal_gap 0.5)
			(thermal_bridge_width 0.5)
			(island_removal_mode 0)
		)
		(polygon
			(pts
				(arc
					(start 249.499882 -37.997638)
					(mid 253.500128 -33.997392)
					(end 257.50012 -37.997638)
				)
				(arc
					(start 257.50012 -41.497504)
					(mid 253.500128 -45.497496)
					(end 249.499882 -41.497504)
				)
			)
		)
	)
	(zone
		(layers "F.Cu" "In4.Cu")
		(hatch none 0.5)
		(connect_pads
			(clearance 0)
		)
		(min_thickness 0.25)
		(keepout
			(tracks not_allowed)
			(vias allowed)
			(pads allowed)
			(copperpour not_allowed)
			(footprints allowed)
		)
		(placement
			(enabled no)
			(sheetname "")
		)
		(fill yes
			(thermal_gap 0.5)
			(thermal_bridge_width 0.5)
			(island_removal_mode 0)
		)
		(polygon
			(pts
				(arc
					(start 66.000122 -272.997422)
					(mid 70.000114 -268.99743)
					(end 74.000106 -272.997422)
				)
				(arc
					(start 74.000106 -276.497542)
					(mid 70.000114 -280.497534)
					(end 66.000122 -276.497542)
				)
			)
		)
	)
	(zone
		(layers "F.Cu" "In4.Cu")
		(hatch none 0.5)
		(connect_pads
			(clearance 0)
		)
		(min_thickness 0.25)
		(keepout
			(tracks not_allowed)
			(vias allowed)
			(pads allowed)
			(copperpour not_allowed)
			(footprints allowed)
		)
		(placement
			(enabled no)
			(sheetname "")
		)
		(fill yes
			(thermal_gap 0.5)
			(thermal_bridge_width 0.5)
			(island_removal_mode 0)
		)
		(polygon
			(pts
				(arc
					(start 4.500118 -68.000118)
					(mid 8.50011 -64.000126)
					(end 12.500102 -68.000118)
				)
				(arc
					(start 12.500102 -71.499984)
					(mid 8.50011 -75.499976)
					(end 4.500118 -71.499984)
				)
			)
		)
	)
	(zone
		(layers "F.Cu" "In4.Cu")
		(hatch none 0.5)
		(connect_pads
			(clearance 0)
		)
		(min_thickness 0.25)
		(keepout
			(tracks not_allowed)
			(vias allowed)
			(pads allowed)
			(copperpour not_allowed)
			(footprints allowed)
		)
		(placement
			(enabled no)
			(sheetname "")
		)
		(fill yes
			(thermal_gap 0.5)
			(thermal_bridge_width 0.5)
			(island_removal_mode 0)
		)
		(polygon
			(pts
				(arc
					(start 1.500124 -484.89997)
					(mid 5.500116 -480.899978)
					(end 9.500108 -484.89997)
				)
				(arc
					(start 9.500108 -488.40009)
					(mid 5.500116 -492.400082)
					(end 1.500124 -488.40009)
				)
			)
		)
	)
	(zone
		(layers "F.Cu" "In5.Cu")
		(hatch none 0.5)
		(connect_pads
			(clearance 0)
		)
		(min_thickness 0.25)
		(keepout
			(tracks not_allowed)
			(vias allowed)
			(pads allowed)
			(copperpour not_allowed)
			(footprints allowed)
		)
		(placement
			(enabled no)
			(sheetname "")
		)
		(fill yes
			(thermal_gap 0.5)
			(thermal_bridge_width 0.5)
			(island_removal_mode 0)
		)
		(polygon
			(pts
				(arc
					(start 5.59054 -326.73544)
					(mid 5.08 -326.2249)
					(end 4.56946 -326.73544)
				)
				(arc
					(start 4.56946 -327.54824)
					(mid 5.07873 -328.058778)
					(end 5.59054 -327.55078)
				)
				(arc
					(start 5.3467 -327.55078)
					(mid 5.08 -327.814952)
					(end 4.8133 -327.55078)
				)
				(arc
					(start 4.8133 -327.54824)
					(mid 5.08 -327.28154)
					(end 5.3467 -327.54824)
				)
				(xy 5.59054 -327.54824) (xy 5.59054 -326.73798)
				(arc
					(start 5.3467 -326.73798)
					(mid 5.08 -327.002152)
					(end 4.8133 -326.73798)
				)
				(arc
					(start 4.8133 -326.73544)
					(mid 5.08 -326.46874)
					(end 5.3467 -326.73544)
				)
			)
		)
	)
	(zone
		(layers "F.Cu" "In5.Cu")
		(hatch none 0.5)
		(connect_pads
			(clearance 0)
		)
		(min_thickness 0.25)
		(keepout
			(tracks not_allowed)
			(vias allowed)
			(pads allowed)
			(copperpour not_allowed)
			(footprints allowed)
		)
		(placement
			(enabled no)
			(sheetname "")
		)
		(fill yes
			(thermal_gap 0.5)
			(thermal_bridge_width 0.5)
			(island_removal_mode 0)
		)
		(polygon
			(pts
				(arc
					(start 5.59054 -206.335376)
					(mid 5.08 -205.824836)
					(end 4.56946 -206.335376)
				)
				(arc
					(start 4.56946 -207.148176)
					(mid 5.07873 -207.658714)
					(end 5.59054 -207.150716)
				)
				(arc
					(start 5.3467 -207.150716)
					(mid 5.08 -207.414888)
					(end 4.8133 -207.150716)
				)
				(arc
					(start 4.8133 -207.148176)
					(mid 5.08 -206.881476)
					(end 5.3467 -207.148176)
				)
				(xy 5.59054 -207.148176) (xy 5.59054 -206.337916)
				(arc
					(start 5.3467 -206.337916)
					(mid 5.08 -206.602088)
					(end 4.8133 -206.337916)
				)
				(arc
					(start 4.8133 -206.335376)
					(mid 5.08 -206.068676)
					(end 5.3467 -206.335376)
				)
			)
		)
	)
	(zone
		(layers "F.Cu" "In5.Cu")
		(hatch none 0.5)
		(connect_pads
			(clearance 0)
		)
		(min_thickness 0.25)
		(keepout
			(tracks not_allowed)
			(vias allowed)
			(pads allowed)
			(copperpour not_allowed)
			(footprints allowed)
		)
		(placement
			(enabled no)
			(sheetname "")
		)
		(fill yes
			(thermal_gap 0.5)
			(thermal_bridge_width 0.5)
			(island_removal_mode 0)
		)
		(polygon
			(pts
				(arc
					(start 5.59054 -309.135526)
					(mid 5.08 -308.624986)
					(end 4.56946 -309.135526)
				)
				(arc
					(start 4.56946 -309.948326)
					(mid 5.07873 -310.458864)
					(end 5.59054 -309.950866)
				)
				(arc
					(start 5.3467 -309.950866)
					(mid 5.08 -310.215038)
					(end 4.8133 -309.950866)
				)
				(arc
					(start 4.8133 -309.948326)
					(mid 5.08 -309.681626)
					(end 5.3467 -309.948326)
				)
				(xy 5.59054 -309.948326) (xy 5.59054 -309.138066)
				(arc
					(start 5.3467 -309.138066)
					(mid 5.08 -309.402238)
					(end 4.8133 -309.138066)
				)
				(arc
					(start 4.8133 -309.135526)
					(mid 5.08 -308.868826)
					(end 5.3467 -309.135526)
				)
			)
		)
	)
	(zone
		(layers "F.Cu" "In5.Cu")
		(hatch none 0.5)
		(connect_pads
			(clearance 0)
		)
		(min_thickness 0.25)
		(keepout
			(tracks not_allowed)
			(vias allowed)
			(pads allowed)
			(copperpour not_allowed)
			(footprints allowed)
		)
		(placement
			(enabled no)
			(sheetname "")
		)
		(fill yes
			(thermal_gap 0.5)
			(thermal_bridge_width 0.5)
			(island_removal_mode 0)
		)
		(polygon
			(pts
				(arc
					(start 5.59054 -416.73526)
					(mid 5.08 -416.22472)
					(end 4.56946 -416.73526)
				)
				(arc
					(start 4.56946 -417.54806)
					(mid 5.07873 -418.058598)
					(end 5.59054 -417.5506)
				)
				(arc
					(start 5.3467 -417.5506)
					(mid 5.08 -417.814772)
					(end 4.8133 -417.5506)
				)
				(arc
					(start 4.8133 -417.54806)
					(mid 5.08 -417.28136)
					(end 5.3467 -417.54806)
				)
				(xy 5.59054 -417.54806) (xy 5.59054 -416.7378)
				(arc
					(start 5.3467 -416.7378)
					(mid 5.08 -417.001972)
					(end 4.8133 -416.7378)
				)
				(arc
					(start 4.8133 -416.73526)
					(mid 5.08 -416.46856)
					(end 5.3467 -416.73526)
				)
			)
		)
	)
	(zone
		(layers "F.Cu" "In5.Cu")
		(hatch none 0.5)
		(connect_pads
			(clearance 0)
		)
		(min_thickness 0.25)
		(keepout
			(tracks not_allowed)
			(vias allowed)
			(pads allowed)
			(copperpour not_allowed)
			(footprints allowed)
		)
		(placement
			(enabled no)
			(sheetname "")
		)
		(fill yes
			(thermal_gap 0.5)
			(thermal_bridge_width 0.5)
			(island_removal_mode 0)
		)
		(polygon
			(pts
				(arc
					(start 5.59054 -317.13551)
					(mid 5.08 -316.62497)
					(end 4.56946 -317.13551)
				)
				(arc
					(start 4.56946 -317.94831)
					(mid 5.07873 -318.458848)
					(end 5.59054 -317.95085)
				)
				(arc
					(start 5.3467 -317.95085)
					(mid 5.08 -318.215022)
					(end 4.8133 -317.95085)
				)
				(arc
					(start 4.8133 -317.94831)
					(mid 5.08 -317.68161)
					(end 5.3467 -317.94831)
				)
				(xy 5.59054 -317.94831) (xy 5.59054 -317.13805)
				(arc
					(start 5.3467 -317.13805)
					(mid 5.08 -317.402222)
					(end 4.8133 -317.13805)
				)
				(arc
					(start 4.8133 -317.13551)
					(mid 5.08 -316.86881)
					(end 5.3467 -317.13551)
				)
			)
		)
	)
	(zone
		(layers "F.Cu" "In5.Cu")
		(hatch none 0.5)
		(connect_pads
			(clearance 0)
		)
		(min_thickness 0.25)
		(keepout
			(tracks not_allowed)
			(vias allowed)
			(pads allowed)
			(copperpour not_allowed)
			(footprints allowed)
		)
		(placement
			(enabled no)
			(sheetname "")
		)
		(fill yes
			(thermal_gap 0.5)
			(thermal_bridge_width 0.5)
			(island_removal_mode 0)
		)
		(polygon
			(pts
				(arc
					(start 5.59054 -183.135524)
					(mid 5.08 -182.624984)
					(end 4.56946 -183.135524)
				)
				(arc
					(start 4.56946 -183.948324)
					(mid 5.07873 -184.458862)
					(end 5.59054 -183.950864)
				)
				(arc
					(start 5.3467 -183.950864)
					(mid 5.08 -184.215036)
					(end 4.8133 -183.950864)
				)
				(arc
					(start 4.8133 -183.948324)
					(mid 5.08 -183.681624)
					(end 5.3467 -183.948324)
				)
				(xy 5.59054 -183.948324) (xy 5.59054 -183.138064)
				(arc
					(start 5.3467 -183.138064)
					(mid 5.08 -183.402236)
					(end 4.8133 -183.138064)
				)
				(arc
					(start 4.8133 -183.135524)
					(mid 5.08 -182.868824)
					(end 5.3467 -183.135524)
				)
			)
		)
	)
	(zone
		(layers "F.Cu" "In5.Cu")
		(hatch none 0.5)
		(connect_pads
			(clearance 0)
		)
		(min_thickness 0.25)
		(keepout
			(tracks not_allowed)
			(vias allowed)
			(pads allowed)
			(copperpour not_allowed)
			(footprints allowed)
		)
		(placement
			(enabled no)
			(sheetname "")
		)
		(fill yes
			(thermal_gap 0.5)
			(thermal_bridge_width 0.5)
			(island_removal_mode 0)
		)
		(polygon
			(pts
				(arc
					(start 5.59054 -429.535082)
					(mid 5.08 -429.024542)
					(end 4.56946 -429.535082)
				)
				(arc
					(start 4.56946 -430.347882)
					(mid 5.07873 -430.85842)
					(end 5.59054 -430.350422)
				)
				(arc
					(start 5.3467 -430.350422)
					(mid 5.08 -430.614594)
					(end 4.8133 -430.350422)
				)
				(arc
					(start 4.8133 -430.347882)
					(mid 5.08 -430.081182)
					(end 5.3467 -430.347882)
				)
				(xy 5.59054 -430.347882) (xy 5.59054 -429.537622)
				(arc
					(start 5.3467 -429.537622)
					(mid 5.08 -429.801794)
					(end 4.8133 -429.537622)
				)
				(arc
					(start 4.8133 -429.535082)
					(mid 5.08 -429.268382)
					(end 5.3467 -429.535082)
				)
			)
		)
	)
	(zone
		(layers "F.Cu" "In5.Cu")
		(hatch none 0.5)
		(connect_pads
			(clearance 0)
		)
		(min_thickness 0.25)
		(keepout
			(tracks not_allowed)
			(vias allowed)
			(pads allowed)
			(copperpour not_allowed)
			(footprints allowed)
		)
		(placement
			(enabled no)
			(sheetname "")
		)
		(fill yes
			(thermal_gap 0.5)
			(thermal_bridge_width 0.5)
			(island_removal_mode 0)
		)
		(polygon
			(pts
				(arc
					(start 5.59054 -351.535492)
					(mid 5.08 -351.024952)
					(end 4.56946 -351.535492)
				)
				(arc
					(start 4.56946 -352.348292)
					(mid 5.07873 -352.85883)
					(end 5.59054 -352.350832)
				)
				(arc
					(start 5.3467 -352.350832)
					(mid 5.08 -352.615004)
					(end 4.8133 -352.350832)
				)
				(arc
					(start 4.8133 -352.348292)
					(mid 5.08 -352.081592)
					(end 5.3467 -352.348292)
				)
				(xy 5.59054 -352.348292) (xy 5.59054 -351.538032)
				(arc
					(start 5.3467 -351.538032)
					(mid 5.08 -351.802204)
					(end 4.8133 -351.538032)
				)
				(arc
					(start 4.8133 -351.535492)
					(mid 5.08 -351.268792)
					(end 5.3467 -351.535492)
				)
			)
		)
	)
	(zone
		(layers "F.Cu" "In5.Cu")
		(hatch none 0.5)
		(connect_pads
			(clearance 0)
		)
		(min_thickness 0.25)
		(keepout
			(tracks not_allowed)
			(vias allowed)
			(pads allowed)
			(copperpour not_allowed)
			(footprints allowed)
		)
		(placement
			(enabled no)
			(sheetname "")
		)
		(fill yes
			(thermal_gap 0.5)
			(thermal_bridge_width 0.5)
			(island_removal_mode 0)
		)
		(polygon
			(pts
				(arc
					(start 5.59054 -191.135508)
					(mid 5.08 -190.624968)
					(end 4.56946 -191.135508)
				)
				(arc
					(start 4.56946 -191.948308)
					(mid 5.07873 -192.458846)
					(end 5.59054 -191.950848)
				)
				(arc
					(start 5.3467 -191.950848)
					(mid 5.08 -192.21502)
					(end 4.8133 -191.950848)
				)
				(arc
					(start 4.8133 -191.948308)
					(mid 5.08 -191.681608)
					(end 5.3467 -191.948308)
				)
				(xy 5.59054 -191.948308) (xy 5.59054 -191.138048)
				(arc
					(start 5.3467 -191.138048)
					(mid 5.08 -191.40222)
					(end 4.8133 -191.138048)
				)
				(arc
					(start 4.8133 -191.135508)
					(mid 5.08 -190.868808)
					(end 5.3467 -191.135508)
				)
			)
		)
	)
	(zone
		(layers "F.Cu" "In5.Cu")
		(hatch none 0.5)
		(connect_pads
			(clearance 0)
		)
		(min_thickness 0.25)
		(keepout
			(tracks not_allowed)
			(vias allowed)
			(pads allowed)
			(copperpour not_allowed)
			(footprints allowed)
		)
		(placement
			(enabled no)
			(sheetname "")
		)
		(fill yes
			(thermal_gap 0.5)
			(thermal_bridge_width 0.5)
			(island_removal_mode 0)
		)
		(polygon
			(pts
				(arc
					(start 5.59054 -348.335346)
					(mid 5.08 -347.824806)
					(end 4.56946 -348.335346)
				)
				(arc
					(start 4.56946 -349.148146)
					(mid 5.07873 -349.658684)
					(end 5.59054 -349.150686)
				)
				(arc
					(start 5.3467 -349.150686)
					(mid 5.08 -349.414858)
					(end 4.8133 -349.150686)
				)
				(arc
					(start 4.8133 -349.148146)
					(mid 5.08 -348.881446)
					(end 5.3467 -349.148146)
				)
				(xy 5.59054 -349.148146) (xy 5.59054 -348.337886)
				(arc
					(start 5.3467 -348.337886)
					(mid 5.08 -348.602058)
					(end 4.8133 -348.337886)
				)
				(arc
					(start 4.8133 -348.335346)
					(mid 5.08 -348.068646)
					(end 5.3467 -348.335346)
				)
			)
		)
	)
	(zone
		(layers "F.Cu" "In5.Cu")
		(hatch none 0.5)
		(connect_pads
			(clearance 0)
		)
		(min_thickness 0.25)
		(keepout
			(tracks not_allowed)
			(vias allowed)
			(pads allowed)
			(copperpour not_allowed)
			(footprints allowed)
		)
		(placement
			(enabled no)
			(sheetname "")
		)
		(fill yes
			(thermal_gap 0.5)
			(thermal_bridge_width 0.5)
			(island_removal_mode 0)
		)
		(polygon
			(pts
				(arc
					(start 5.59054 -403.935184)
					(mid 5.08 -403.424644)
					(end 4.56946 -403.935184)
				)
				(arc
					(start 4.56946 -404.74773)
					(mid 5.078603 -405.258522)
					(end 5.59054 -404.750524)
				)
				(arc
					(start 5.3467 -404.750524)
					(mid 5.08 -405.014696)
					(end 4.8133 -404.750524)
				)
				(arc
					(start 4.8133 -404.747984)
					(mid 5.08 -404.481284)
					(end 5.3467 -404.747984)
				)
				(xy 5.59054 -404.747984) (xy 5.59054 -403.937724)
				(arc
					(start 5.3467 -403.937724)
					(mid 5.08 -404.201896)
					(end 4.8133 -403.937724)
				)
				(arc
					(start 4.8133 -403.935184)
					(mid 5.08 -403.668484)
					(end 5.3467 -403.935184)
				)
			)
		)
	)
	(zone
		(layers "F.Cu" "In5.Cu")
		(hatch none 0.5)
		(connect_pads
			(clearance 0)
		)
		(min_thickness 0.25)
		(keepout
			(tracks not_allowed)
			(vias allowed)
			(pads allowed)
			(copperpour not_allowed)
			(footprints allowed)
		)
		(placement
			(enabled no)
			(sheetname "")
		)
		(fill yes
			(thermal_gap 0.5)
			(thermal_bridge_width 0.5)
			(island_removal_mode 0)
		)
		(polygon
			(pts
				(arc
					(start 5.59054 -212.735414)
					(mid 5.08 -212.224874)
					(end 4.56946 -212.735414)
				)
				(arc
					(start 4.56946 -213.548214)
					(mid 5.07873 -214.058752)
					(end 5.59054 -213.550754)
				)
				(arc
					(start 5.3467 -213.550754)
					(mid 5.08 -213.814926)
					(end 4.8133 -213.550754)
				)
				(arc
					(start 4.8133 -213.548214)
					(mid 5.08 -213.281514)
					(end 5.3467 -213.548214)
				)
				(xy 5.59054 -213.548214) (xy 5.59054 -212.737954)
				(arc
					(start 5.3467 -212.737954)
					(mid 5.08 -213.002126)
					(end 4.8133 -212.737954)
				)
				(arc
					(start 4.8133 -212.735414)
					(mid 5.08 -212.468714)
					(end 5.3467 -212.735414)
				)
			)
		)
	)
	(zone
		(layers "F.Cu" "In5.Cu")
		(hatch none 0.5)
		(connect_pads
			(clearance 0)
		)
		(min_thickness 0.25)
		(keepout
			(tracks not_allowed)
			(vias allowed)
			(pads allowed)
			(copperpour not_allowed)
			(footprints allowed)
		)
		(placement
			(enabled no)
			(sheetname "")
		)
		(fill yes
			(thermal_gap 0.5)
			(thermal_bridge_width 0.5)
			(island_removal_mode 0)
		)
		(polygon
			(pts
				(arc
					(start 5.59054 -280.335482)
					(mid 5.08 -279.824942)
					(end 4.56946 -280.335482)
				)
				(arc
					(start 4.56946 -281.148282)
					(mid 5.07873 -281.65882)
					(end 5.59054 -281.150822)
				)
				(arc
					(start 5.3467 -281.150822)
					(mid 5.08 -281.414994)
					(end 4.8133 -281.150822)
				)
				(arc
					(start 4.8133 -281.148282)
					(mid 5.08 -280.881582)
					(end 5.3467 -281.148282)
				)
				(xy 5.59054 -281.148282) (xy 5.59054 -280.338022)
				(arc
					(start 5.3467 -280.338022)
					(mid 5.08 -280.602194)
					(end 4.8133 -280.338022)
				)
				(arc
					(start 4.8133 -280.335482)
					(mid 5.08 -280.068782)
					(end 5.3467 -280.335482)
				)
			)
		)
	)
	(zone
		(layers "F.Cu" "In5.Cu")
		(hatch none 0.5)
		(connect_pads
			(clearance 0)
		)
		(min_thickness 0.25)
		(keepout
			(tracks not_allowed)
			(vias allowed)
			(pads allowed)
			(copperpour not_allowed)
			(footprints allowed)
		)
		(placement
			(enabled no)
			(sheetname "")
		)
		(fill yes
			(thermal_gap 0.5)
			(thermal_bridge_width 0.5)
			(island_removal_mode 0)
		)
		(polygon
			(pts
				(arc
					(start 5.59054 -179.935378)
					(mid 5.08 -179.424838)
					(end 4.56946 -179.935378)
				)
				(arc
					(start 4.56946 -180.748178)
					(mid 5.07873 -181.258716)
					(end 5.59054 -180.750718)
				)
				(arc
					(start 5.3467 -180.750718)
					(mid 5.08 -181.01489)
					(end 4.8133 -180.750718)
				)
				(arc
					(start 4.8133 -180.748178)
					(mid 5.08 -180.481478)
					(end 5.3467 -180.748178)
				)
				(xy 5.59054 -180.748178) (xy 5.59054 -179.937918)
				(arc
					(start 5.3467 -179.937918)
					(mid 5.08 -180.20209)
					(end 4.8133 -179.937918)
				)
				(arc
					(start 4.8133 -179.935378)
					(mid 5.08 -179.668678)
					(end 5.3467 -179.935378)
				)
			)
		)
	)
	(zone
		(layers "F.Cu" "In5.Cu")
		(hatch none 0.5)
		(connect_pads
			(clearance 0)
		)
		(min_thickness 0.25)
		(keepout
			(tracks not_allowed)
			(vias allowed)
			(pads allowed)
			(copperpour not_allowed)
			(footprints allowed)
		)
		(placement
			(enabled no)
			(sheetname "")
		)
		(fill yes
			(thermal_gap 0.5)
			(thermal_bridge_width 0.5)
			(island_removal_mode 0)
		)
		(polygon
			(pts
				(arc
					(start 5.59054 -323.535294)
					(mid 5.08 -323.024754)
					(end 4.56946 -323.535294)
				)
				(arc
					(start 4.56946 -324.348094)
					(mid 5.07873 -324.858632)
					(end 5.59054 -324.350634)
				)
				(arc
					(start 5.3467 -324.350634)
					(mid 5.08 -324.614806)
					(end 4.8133 -324.350634)
				)
				(arc
					(start 4.8133 -324.348094)
					(mid 5.08 -324.081394)
					(end 5.3467 -324.348094)
				)
				(xy 5.59054 -324.348094) (xy 5.59054 -323.537834)
				(arc
					(start 5.3467 -323.537834)
					(mid 5.08 -323.802006)
					(end 4.8133 -323.537834)
				)
				(arc
					(start 4.8133 -323.535294)
					(mid 5.08 -323.268594)
					(end 5.3467 -323.535294)
				)
			)
		)
	)
	(zone
		(layers "F.Cu" "In5.Cu")
		(hatch none 0.5)
		(connect_pads
			(clearance 0)
		)
		(min_thickness 0.25)
		(keepout
			(tracks not_allowed)
			(vias allowed)
			(pads allowed)
			(copperpour not_allowed)
			(footprints allowed)
		)
		(placement
			(enabled no)
			(sheetname "")
		)
		(fill yes
			(thermal_gap 0.5)
			(thermal_bridge_width 0.5)
			(island_removal_mode 0)
		)
		(polygon
			(pts
				(arc
					(start 5.59054 -444.735204)
					(mid 5.08 -444.224664)
					(end 4.56946 -444.735204)
				)
				(arc
					(start 4.56946 -445.54775)
					(mid 5.078603 -446.058542)
					(end 5.59054 -445.550544)
				)
				(arc
					(start 5.3467 -445.550544)
					(mid 5.08 -445.814716)
					(end 4.8133 -445.550544)
				)
				(arc
					(start 4.8133 -445.548004)
					(mid 5.08 -445.281304)
					(end 5.3467 -445.548004)
				)
				(xy 5.59054 -445.548004) (xy 5.59054 -444.737744)
				(arc
					(start 5.3467 -444.737744)
					(mid 5.08 -445.001916)
					(end 4.8133 -444.737744)
				)
				(arc
					(start 4.8133 -444.735204)
					(mid 5.08 -444.468504)
					(end 5.3467 -444.735204)
				)
			)
		)
	)
	(zone
		(layers "F.Cu" "In5.Cu")
		(hatch none 0.5)
		(connect_pads
			(clearance 0)
		)
		(min_thickness 0.25)
		(keepout
			(tracks not_allowed)
			(vias allowed)
			(pads allowed)
			(copperpour not_allowed)
			(footprints allowed)
		)
		(placement
			(enabled no)
			(sheetname "")
		)
		(fill yes
			(thermal_gap 0.5)
			(thermal_bridge_width 0.5)
			(island_removal_mode 0)
		)
		(polygon
			(pts
				(arc
					(start 5.59054 -329.935332)
					(mid 5.08 -329.424792)
					(end 4.56946 -329.935332)
				)
				(arc
					(start 4.56946 -330.748132)
					(mid 5.07873 -331.25867)
					(end 5.59054 -330.750672)
				)
				(arc
					(start 5.3467 -330.750672)
					(mid 5.08 -331.014844)
					(end 4.8133 -330.750672)
				)
				(arc
					(start 4.8133 -330.748132)
					(mid 5.08 -330.481432)
					(end 5.3467 -330.748132)
				)
				(xy 5.59054 -330.748132) (xy 5.59054 -329.937872)
				(arc
					(start 5.3467 -329.937872)
					(mid 5.08 -330.202044)
					(end 4.8133 -329.937872)
				)
				(arc
					(start 4.8133 -329.935332)
					(mid 5.08 -329.668632)
					(end 5.3467 -329.935332)
				)
			)
		)
	)
	(zone
		(layers "F.Cu" "In5.Cu")
		(hatch none 0.5)
		(connect_pads
			(clearance 0)
		)
		(min_thickness 0.25)
		(keepout
			(tracks not_allowed)
			(vias allowed)
			(pads allowed)
			(copperpour not_allowed)
			(footprints allowed)
		)
		(placement
			(enabled no)
			(sheetname "")
		)
		(fill yes
			(thermal_gap 0.5)
			(thermal_bridge_width 0.5)
			(island_removal_mode 0)
		)
		(polygon
			(pts
				(arc
					(start 5.59054 -345.135454)
					(mid 5.08 -344.624914)
					(end 4.56946 -345.135454)
				)
				(arc
					(start 4.56946 -345.948254)
					(mid 5.07873 -346.458792)
					(end 5.59054 -345.950794)
				)
				(arc
					(start 5.3467 -345.950794)
					(mid 5.08 -346.214966)
					(end 4.8133 -345.950794)
				)
				(arc
					(start 4.8133 -345.948254)
					(mid 5.08 -345.681554)
					(end 5.3467 -345.948254)
				)
				(xy 5.59054 -345.948254) (xy 5.59054 -345.137994)
				(arc
					(start 5.3467 -345.137994)
					(mid 5.08 -345.402166)
					(end 4.8133 -345.137994)
				)
				(arc
					(start 4.8133 -345.135454)
					(mid 5.08 -344.868754)
					(end 5.3467 -345.135454)
				)
			)
		)
	)
	(zone
		(layers "F.Cu" "In5.Cu")
		(hatch none 0.5)
		(connect_pads
			(clearance 0)
		)
		(min_thickness 0.25)
		(keepout
			(tracks not_allowed)
			(vias allowed)
			(pads allowed)
			(copperpour not_allowed)
			(footprints allowed)
		)
		(placement
			(enabled no)
			(sheetname "")
		)
		(fill yes
			(thermal_gap 0.5)
			(thermal_bridge_width 0.5)
			(island_removal_mode 0)
		)
		(polygon
			(pts
				(arc
					(start 5.59054 -435.135274)
					(mid 5.08 -434.624734)
					(end 4.56946 -435.135274)
				)
				(arc
					(start 4.56946 -435.94782)
					(mid 5.078603 -436.458612)
					(end 5.59054 -435.950614)
				)
				(arc
					(start 5.3467 -435.950614)
					(mid 5.08 -436.214786)
					(end 4.8133 -435.950614)
				)
				(arc
					(start 4.8133 -435.948074)
					(mid 5.08 -435.681374)
					(end 5.3467 -435.948074)
				)
				(xy 5.59054 -435.948074) (xy 5.59054 -435.137814)
				(arc
					(start 5.3467 -435.137814)
					(mid 5.08 -435.401986)
					(end 4.8133 -435.137814)
				)
				(arc
					(start 4.8133 -435.135274)
					(mid 5.08 -434.868574)
					(end 5.3467 -435.135274)
				)
			)
		)
	)
	(zone
		(layers "F.Cu" "In5.Cu")
		(hatch none 0.5)
		(connect_pads
			(clearance 0)
		)
		(min_thickness 0.25)
		(keepout
			(tracks not_allowed)
			(vias allowed)
			(pads allowed)
			(copperpour not_allowed)
			(footprints allowed)
		)
		(placement
			(enabled no)
			(sheetname "")
		)
		(fill yes
			(thermal_gap 0.5)
			(thermal_bridge_width 0.5)
			(island_removal_mode 0)
		)
		(polygon
			(pts
				(arc
					(start 5.59054 -410.335222)
					(mid 5.08 -409.824682)
					(end 4.56946 -410.335222)
				)
				(arc
					(start 4.56946 -411.147768)
					(mid 5.078603 -411.65856)
					(end 5.59054 -411.150562)
				)
				(arc
					(start 5.3467 -411.150562)
					(mid 5.08 -411.414734)
					(end 4.8133 -411.150562)
				)
				(arc
					(start 4.8133 -411.148022)
					(mid 5.08 -410.881322)
					(end 5.3467 -411.148022)
				)
				(xy 5.59054 -411.148022) (xy 5.59054 -410.337762)
				(arc
					(start 5.3467 -410.337762)
					(mid 5.08 -410.601934)
					(end 4.8133 -410.337762)
				)
				(arc
					(start 4.8133 -410.335222)
					(mid 5.08 -410.068522)
					(end 5.3467 -410.335222)
				)
			)
		)
	)
	(zone
		(layers "F.Cu" "In5.Cu")
		(hatch none 0.5)
		(connect_pads
			(clearance 0)
		)
		(min_thickness 0.25)
		(keepout
			(tracks not_allowed)
			(vias allowed)
			(pads allowed)
			(copperpour not_allowed)
			(footprints allowed)
		)
		(placement
			(enabled no)
			(sheetname "")
		)
		(fill yes
			(thermal_gap 0.5)
			(thermal_bridge_width 0.5)
			(island_removal_mode 0)
		)
		(polygon
			(pts
				(arc
					(start 5.59054 -167.135302)
					(mid 5.08 -166.624762)
					(end 4.56946 -167.135302)
				)
				(arc
					(start 4.56946 -167.948102)
					(mid 5.07873 -168.45864)
					(end 5.59054 -167.950642)
				)
				(arc
					(start 5.3467 -167.950642)
					(mid 5.08 -168.214814)
					(end 4.8133 -167.950642)
				)
				(arc
					(start 4.8133 -167.948102)
					(mid 5.08 -167.681402)
					(end 5.3467 -167.948102)
				)
				(xy 5.59054 -167.948102) (xy 5.59054 -167.137842)
				(arc
					(start 5.3467 -167.137842)
					(mid 5.08 -167.402014)
					(end 4.8133 -167.137842)
				)
				(arc
					(start 4.8133 -167.135302)
					(mid 5.08 -166.868602)
					(end 5.3467 -167.135302)
				)
			)
		)
	)
	(zone
		(layers "F.Cu" "In5.Cu")
		(hatch none 0.5)
		(connect_pads
			(clearance 0)
		)
		(min_thickness 0.25)
		(keepout
			(tracks not_allowed)
			(vias allowed)
			(pads allowed)
			(copperpour not_allowed)
			(footprints allowed)
		)
		(placement
			(enabled no)
			(sheetname "")
		)
		(fill yes
			(thermal_gap 0.5)
			(thermal_bridge_width 0.5)
			(island_removal_mode 0)
		)
		(polygon
			(pts
				(arc
					(start 5.59054 -160.735518)
					(mid 5.08 -160.224978)
					(end 4.56946 -160.735518)
				)
				(arc
					(start 4.56946 -161.548318)
					(mid 5.07873 -162.058856)
					(end 5.59054 -161.550858)
				)
				(arc
					(start 5.3467 -161.550858)
					(mid 5.08 -161.81503)
					(end 4.8133 -161.550858)
				)
				(arc
					(start 4.8133 -161.548318)
					(mid 5.08 -161.281618)
					(end 5.3467 -161.548318)
				)
				(xy 5.59054 -161.548318) (xy 5.59054 -160.738058)
				(arc
					(start 5.3467 -160.738058)
					(mid 5.08 -161.00223)
					(end 4.8133 -160.738058)
				)
				(arc
					(start 4.8133 -160.735518)
					(mid 5.08 -160.468818)
					(end 5.3467 -160.735518)
				)
			)
		)
	)
	(zone
		(layers "F.Cu" "In5.Cu")
		(hatch none 0.5)
		(connect_pads
			(clearance 0)
		)
		(min_thickness 0.25)
		(keepout
			(tracks not_allowed)
			(vias allowed)
			(pads allowed)
			(copperpour not_allowed)
			(footprints allowed)
		)
		(placement
			(enabled no)
			(sheetname "")
		)
		(fill yes
			(thermal_gap 0.5)
			(thermal_bridge_width 0.5)
			(island_removal_mode 0)
		)
		(polygon
			(pts
				(arc
					(start 5.59054 -407.135076)
					(mid 5.08 -406.624536)
					(end 4.56946 -407.135076)
				)
				(arc
					(start 4.56946 -407.947622)
					(mid 5.078603 -408.458414)
					(end 5.59054 -407.950416)
				)
				(arc
					(start 5.3467 -407.950416)
					(mid 5.08 -408.214588)
					(end 4.8133 -407.950416)
				)
				(arc
					(start 4.8133 -407.947876)
					(mid 5.08 -407.681176)
					(end 5.3467 -407.947876)
				)
				(xy 5.59054 -407.947876) (xy 5.59054 -407.137616)
				(arc
					(start 5.3467 -407.137616)
					(mid 5.08 -407.401788)
					(end 4.8133 -407.137616)
				)
				(arc
					(start 4.8133 -407.135076)
					(mid 5.08 -406.868376)
					(end 5.3467 -407.135076)
				)
			)
		)
	)
	(zone
		(layers "F.Cu" "In5.Cu")
		(hatch none 0.5)
		(connect_pads
			(clearance 0)
		)
		(min_thickness 0.25)
		(keepout
			(tracks not_allowed)
			(vias allowed)
			(pads allowed)
			(copperpour not_allowed)
			(footprints allowed)
		)
		(placement
			(enabled no)
			(sheetname "")
		)
		(fill yes
			(thermal_gap 0.5)
			(thermal_bridge_width 0.5)
			(island_removal_mode 0)
		)
		(polygon
			(pts
				(arc
					(start 5.59054 -163.93541)
					(mid 5.08 -163.42487)
					(end 4.56946 -163.93541)
				)
				(arc
					(start 4.56946 -164.74821)
					(mid 5.07873 -165.258748)
					(end 5.59054 -164.75075)
				)
				(arc
					(start 5.3467 -164.75075)
					(mid 5.08 -165.014922)
					(end 4.8133 -164.75075)
				)
				(arc
					(start 4.8133 -164.74821)
					(mid 5.08 -164.48151)
					(end 5.3467 -164.74821)
				)
				(xy 5.59054 -164.74821) (xy 5.59054 -163.93795)
				(arc
					(start 5.3467 -163.93795)
					(mid 5.08 -164.202122)
					(end 4.8133 -163.93795)
				)
				(arc
					(start 4.8133 -163.93541)
					(mid 5.08 -163.66871)
					(end 5.3467 -163.93541)
				)
			)
		)
	)
	(zone
		(layers "F.Cu" "In5.Cu")
		(hatch none 0.5)
		(connect_pads
			(clearance 0)
		)
		(min_thickness 0.25)
		(keepout
			(tracks not_allowed)
			(vias allowed)
			(pads allowed)
			(copperpour not_allowed)
			(footprints allowed)
		)
		(placement
			(enabled no)
			(sheetname "")
		)
		(fill yes
			(thermal_gap 0.5)
			(thermal_bridge_width 0.5)
			(island_removal_mode 0)
		)
		(polygon
			(pts
				(arc
					(start 5.59054 -203.135484)
					(mid 5.08 -202.624944)
					(end 4.56946 -203.135484)
				)
				(arc
					(start 4.56946 -203.948284)
					(mid 5.07873 -204.458822)
					(end 5.59054 -203.950824)
				)
				(arc
					(start 5.3467 -203.950824)
					(mid 5.08 -204.214996)
					(end 4.8133 -203.950824)
				)
				(arc
					(start 4.8133 -203.948284)
					(mid 5.08 -203.681584)
					(end 5.3467 -203.948284)
				)
				(xy 5.59054 -203.948284) (xy 5.59054 -203.138024)
				(arc
					(start 5.3467 -203.138024)
					(mid 5.08 -203.402196)
					(end 4.8133 -203.138024)
				)
				(arc
					(start 4.8133 -203.135484)
					(mid 5.08 -202.868784)
					(end 5.3467 -203.135484)
				)
			)
		)
	)
	(zone
		(layers "F.Cu" "In5.Cu")
		(hatch none 0.5)
		(connect_pads
			(clearance 0)
		)
		(min_thickness 0.25)
		(keepout
			(tracks not_allowed)
			(vias allowed)
			(pads allowed)
			(copperpour not_allowed)
			(footprints allowed)
		)
		(placement
			(enabled no)
			(sheetname "")
		)
		(fill yes
			(thermal_gap 0.5)
			(thermal_bridge_width 0.5)
			(island_removal_mode 0)
		)
		(polygon
			(pts
				(arc
					(start 5.59054 -299.535342)
					(mid 5.08 -299.024802)
					(end 4.56946 -299.535342)
				)
				(arc
					(start 4.56946 -300.348142)
					(mid 5.07873 -300.85868)
					(end 5.59054 -300.350682)
				)
				(arc
					(start 5.3467 -300.350682)
					(mid 5.08 -300.614854)
					(end 4.8133 -300.350682)
				)
				(arc
					(start 4.8133 -300.348142)
					(mid 5.08 -300.081442)
					(end 5.3467 -300.348142)
				)
				(xy 5.59054 -300.348142) (xy 5.59054 -299.537882)
				(arc
					(start 5.3467 -299.537882)
					(mid 5.08 -299.802054)
					(end 4.8133 -299.537882)
				)
				(arc
					(start 4.8133 -299.535342)
					(mid 5.08 -299.268642)
					(end 5.3467 -299.535342)
				)
			)
		)
	)
	(zone
		(layers "F.Cu" "In5.Cu")
		(hatch none 0.5)
		(connect_pads
			(clearance 0)
		)
		(min_thickness 0.25)
		(keepout
			(tracks not_allowed)
			(vias allowed)
			(pads allowed)
			(copperpour not_allowed)
			(footprints allowed)
		)
		(placement
			(enabled no)
			(sheetname "")
		)
		(fill yes
			(thermal_gap 0.5)
			(thermal_bridge_width 0.5)
			(island_removal_mode 0)
		)
		(polygon
			(pts
				(arc
					(start 5.59054 -199.935338)
					(mid 5.08 -199.424798)
					(end 4.56946 -199.935338)
				)
				(arc
					(start 4.56946 -200.748138)
					(mid 5.07873 -201.258676)
					(end 5.59054 -200.750678)
				)
				(arc
					(start 5.3467 -200.750678)
					(mid 5.08 -201.01485)
					(end 4.8133 -200.750678)
				)
				(arc
					(start 4.8133 -200.748138)
					(mid 5.08 -200.481438)
					(end 5.3467 -200.748138)
				)
				(xy 5.59054 -200.748138) (xy 5.59054 -199.937878)
				(arc
					(start 5.3467 -199.937878)
					(mid 5.08 -200.20205)
					(end 4.8133 -199.937878)
				)
				(arc
					(start 4.8133 -199.935338)
					(mid 5.08 -199.668638)
					(end 5.3467 -199.935338)
				)
			)
		)
	)
	(zone
		(layers "F.Cu" "In5.Cu")
		(hatch none 0.5)
		(connect_pads
			(clearance 0)
		)
		(min_thickness 0.25)
		(keepout
			(tracks not_allowed)
			(vias allowed)
			(pads allowed)
			(copperpour not_allowed)
			(footprints allowed)
		)
		(placement
			(enabled no)
			(sheetname "")
		)
		(fill yes
			(thermal_gap 0.5)
			(thermal_bridge_width 0.5)
			(island_removal_mode 0)
		)
		(polygon
			(pts
				(arc
					(start 5.59054 -357.93553)
					(mid 5.08 -357.42499)
					(end 4.56946 -357.93553)
				)
				(arc
					(start 4.56946 -358.74833)
					(mid 5.07873 -359.258868)
					(end 5.59054 -358.75087)
				)
				(arc
					(start 5.3467 -358.75087)
					(mid 5.08 -359.015042)
					(end 4.8133 -358.75087)
				)
				(arc
					(start 4.8133 -358.74833)
					(mid 5.08 -358.48163)
					(end 5.3467 -358.74833)
				)
				(xy 5.59054 -358.74833) (xy 5.59054 -357.93807)
				(arc
					(start 5.3467 -357.93807)
					(mid 5.08 -358.202242)
					(end 4.8133 -357.93807)
				)
				(arc
					(start 4.8133 -357.93553)
					(mid 5.08 -357.66883)
					(end 5.3467 -357.93553)
				)
			)
		)
	)
	(zone
		(layers "F.Cu" "In5.Cu")
		(hatch none 0.5)
		(connect_pads
			(clearance 0)
		)
		(min_thickness 0.25)
		(keepout
			(tracks not_allowed)
			(vias allowed)
			(pads allowed)
			(copperpour not_allowed)
			(footprints allowed)
		)
		(placement
			(enabled no)
			(sheetname "")
		)
		(fill yes
			(thermal_gap 0.5)
			(thermal_bridge_width 0.5)
			(island_removal_mode 0)
		)
		(polygon
			(pts
				(arc
					(start 5.59054 -441.535312)
					(mid 5.08 -441.024772)
					(end 4.56946 -441.535312)
				)
				(arc
					(start 4.56946 -442.347858)
					(mid 5.078603 -442.85865)
					(end 5.59054 -442.350652)
				)
				(arc
					(start 5.3467 -442.350652)
					(mid 5.08 -442.614824)
					(end 4.8133 -442.350652)
				)
				(arc
					(start 4.8133 -442.348112)
					(mid 5.08 -442.081412)
					(end 5.3467 -442.348112)
				)
				(xy 5.59054 -442.348112) (xy 5.59054 -441.537852)
				(arc
					(start 5.3467 -441.537852)
					(mid 5.08 -441.802024)
					(end 4.8133 -441.537852)
				)
				(arc
					(start 4.8133 -441.535312)
					(mid 5.08 -441.268612)
					(end 5.3467 -441.535312)
				)
			)
		)
	)
	(zone
		(layers "F.Cu" "In5.Cu")
		(hatch none 0.5)
		(connect_pads
			(clearance 0)
		)
		(min_thickness 0.25)
		(keepout
			(tracks not_allowed)
			(vias allowed)
			(pads allowed)
			(copperpour not_allowed)
			(footprints allowed)
		)
		(placement
			(enabled no)
			(sheetname "")
		)
		(fill yes
			(thermal_gap 0.5)
			(thermal_bridge_width 0.5)
			(island_removal_mode 0)
		)
		(polygon
			(pts
				(arc
					(start 5.59054 -209.535522)
					(mid 5.08 -209.024982)
					(end 4.56946 -209.535522)
				)
				(arc
					(start 4.56946 -210.348322)
					(mid 5.07873 -210.85886)
					(end 5.59054 -210.350862)
				)
				(arc
					(start 5.3467 -210.350862)
					(mid 5.08 -210.615034)
					(end 4.8133 -210.350862)
				)
				(arc
					(start 4.8133 -210.348322)
					(mid 5.08 -210.081622)
					(end 5.3467 -210.348322)
				)
				(xy 5.59054 -210.348322) (xy 5.59054 -209.538062)
				(arc
					(start 5.3467 -209.538062)
					(mid 5.08 -209.802234)
					(end 4.8133 -209.538062)
				)
				(arc
					(start 4.8133 -209.535522)
					(mid 5.08 -209.268822)
					(end 5.3467 -209.535522)
				)
			)
		)
	)
	(zone
		(layers "F.Cu" "In5.Cu")
		(hatch none 0.5)
		(connect_pads
			(clearance 0)
		)
		(min_thickness 0.25)
		(keepout
			(tracks not_allowed)
			(vias allowed)
			(pads allowed)
			(copperpour not_allowed)
			(footprints allowed)
		)
		(placement
			(enabled no)
			(sheetname "")
		)
		(fill yes
			(thermal_gap 0.5)
			(thermal_bridge_width 0.5)
			(island_removal_mode 0)
		)
		(polygon
			(pts
				(arc
					(start 5.59054 -215.935306)
					(mid 5.08 -215.424766)
					(end 4.56946 -215.935306)
				)
				(arc
					(start 4.56946 -216.748106)
					(mid 5.07873 -217.258644)
					(end 5.59054 -216.750646)
				)
				(arc
					(start 5.3467 -216.750646)
					(mid 5.08 -217.014818)
					(end 4.8133 -216.750646)
				)
				(arc
					(start 4.8133 -216.748106)
					(mid 5.08 -216.481406)
					(end 5.3467 -216.748106)
				)
				(xy 5.59054 -216.748106) (xy 5.59054 -215.937846)
				(arc
					(start 5.3467 -215.937846)
					(mid 5.08 -216.202018)
					(end 4.8133 -215.937846)
				)
				(arc
					(start 4.8133 -215.935306)
					(mid 5.08 -215.668606)
					(end 5.3467 -215.935306)
				)
			)
		)
	)
	(zone
		(layers "F.Cu" "In5.Cu")
		(hatch none 0.5)
		(connect_pads
			(clearance 0)
		)
		(min_thickness 0.25)
		(keepout
			(tracks not_allowed)
			(vias allowed)
			(pads allowed)
			(copperpour not_allowed)
			(footprints allowed)
		)
		(placement
			(enabled no)
			(sheetname "")
		)
		(fill yes
			(thermal_gap 0.5)
			(thermal_bridge_width 0.5)
			(island_removal_mode 0)
		)
		(polygon
			(pts
				(arc
					(start 5.59054 -423.135298)
					(mid 5.08 -422.624758)
					(end 4.56946 -423.135298)
				)
				(arc
					(start 4.56946 -423.948098)
					(mid 5.07873 -424.458636)
					(end 5.59054 -423.950638)
				)
				(arc
					(start 5.3467 -423.950638)
					(mid 5.08 -424.21481)
					(end 4.8133 -423.950638)
				)
				(arc
					(start 4.8133 -423.948098)
					(mid 5.08 -423.681398)
					(end 5.3467 -423.948098)
				)
				(xy 5.59054 -423.948098) (xy 5.59054 -423.137838)
				(arc
					(start 5.3467 -423.137838)
					(mid 5.08 -423.40201)
					(end 4.8133 -423.137838)
				)
				(arc
					(start 4.8133 -423.135298)
					(mid 5.08 -422.868598)
					(end 5.3467 -423.135298)
				)
			)
		)
	)
	(zone
		(layers "F.Cu" "In5.Cu")
		(hatch none 0.5)
		(connect_pads
			(clearance 0)
		)
		(min_thickness 0.25)
		(keepout
			(tracks not_allowed)
			(vias allowed)
			(pads allowed)
			(copperpour not_allowed)
			(footprints allowed)
		)
		(placement
			(enabled no)
			(sheetname "")
		)
		(fill yes
			(thermal_gap 0.5)
			(thermal_bridge_width 0.5)
			(island_removal_mode 0)
		)
		(polygon
			(pts
				(arc
					(start 5.59054 -222.335344)
					(mid 5.08 -221.824804)
					(end 4.56946 -222.335344)
				)
				(arc
					(start 4.56946 -223.148144)
					(mid 5.07873 -223.658682)
					(end 5.59054 -223.150684)
				)
				(arc
					(start 5.3467 -223.150684)
					(mid 5.08 -223.414856)
					(end 4.8133 -223.150684)
				)
				(arc
					(start 4.8133 -223.148144)
					(mid 5.08 -222.881444)
					(end 5.3467 -223.148144)
				)
				(xy 5.59054 -223.148144) (xy 5.59054 -222.337884)
				(arc
					(start 5.3467 -222.337884)
					(mid 5.08 -222.602056)
					(end 4.8133 -222.337884)
				)
				(arc
					(start 4.8133 -222.335344)
					(mid 5.08 -222.068644)
					(end 5.3467 -222.335344)
				)
			)
		)
	)
	(zone
		(layers "F.Cu" "In5.Cu")
		(hatch none 0.5)
		(connect_pads
			(clearance 0)
		)
		(min_thickness 0.25)
		(keepout
			(tracks not_allowed)
			(vias allowed)
			(pads allowed)
			(copperpour not_allowed)
			(footprints allowed)
		)
		(placement
			(enabled no)
			(sheetname "")
		)
		(fill yes
			(thermal_gap 0.5)
			(thermal_bridge_width 0.5)
			(island_removal_mode 0)
		)
		(polygon
			(pts
				(arc
					(start 5.59054 -398.335246)
					(mid 5.08 -397.824706)
					(end 4.56946 -398.335246)
				)
				(arc
					(start 4.56946 -399.148046)
					(mid 5.07873 -399.658584)
					(end 5.59054 -399.150586)
				)
				(arc
					(start 5.3467 -399.150586)
					(mid 5.08 -399.414758)
					(end 4.8133 -399.150586)
				)
				(arc
					(start 4.8133 -399.148046)
					(mid 5.08 -398.881346)
					(end 5.3467 -399.148046)
				)
				(xy 5.59054 -399.148046) (xy 5.59054 -398.337786)
				(arc
					(start 5.3467 -398.337786)
					(mid 5.08 -398.601958)
					(end 4.8133 -398.337786)
				)
				(arc
					(start 4.8133 -398.335246)
					(mid 5.08 -398.068546)
					(end 5.3467 -398.335246)
				)
			)
		)
	)
	(zone
		(layers "F.Cu" "In5.Cu")
		(hatch none 0.5)
		(connect_pads
			(clearance 0)
		)
		(min_thickness 0.25)
		(keepout
			(tracks not_allowed)
			(vias allowed)
			(pads allowed)
			(copperpour not_allowed)
			(footprints allowed)
		)
		(placement
			(enabled no)
			(sheetname "")
		)
		(fill yes
			(thermal_gap 0.5)
			(thermal_bridge_width 0.5)
			(island_removal_mode 0)
		)
		(polygon
			(pts
				(arc
					(start 5.59054 -154.33548)
					(mid 5.08 -153.82494)
					(end 4.56946 -154.33548)
				)
				(arc
					(start 4.56946 -155.14828)
					(mid 5.07873 -155.658818)
					(end 5.59054 -155.15082)
				)
				(arc
					(start 5.3467 -155.15082)
					(mid 5.08 -155.414992)
					(end 4.8133 -155.15082)
				)
				(arc
					(start 4.8133 -155.14828)
					(mid 5.08 -154.88158)
					(end 5.3467 -155.14828)
				)
				(xy 5.59054 -155.14828) (xy 5.59054 -154.33802)
				(arc
					(start 5.3467 -154.33802)
					(mid 5.08 -154.602192)
					(end 4.8133 -154.33802)
				)
				(arc
					(start 4.8133 -154.33548)
					(mid 5.08 -154.06878)
					(end 5.3467 -154.33548)
				)
			)
		)
	)
	(zone
		(layers "F.Cu" "In5.Cu")
		(hatch none 0.5)
		(connect_pads
			(clearance 0)
		)
		(min_thickness 0.25)
		(keepout
			(tracks not_allowed)
			(vias allowed)
			(pads allowed)
			(copperpour not_allowed)
			(footprints allowed)
		)
		(placement
			(enabled no)
			(sheetname "")
		)
		(fill yes
			(thermal_gap 0.5)
			(thermal_bridge_width 0.5)
			(island_removal_mode 0)
		)
		(polygon
			(pts
				(arc
					(start 5.59054 -320.335402)
					(mid 5.08 -319.824862)
					(end 4.56946 -320.335402)
				)
				(arc
					(start 4.56946 -321.148202)
					(mid 5.07873 -321.65874)
					(end 5.59054 -321.150742)
				)
				(arc
					(start 5.3467 -321.150742)
					(mid 5.08 -321.414914)
					(end 4.8133 -321.150742)
				)
				(arc
					(start 4.8133 -321.148202)
					(mid 5.08 -320.881502)
					(end 5.3467 -321.148202)
				)
				(xy 5.59054 -321.148202) (xy 5.59054 -320.337942)
				(arc
					(start 5.3467 -320.337942)
					(mid 5.08 -320.602114)
					(end 4.8133 -320.337942)
				)
				(arc
					(start 4.8133 -320.335402)
					(mid 5.08 -320.068702)
					(end 5.3467 -320.335402)
				)
			)
		)
	)
	(zone
		(layers "F.Cu" "In5.Cu")
		(hatch none 0.5)
		(connect_pads
			(clearance 0)
		)
		(min_thickness 0.25)
		(keepout
			(tracks not_allowed)
			(vias allowed)
			(pads allowed)
			(copperpour not_allowed)
			(footprints allowed)
		)
		(placement
			(enabled no)
			(sheetname "")
		)
		(fill yes
			(thermal_gap 0.5)
			(thermal_bridge_width 0.5)
			(island_removal_mode 0)
		)
		(polygon
			(pts
				(arc
					(start 5.59054 -173.53534)
					(mid 5.08 -173.0248)
					(end 4.56946 -173.53534)
				)
				(arc
					(start 4.56946 -174.34814)
					(mid 5.07873 -174.858678)
					(end 5.59054 -174.35068)
				)
				(arc
					(start 5.3467 -174.35068)
					(mid 5.08 -174.614852)
					(end 4.8133 -174.35068)
				)
				(arc
					(start 4.8133 -174.34814)
					(mid 5.08 -174.08144)
					(end 5.3467 -174.34814)
				)
				(xy 5.59054 -174.34814) (xy 5.59054 -173.53788)
				(arc
					(start 5.3467 -173.53788)
					(mid 5.08 -173.802052)
					(end 4.8133 -173.53788)
				)
				(arc
					(start 4.8133 -173.53534)
					(mid 5.08 -173.26864)
					(end 5.3467 -173.53534)
				)
			)
		)
	)
	(zone
		(layers "F.Cu" "In5.Cu")
		(hatch none 0.5)
		(connect_pads
			(clearance 0)
		)
		(min_thickness 0.25)
		(keepout
			(tracks not_allowed)
			(vias allowed)
			(pads allowed)
			(copperpour not_allowed)
			(footprints allowed)
		)
		(placement
			(enabled no)
			(sheetname "")
		)
		(fill yes
			(thermal_gap 0.5)
			(thermal_bridge_width 0.5)
			(island_removal_mode 0)
		)
		(polygon
			(pts
				(arc
					(start 5.59054 -426.33519)
					(mid 5.08 -425.82465)
					(end 4.56946 -426.33519)
				)
				(arc
					(start 4.56946 -427.14799)
					(mid 5.07873 -427.658528)
					(end 5.59054 -427.15053)
				)
				(arc
					(start 5.3467 -427.15053)
					(mid 5.08 -427.414702)
					(end 4.8133 -427.15053)
				)
				(arc
					(start 4.8133 -427.14799)
					(mid 5.08 -426.88129)
					(end 5.3467 -427.14799)
				)
				(xy 5.59054 -427.14799) (xy 5.59054 -426.33773)
				(arc
					(start 5.3467 -426.33773)
					(mid 5.08 -426.601902)
					(end 4.8133 -426.33773)
				)
				(arc
					(start 4.8133 -426.33519)
					(mid 5.08 -426.06849)
					(end 5.3467 -426.33519)
				)
			)
		)
	)
	(zone
		(layers "F.Cu" "In5.Cu")
		(hatch none 0.5)
		(connect_pads
			(clearance 0)
		)
		(min_thickness 0.25)
		(keepout
			(tracks not_allowed)
			(vias allowed)
			(pads allowed)
			(copperpour not_allowed)
			(footprints allowed)
		)
		(placement
			(enabled no)
			(sheetname "")
		)
		(fill yes
			(thermal_gap 0.5)
			(thermal_bridge_width 0.5)
			(island_removal_mode 0)
		)
		(polygon
			(pts
				(arc
					(start 5.59054 -283.535374)
					(mid 5.08 -283.024834)
					(end 4.56946 -283.535374)
				)
				(arc
					(start 4.56946 -284.348174)
					(mid 5.07873 -284.858712)
					(end 5.59054 -284.350714)
				)
				(arc
					(start 5.3467 -284.350714)
					(mid 5.08 -284.614886)
					(end 4.8133 -284.350714)
				)
				(arc
					(start 4.8133 -284.348174)
					(mid 5.08 -284.081474)
					(end 5.3467 -284.348174)
				)
				(xy 5.59054 -284.348174) (xy 5.59054 -283.537914)
				(arc
					(start 5.3467 -283.537914)
					(mid 5.08 -283.802086)
					(end 4.8133 -283.537914)
				)
				(arc
					(start 4.8133 -283.535374)
					(mid 5.08 -283.268674)
					(end 5.3467 -283.535374)
				)
			)
		)
	)
	(zone
		(layers "F.Cu" "In5.Cu")
		(hatch none 0.5)
		(connect_pads
			(clearance 0)
		)
		(min_thickness 0.25)
		(keepout
			(tracks not_allowed)
			(vias allowed)
			(pads allowed)
			(copperpour not_allowed)
			(footprints allowed)
		)
		(placement
			(enabled no)
			(sheetname "")
		)
		(fill yes
			(thermal_gap 0.5)
			(thermal_bridge_width 0.5)
			(island_removal_mode 0)
		)
		(polygon
			(pts
				(arc
					(start 5.59054 -302.735488)
					(mid 5.08 -302.224948)
					(end 4.56946 -302.735488)
				)
				(arc
					(start 4.56946 -303.548288)
					(mid 5.07873 -304.058826)
					(end 5.59054 -303.550828)
				)
				(arc
					(start 5.3467 -303.550828)
					(mid 5.08 -303.815)
					(end 4.8133 -303.550828)
				)
				(arc
					(start 4.8133 -303.548288)
					(mid 5.08 -303.281588)
					(end 5.3467 -303.548288)
				)
				(xy 5.59054 -303.548288) (xy 5.59054 -302.738028)
				(arc
					(start 5.3467 -302.738028)
					(mid 5.08 -303.0022)
					(end 4.8133 -302.738028)
				)
				(arc
					(start 4.8133 -302.735488)
					(mid 5.08 -302.468788)
					(end 5.3467 -302.735488)
				)
			)
		)
	)
	(zone
		(layers "F.Cu" "In5.Cu")
		(hatch none 0.5)
		(connect_pads
			(clearance 0)
		)
		(min_thickness 0.25)
		(keepout
			(tracks not_allowed)
			(vias allowed)
			(pads allowed)
			(copperpour not_allowed)
			(footprints allowed)
		)
		(placement
			(enabled no)
			(sheetname "")
		)
		(fill yes
			(thermal_gap 0.5)
			(thermal_bridge_width 0.5)
			(island_removal_mode 0)
		)
		(polygon
			(pts
				(arc
					(start 5.59054 -219.135452)
					(mid 5.08 -218.624912)
					(end 4.56946 -219.135452)
				)
				(arc
					(start 4.56946 -219.948252)
					(mid 5.07873 -220.45879)
					(end 5.59054 -219.950792)
				)
				(arc
					(start 5.3467 -219.950792)
					(mid 5.08 -220.214964)
					(end 4.8133 -219.950792)
				)
				(arc
					(start 4.8133 -219.948252)
					(mid 5.08 -219.681552)
					(end 5.3467 -219.948252)
				)
				(xy 5.59054 -219.948252) (xy 5.59054 -219.137992)
				(arc
					(start 5.3467 -219.137992)
					(mid 5.08 -219.402164)
					(end 4.8133 -219.137992)
				)
				(arc
					(start 4.8133 -219.135452)
					(mid 5.08 -218.868752)
					(end 5.3467 -219.135452)
				)
			)
		)
	)
	(zone
		(layers "F.Cu" "In5.Cu")
		(hatch none 0.5)
		(connect_pads
			(clearance 0)
		)
		(min_thickness 0.25)
		(keepout
			(tracks not_allowed)
			(vias allowed)
			(pads allowed)
			(copperpour not_allowed)
			(footprints allowed)
		)
		(placement
			(enabled no)
			(sheetname "")
		)
		(fill yes
			(thermal_gap 0.5)
			(thermal_bridge_width 0.5)
			(island_removal_mode 0)
		)
		(polygon
			(pts
				(arc
					(start 5.59054 -289.935412)
					(mid 5.08 -289.424872)
					(end 4.56946 -289.935412)
				)
				(arc
					(start 4.56946 -290.748212)
					(mid 5.07873 -291.25875)
					(end 5.59054 -290.750752)
				)
				(arc
					(start 5.3467 -290.750752)
					(mid 5.08 -291.014924)
					(end 4.8133 -290.750752)
				)
				(arc
					(start 4.8133 -290.748212)
					(mid 5.08 -290.481512)
					(end 5.3467 -290.748212)
				)
				(xy 5.59054 -290.748212) (xy 5.59054 -289.937952)
				(arc
					(start 5.3467 -289.937952)
					(mid 5.08 -290.202124)
					(end 4.8133 -289.937952)
				)
				(arc
					(start 4.8133 -289.935412)
					(mid 5.08 -289.668712)
					(end 5.3467 -289.935412)
				)
			)
		)
	)
	(zone
		(layers "F.Cu" "In5.Cu")
		(hatch none 0.5)
		(connect_pads
			(clearance 0)
		)
		(min_thickness 0.25)
		(keepout
			(tracks not_allowed)
			(vias allowed)
			(pads allowed)
			(copperpour not_allowed)
			(footprints allowed)
		)
		(placement
			(enabled no)
			(sheetname "")
		)
		(fill yes
			(thermal_gap 0.5)
			(thermal_bridge_width 0.5)
			(island_removal_mode 0)
		)
		(polygon
			(pts
				(arc
					(start 5.59054 -194.3354)
					(mid 5.08 -193.82486)
					(end 4.56946 -194.3354)
				)
				(arc
					(start 4.56946 -195.1482)
					(mid 5.07873 -195.658738)
					(end 5.59054 -195.15074)
				)
				(arc
					(start 5.3467 -195.15074)
					(mid 5.08 -195.414912)
					(end 4.8133 -195.15074)
				)
				(arc
					(start 4.8133 -195.1482)
					(mid 5.08 -194.8815)
					(end 5.3467 -195.1482)
				)
				(xy 5.59054 -195.1482) (xy 5.59054 -194.33794)
				(arc
					(start 5.3467 -194.33794)
					(mid 5.08 -194.602112)
					(end 4.8133 -194.33794)
				)
				(arc
					(start 4.8133 -194.3354)
					(mid 5.08 -194.0687)
					(end 5.3467 -194.3354)
				)
			)
		)
	)
	(zone
		(layers "F.Cu" "In5.Cu")
		(hatch none 0.5)
		(connect_pads
			(clearance 0)
		)
		(min_thickness 0.25)
		(keepout
			(tracks not_allowed)
			(vias allowed)
			(pads allowed)
			(copperpour not_allowed)
			(footprints allowed)
		)
		(placement
			(enabled no)
			(sheetname "")
		)
		(fill yes
			(thermal_gap 0.5)
			(thermal_bridge_width 0.5)
			(island_removal_mode 0)
		)
		(polygon
			(pts
				(arc
					(start 5.59054 -354.735384)
					(mid 5.08 -354.224844)
					(end 4.56946 -354.735384)
				)
				(arc
					(start 4.56946 -355.548184)
					(mid 5.07873 -356.058722)
					(end 5.59054 -355.550724)
				)
				(arc
					(start 5.3467 -355.550724)
					(mid 5.08 -355.814896)
					(end 4.8133 -355.550724)
				)
				(arc
					(start 4.8133 -355.548184)
					(mid 5.08 -355.281484)
					(end 5.3467 -355.548184)
				)
				(xy 5.59054 -355.548184) (xy 5.59054 -354.737924)
				(arc
					(start 5.3467 -354.737924)
					(mid 5.08 -355.002096)
					(end 4.8133 -354.737924)
				)
				(arc
					(start 4.8133 -354.735384)
					(mid 5.08 -354.468684)
					(end 5.3467 -354.735384)
				)
			)
		)
	)
	(zone
		(layers "F.Cu" "In5.Cu")
		(hatch none 0.5)
		(connect_pads
			(clearance 0)
		)
		(min_thickness 0.25)
		(keepout
			(tracks not_allowed)
			(vias allowed)
			(pads allowed)
			(copperpour not_allowed)
			(footprints allowed)
		)
		(placement
			(enabled no)
			(sheetname "")
		)
		(fill yes
			(thermal_gap 0.5)
			(thermal_bridge_width 0.5)
			(island_removal_mode 0)
		)
		(polygon
			(pts
				(arc
					(start 5.59054 -293.135304)
					(mid 5.08 -292.624764)
					(end 4.56946 -293.135304)
				)
				(arc
					(start 4.56946 -293.948104)
					(mid 5.07873 -294.458642)
					(end 5.59054 -293.950644)
				)
				(arc
					(start 5.3467 -293.950644)
					(mid 5.08 -294.214816)
					(end 4.8133 -293.950644)
				)
				(arc
					(start 4.8133 -293.948104)
					(mid 5.08 -293.681404)
					(end 5.3467 -293.948104)
				)
				(xy 5.59054 -293.948104) (xy 5.59054 -293.137844)
				(arc
					(start 5.3467 -293.137844)
					(mid 5.08 -293.402016)
					(end 4.8133 -293.137844)
				)
				(arc
					(start 4.8133 -293.135304)
					(mid 5.08 -292.868604)
					(end 5.3467 -293.135304)
				)
			)
		)
	)
	(zone
		(layers "F.Cu" "In5.Cu")
		(hatch none 0.5)
		(connect_pads
			(clearance 0)
		)
		(min_thickness 0.25)
		(keepout
			(tracks not_allowed)
			(vias allowed)
			(pads allowed)
			(copperpour not_allowed)
			(footprints allowed)
		)
		(placement
			(enabled no)
			(sheetname "")
		)
		(fill yes
			(thermal_gap 0.5)
			(thermal_bridge_width 0.5)
			(island_removal_mode 0)
		)
		(polygon
			(pts
				(arc
					(start 5.59054 -335.535524)
					(mid 5.08 -335.024984)
					(end 4.56946 -335.535524)
				)
				(arc
					(start 4.56946 -336.348324)
					(mid 5.07873 -336.858862)
					(end 5.59054 -336.350864)
				)
				(arc
					(start 5.3467 -336.350864)
					(mid 5.08 -336.615036)
					(end 4.8133 -336.350864)
				)
				(arc
					(start 4.8133 -336.348324)
					(mid 5.08 -336.081624)
					(end 5.3467 -336.348324)
				)
				(xy 5.59054 -336.348324) (xy 5.59054 -335.538064)
				(arc
					(start 5.3467 -335.538064)
					(mid 5.08 -335.802236)
					(end 4.8133 -335.538064)
				)
				(arc
					(start 4.8133 -335.535524)
					(mid 5.08 -335.268824)
					(end 5.3467 -335.535524)
				)
			)
		)
	)
	(zone
		(layers "F.Cu" "In5.Cu")
		(hatch none 0.5)
		(connect_pads
			(clearance 0)
		)
		(min_thickness 0.25)
		(keepout
			(tracks not_allowed)
			(vias allowed)
			(pads allowed)
			(copperpour not_allowed)
			(footprints allowed)
		)
		(placement
			(enabled no)
			(sheetname "")
		)
		(fill yes
			(thermal_gap 0.5)
			(thermal_bridge_width 0.5)
			(island_removal_mode 0)
		)
		(polygon
			(pts
				(arc
					(start 5.59054 -341.935308)
					(mid 5.08 -341.424768)
					(end 4.56946 -341.935308)
				)
				(arc
					(start 4.56946 -342.748108)
					(mid 5.07873 -343.258646)
					(end 5.59054 -342.750648)
				)
				(arc
					(start 5.3467 -342.750648)
					(mid 5.08 -343.01482)
					(end 4.8133 -342.750648)
				)
				(arc
					(start 4.8133 -342.748108)
					(mid 5.08 -342.481408)
					(end 5.3467 -342.748108)
				)
				(xy 5.59054 -342.748108) (xy 5.59054 -341.937848)
				(arc
					(start 5.3467 -341.937848)
					(mid 5.08 -342.20202)
					(end 4.8133 -341.937848)
				)
				(arc
					(start 4.8133 -341.935308)
					(mid 5.08 -341.668608)
					(end 5.3467 -341.935308)
				)
			)
		)
	)
	(zone
		(layers "F.Cu" "In5.Cu")
		(hatch none 0.5)
		(connect_pads
			(clearance 0)
		)
		(min_thickness 0.25)
		(keepout
			(tracks not_allowed)
			(vias allowed)
			(pads allowed)
			(copperpour not_allowed)
			(footprints allowed)
		)
		(placement
			(enabled no)
			(sheetname "")
		)
		(fill yes
			(thermal_gap 0.5)
			(thermal_bridge_width 0.5)
			(island_removal_mode 0)
		)
		(polygon
			(pts
				(arc
					(start 5.59054 -395.1351)
					(mid 5.08 -394.62456)
					(end 4.56946 -395.1351)
				)
				(arc
					(start 4.56946 -395.9479)
					(mid 5.07873 -396.458438)
					(end 5.59054 -395.95044)
				)
				(arc
					(start 5.3467 -395.95044)
					(mid 5.08 -396.214612)
					(end 4.8133 -395.95044)
				)
				(arc
					(start 4.8133 -395.9479)
					(mid 5.08 -395.6812)
					(end 5.3467 -395.9479)
				)
				(xy 5.59054 -395.9479) (xy 5.59054 -395.13764)
				(arc
					(start 5.3467 -395.13764)
					(mid 5.08 -395.401812)
					(end 4.8133 -395.13764)
				)
				(arc
					(start 4.8133 -395.1351)
					(mid 5.08 -394.8684)
					(end 5.3467 -395.1351)
				)
			)
		)
	)
	(zone
		(layers "F.Cu" "In5.Cu")
		(hatch none 0.5)
		(connect_pads
			(clearance 0)
		)
		(min_thickness 0.25)
		(keepout
			(tracks not_allowed)
			(vias allowed)
			(pads allowed)
			(copperpour not_allowed)
			(footprints allowed)
		)
		(placement
			(enabled no)
			(sheetname "")
		)
		(fill yes
			(thermal_gap 0.5)
			(thermal_bridge_width 0.5)
			(island_removal_mode 0)
		)
		(polygon
			(pts
				(arc
					(start 5.59054 -391.935208)
					(mid 5.08 -391.424668)
					(end 4.56946 -391.935208)
				)
				(arc
					(start 4.56946 -392.748008)
					(mid 5.07873 -393.258546)
					(end 5.59054 -392.750548)
				)
				(arc
					(start 5.3467 -392.750548)
					(mid 5.08 -393.01472)
					(end 4.8133 -392.750548)
				)
				(arc
					(start 4.8133 -392.748008)
					(mid 5.08 -392.481308)
					(end 5.3467 -392.748008)
				)
				(xy 5.59054 -392.748008) (xy 5.59054 -391.937748)
				(arc
					(start 5.3467 -391.937748)
					(mid 5.08 -392.20192)
					(end 4.8133 -391.937748)
				)
				(arc
					(start 4.8133 -391.935208)
					(mid 5.08 -391.668508)
					(end 5.3467 -391.935208)
				)
			)
		)
	)
	(zone
		(layers "F.Cu" "In5.Cu")
		(hatch none 0.5)
		(connect_pads
			(clearance 0)
		)
		(min_thickness 0.25)
		(keepout
			(tracks not_allowed)
			(vias allowed)
			(pads allowed)
			(copperpour not_allowed)
			(footprints allowed)
		)
		(placement
			(enabled no)
			(sheetname "")
		)
		(fill yes
			(thermal_gap 0.5)
			(thermal_bridge_width 0.5)
			(island_removal_mode 0)
		)
		(polygon
			(pts
				(arc
					(start 5.59054 -438.335166)
					(mid 5.08 -437.824626)
					(end 4.56946 -438.335166)
				)
				(arc
					(start 4.56946 -439.147712)
					(mid 5.078603 -439.658504)
					(end 5.59054 -439.150506)
				)
				(arc
					(start 5.3467 -439.150506)
					(mid 5.08 -439.414678)
					(end 4.8133 -439.150506)
				)
				(arc
					(start 4.8133 -439.147966)
					(mid 5.08 -438.881266)
					(end 5.3467 -439.147966)
				)
				(xy 5.59054 -439.147966) (xy 5.59054 -438.337706)
				(arc
					(start 5.3467 -438.337706)
					(mid 5.08 -438.601878)
					(end 4.8133 -438.337706)
				)
				(arc
					(start 4.8133 -438.335166)
					(mid 5.08 -438.068466)
					(end 5.3467 -438.335166)
				)
			)
		)
	)
	(zone
		(layers "F.Cu" "In5.Cu")
		(hatch none 0.5)
		(connect_pads
			(clearance 0)
		)
		(min_thickness 0.25)
		(keepout
			(tracks not_allowed)
			(vias allowed)
			(pads allowed)
			(copperpour not_allowed)
			(footprints allowed)
		)
		(placement
			(enabled no)
			(sheetname "")
		)
		(fill yes
			(thermal_gap 0.5)
			(thermal_bridge_width 0.5)
			(island_removal_mode 0)
		)
		(polygon
			(pts
				(arc
					(start 5.59054 -170.335448)
					(mid 5.08 -169.824908)
					(end 4.56946 -170.335448)
				)
				(arc
					(start 4.56946 -171.148248)
					(mid 5.07873 -171.658786)
					(end 5.59054 -171.150788)
				)
				(arc
					(start 5.3467 -171.150788)
					(mid 5.08 -171.41496)
					(end 4.8133 -171.150788)
				)
				(arc
					(start 4.8133 -171.148248)
					(mid 5.08 -170.881548)
					(end 5.3467 -171.148248)
				)
				(xy 5.59054 -171.148248) (xy 5.59054 -170.337988)
				(arc
					(start 5.3467 -170.337988)
					(mid 5.08 -170.60216)
					(end 4.8133 -170.337988)
				)
				(arc
					(start 4.8133 -170.335448)
					(mid 5.08 -170.068748)
					(end 5.3467 -170.335448)
				)
			)
		)
	)
	(zone
		(layers "F.Cu" "In5.Cu")
		(hatch none 0.5)
		(connect_pads
			(clearance 0)
		)
		(min_thickness 0.25)
		(keepout
			(tracks not_allowed)
			(vias allowed)
			(pads allowed)
			(copperpour not_allowed)
			(footprints allowed)
		)
		(placement
			(enabled no)
			(sheetname "")
		)
		(fill yes
			(thermal_gap 0.5)
			(thermal_bridge_width 0.5)
			(island_removal_mode 0)
		)
		(polygon
			(pts
				(arc
					(start 5.59054 -228.735382)
					(mid 5.08 -228.224842)
					(end 4.56946 -228.735382)
				)
				(arc
					(start 4.56946 -229.548182)
					(mid 5.07873 -230.05872)
					(end 5.59054 -229.550722)
				)
				(arc
					(start 5.3467 -229.550722)
					(mid 5.08 -229.814894)
					(end 4.8133 -229.550722)
				)
				(arc
					(start 4.8133 -229.548182)
					(mid 5.08 -229.281482)
					(end 5.3467 -229.548182)
				)
				(xy 5.59054 -229.548182) (xy 5.59054 -228.737922)
				(arc
					(start 5.3467 -228.737922)
					(mid 5.08 -229.002094)
					(end 4.8133 -228.737922)
				)
				(arc
					(start 4.8133 -228.735382)
					(mid 5.08 -228.468682)
					(end 5.3467 -228.735382)
				)
			)
		)
	)
	(zone
		(layers "F.Cu" "In5.Cu")
		(hatch none 0.5)
		(connect_pads
			(clearance 0)
		)
		(min_thickness 0.25)
		(keepout
			(tracks not_allowed)
			(vias allowed)
			(pads allowed)
			(copperpour not_allowed)
			(footprints allowed)
		)
		(placement
			(enabled no)
			(sheetname "")
		)
		(fill yes
			(thermal_gap 0.5)
			(thermal_bridge_width 0.5)
			(island_removal_mode 0)
		)
		(polygon
			(pts
				(arc
					(start 5.59054 -176.735486)
					(mid 5.08 -176.224946)
					(end 4.56946 -176.735486)
				)
				(arc
					(start 4.56946 -177.548286)
					(mid 5.07873 -178.058824)
					(end 5.59054 -177.550826)
				)
				(arc
					(start 5.3467 -177.550826)
					(mid 5.08 -177.814998)
					(end 4.8133 -177.550826)
				)
				(arc
					(start 4.8133 -177.548286)
					(mid 5.08 -177.281586)
					(end 5.3467 -177.548286)
				)
				(xy 5.59054 -177.548286) (xy 5.59054 -176.738026)
				(arc
					(start 5.3467 -176.738026)
					(mid 5.08 -177.002198)
					(end 4.8133 -176.738026)
				)
				(arc
					(start 4.8133 -176.735486)
					(mid 5.08 -176.468786)
					(end 5.3467 -176.735486)
				)
			)
		)
	)
	(zone
		(layers "F.Cu" "In5.Cu")
		(hatch none 0.5)
		(connect_pads
			(clearance 0)
		)
		(min_thickness 0.25)
		(keepout
			(tracks not_allowed)
			(vias allowed)
			(pads allowed)
			(copperpour not_allowed)
			(footprints allowed)
		)
		(placement
			(enabled no)
			(sheetname "")
		)
		(fill yes
			(thermal_gap 0.5)
			(thermal_bridge_width 0.5)
			(island_removal_mode 0)
		)
		(polygon
			(pts
				(arc
					(start 5.59054 -388.735316)
					(mid 5.08 -388.224776)
					(end 4.56946 -388.735316)
				)
				(arc
					(start 4.56946 -389.548116)
					(mid 5.07873 -390.058654)
					(end 5.59054 -389.550656)
				)
				(arc
					(start 5.3467 -389.550656)
					(mid 5.08 -389.814828)
					(end 4.8133 -389.550656)
				)
				(arc
					(start 4.8133 -389.548116)
					(mid 5.08 -389.281416)
					(end 5.3467 -389.548116)
				)
				(xy 5.59054 -389.548116) (xy 5.59054 -388.737856)
				(arc
					(start 5.3467 -388.737856)
					(mid 5.08 -389.002028)
					(end 4.8133 -388.737856)
				)
				(arc
					(start 4.8133 -388.735316)
					(mid 5.08 -388.468616)
					(end 5.3467 -388.735316)
				)
			)
		)
	)
	(zone
		(layers "F.Cu" "In5.Cu")
		(hatch none 0.5)
		(connect_pads
			(clearance 0)
		)
		(min_thickness 0.25)
		(keepout
			(tracks not_allowed)
			(vias allowed)
			(pads allowed)
			(copperpour not_allowed)
			(footprints allowed)
		)
		(placement
			(enabled no)
			(sheetname "")
		)
		(fill yes
			(thermal_gap 0.5)
			(thermal_bridge_width 0.5)
			(island_removal_mode 0)
		)
		(polygon
			(pts
				(arc
					(start 5.59054 -296.33545)
					(mid 5.08 -295.82491)
					(end 4.56946 -296.33545)
				)
				(arc
					(start 4.56946 -297.14825)
					(mid 5.07873 -297.658788)
					(end 5.59054 -297.15079)
				)
				(arc
					(start 5.3467 -297.15079)
					(mid 5.08 -297.414962)
					(end 4.8133 -297.15079)
				)
				(arc
					(start 4.8133 -297.14825)
					(mid 5.08 -296.88155)
					(end 5.3467 -297.14825)
				)
				(xy 5.59054 -297.14825) (xy 5.59054 -296.33799)
				(arc
					(start 5.3467 -296.33799)
					(mid 5.08 -296.602162)
					(end 4.8133 -296.33799)
				)
				(arc
					(start 4.8133 -296.33545)
					(mid 5.08 -296.06875)
					(end 5.3467 -296.33545)
				)
			)
		)
	)
	(zone
		(layers "F.Cu" "In5.Cu")
		(hatch none 0.5)
		(connect_pads
			(clearance 0)
		)
		(min_thickness 0.25)
		(keepout
			(tracks not_allowed)
			(vias allowed)
			(pads allowed)
			(copperpour not_allowed)
			(footprints allowed)
		)
		(placement
			(enabled no)
			(sheetname "")
		)
		(fill yes
			(thermal_gap 0.5)
			(thermal_bridge_width 0.5)
			(island_removal_mode 0)
		)
		(polygon
			(pts
				(arc
					(start 5.59054 -338.735416)
					(mid 5.08 -338.224876)
					(end 4.56946 -338.735416)
				)
				(arc
					(start 4.56946 -339.548216)
					(mid 5.07873 -340.058754)
					(end 5.59054 -339.550756)
				)
				(arc
					(start 5.3467 -339.550756)
					(mid 5.08 -339.814928)
					(end 4.8133 -339.550756)
				)
				(arc
					(start 4.8133 -339.548216)
					(mid 5.08 -339.281516)
					(end 5.3467 -339.548216)
				)
				(xy 5.59054 -339.548216) (xy 5.59054 -338.737956)
				(arc
					(start 5.3467 -338.737956)
					(mid 5.08 -339.002128)
					(end 4.8133 -338.737956)
				)
				(arc
					(start 4.8133 -338.735416)
					(mid 5.08 -338.468716)
					(end 5.3467 -338.735416)
				)
			)
		)
	)
	(zone
		(layers "F.Cu" "In5.Cu")
		(hatch none 0.5)
		(connect_pads
			(clearance 0)
		)
		(min_thickness 0.25)
		(keepout
			(tracks not_allowed)
			(vias allowed)
			(pads allowed)
			(copperpour not_allowed)
			(footprints allowed)
		)
		(placement
			(enabled no)
			(sheetname "")
		)
		(fill yes
			(thermal_gap 0.5)
			(thermal_bridge_width 0.5)
			(island_removal_mode 0)
		)
		(polygon
			(pts
				(arc
					(start 5.59054 -231.935528)
					(mid 5.08 -231.424988)
					(end 4.56946 -231.935528)
				)
				(arc
					(start 4.56946 -232.748328)
					(mid 5.07873 -233.258866)
					(end 5.59054 -232.750868)
				)
				(arc
					(start 5.3467 -232.750868)
					(mid 5.08 -233.01504)
					(end 4.8133 -232.750868)
				)
				(arc
					(start 4.8133 -232.748328)
					(mid 5.08 -232.481628)
					(end 5.3467 -232.748328)
				)
				(xy 5.59054 -232.748328) (xy 5.59054 -231.938068)
				(arc
					(start 5.3467 -231.938068)
					(mid 5.08 -232.20224)
					(end 4.8133 -231.938068)
				)
				(arc
					(start 4.8133 -231.935528)
					(mid 5.08 -231.668828)
					(end 5.3467 -231.935528)
				)
			)
		)
	)
	(zone
		(layers "F.Cu" "In5.Cu")
		(hatch none 0.5)
		(connect_pads
			(clearance 0)
		)
		(min_thickness 0.25)
		(keepout
			(tracks not_allowed)
			(vias allowed)
			(pads allowed)
			(copperpour not_allowed)
			(footprints allowed)
		)
		(placement
			(enabled no)
			(sheetname "")
		)
		(fill yes
			(thermal_gap 0.5)
			(thermal_bridge_width 0.5)
			(island_removal_mode 0)
		)
		(polygon
			(pts
				(arc
					(start 5.59054 -305.93538)
					(mid 5.08 -305.42484)
					(end 4.56946 -305.93538)
				)
				(arc
					(start 4.56946 -306.74818)
					(mid 5.07873 -307.258718)
					(end 5.59054 -306.75072)
				)
				(arc
					(start 5.3467 -306.75072)
					(mid 5.08 -307.014892)
					(end 4.8133 -306.75072)
				)
				(arc
					(start 4.8133 -306.74818)
					(mid 5.08 -306.48148)
					(end 5.3467 -306.74818)
				)
				(xy 5.59054 -306.74818) (xy 5.59054 -305.93792)
				(arc
					(start 5.3467 -305.93792)
					(mid 5.08 -306.202092)
					(end 4.8133 -305.93792)
				)
				(arc
					(start 4.8133 -305.93538)
					(mid 5.08 -305.66868)
					(end 5.3467 -305.93538)
				)
			)
		)
	)
	(zone
		(layers "F.Cu" "In5.Cu")
		(hatch none 0.5)
		(connect_pads
			(clearance 0)
		)
		(min_thickness 0.25)
		(keepout
			(tracks not_allowed)
			(vias allowed)
			(pads allowed)
			(copperpour not_allowed)
			(footprints allowed)
		)
		(placement
			(enabled no)
			(sheetname "")
		)
		(fill yes
			(thermal_gap 0.5)
			(thermal_bridge_width 0.5)
			(island_removal_mode 0)
		)
		(polygon
			(pts
				(arc
					(start 5.59054 -413.535114)
					(mid 5.08 -413.024574)
					(end 4.56946 -413.535114)
				)
				(arc
					(start 4.56946 -414.34766)
					(mid 5.078603 -414.858452)
					(end 5.59054 -414.350454)
				)
				(arc
					(start 5.3467 -414.350454)
					(mid 5.08 -414.614626)
					(end 4.8133 -414.350454)
				)
				(arc
					(start 4.8133 -414.347914)
					(mid 5.08 -414.081214)
					(end 5.3467 -414.347914)
				)
				(xy 5.59054 -414.347914) (xy 5.59054 -413.537654)
				(arc
					(start 5.3467 -413.537654)
					(mid 5.08 -413.801826)
					(end 4.8133 -413.537654)
				)
				(arc
					(start 4.8133 -413.535114)
					(mid 5.08 -413.268414)
					(end 5.3467 -413.535114)
				)
			)
		)
	)
	(zone
		(layers "F.Cu" "In5.Cu")
		(hatch none 0.5)
		(connect_pads
			(clearance 0)
		)
		(min_thickness 0.25)
		(keepout
			(tracks not_allowed)
			(vias allowed)
			(pads allowed)
			(copperpour not_allowed)
			(footprints allowed)
		)
		(placement
			(enabled no)
			(sheetname "")
		)
		(fill yes
			(thermal_gap 0.5)
			(thermal_bridge_width 0.5)
			(island_removal_mode 0)
		)
		(polygon
			(pts
				(arc
					(start 5.59054 -157.535372)
					(mid 5.08 -157.024832)
					(end 4.56946 -157.535372)
				)
				(arc
					(start 4.56946 -158.348172)
					(mid 5.07873 -158.85871)
					(end 5.59054 -158.350712)
				)
				(arc
					(start 5.3467 -158.350712)
					(mid 5.08 -158.614884)
					(end 4.8133 -158.350712)
				)
				(arc
					(start 4.8133 -158.348172)
					(mid 5.08 -158.081472)
					(end 5.3467 -158.348172)
				)
				(xy 5.59054 -158.348172) (xy 5.59054 -157.537912)
				(arc
					(start 5.3467 -157.537912)
					(mid 5.08 -157.802084)
					(end 4.8133 -157.537912)
				)
				(arc
					(start 4.8133 -157.535372)
					(mid 5.08 -157.268672)
					(end 5.3467 -157.535372)
				)
			)
		)
	)
	(zone
		(layer "B.Cu")
		(hatch none 0.5)
		(connect_pads
			(clearance 0)
		)
		(min_thickness 0.25)
		(keepout
			(tracks not_allowed)
			(vias allowed)
			(pads allowed)
			(copperpour not_allowed)
			(footprints allowed)
		)
		(placement
			(enabled no)
			(sheetname "")
		)
		(fill
			(thermal_gap 0.5)
			(thermal_bridge_width 0.5)
			(island_removal_mode 0)
		)
		(polygon
			(pts
				(arc
					(start 233.897424 -60.579254)
					(mid 233.386884 -60.068714)
					(end 232.876344 -60.579254)
				)
				(xy 232.876344 -60.732924) (xy 233.091736 -60.732924)
				(arc
					(start 233.141266 -60.683394)
					(mid 233.575528 -60.39061)
					(end 233.282744 -60.824872)
				)
				(xy 233.17454 -60.933076) (xy 232.876344 -60.933076) (xy 232.876344 -61.037978) (xy 233.174286 -61.037978)
				(arc
					(start 233.282744 -61.146436)
					(mid 233.575528 -61.580698)
					(end 233.141266 -61.287914)
				)
				(xy 233.091482 -61.23813) (xy 232.876344 -61.23813)
				(arc
					(start 232.876344 -61.3918)
					(mid 233.386757 -61.902594)
					(end 233.897424 -61.392054)
				)
			)
		)
	)
	(zone
		(layer "B.Cu")
		(hatch none 0.5)
		(connect_pads
			(clearance 0)
		)
		(min_thickness 0.25)
		(keepout
			(tracks not_allowed)
			(vias allowed)
			(pads allowed)
			(copperpour not_allowed)
			(footprints allowed)
		)
		(placement
			(enabled no)
			(sheetname "")
		)
		(fill
			(thermal_gap 0.5)
			(thermal_bridge_width 0.5)
			(island_removal_mode 0)
		)
		(polygon
			(pts
				(arc
					(start 48.89754 -369.579652)
					(mid 48.387127 -369.068858)
					(end 47.87646 -369.579398)
				)
				(xy 47.87646 -369.733068) (xy 48.091852 -369.733068)
				(arc
					(start 48.141382 -369.683538)
					(mid 48.575644 -369.390754)
					(end 48.28286 -369.825016)
				)
				(xy 48.174656 -369.93322) (xy 47.87646 -369.93322) (xy 47.87646 -370.038122) (xy 48.174402 -370.038122)
				(arc
					(start 48.28286 -370.14658)
					(mid 48.575644 -370.580842)
					(end 48.141382 -370.288058)
				)
				(xy 48.091598 -370.238274) (xy 47.87646 -370.238274)
				(arc
					(start 47.87646 -370.392198)
					(mid 48.387 -370.902738)
					(end 48.89754 -370.392198)
				)
			)
		)
	)
	(zone
		(net "GND")
		(layer "B.Cu")
		(hatch none 0.5)
		(connect_pads
			(clearance 0.5)
		)
		(min_thickness 0.25)
		(fill yes
			(thermal_gap 0.5)
			(thermal_bridge_width 0.5)
			(island_removal_mode 0)
		)
		(polygon
			(pts
				(xy 80.6958 -384.0734) (xy 76.1238 -384.0734) (xy 60.706 -399.4912) (xy 60.706 -432.435) (xy 61.849 -433.578)
				(xy 65.024 -433.578) (xy 66.138806 -432.463194) (xy 76.298806 -432.463194) (xy 83.3882 -425.3738)
				(xy 83.3882 -386.7658)
			)
		)
	)
	(zone
		(layer "B.Cu")
		(hatch none 0.5)
		(connect_pads
			(clearance 0)
		)
		(min_thickness 0.25)
		(keepout
			(tracks not_allowed)
			(vias allowed)
			(pads allowed)
			(copperpour not_allowed)
			(footprints allowed)
		)
		(placement
			(enabled no)
			(sheetname "")
		)
		(fill
			(thermal_gap 0.5)
			(thermal_bridge_width 0.5)
			(island_removal_mode 0)
		)
		(polygon
			(pts
				(arc
					(start 5.59054 -206.33563)
					(mid 5.080127 -205.824836)
					(end 4.56946 -206.335376)
				)
				(xy 4.56946 -206.489554) (xy 4.784344 -206.489554)
				(arc
					(start 4.834382 -206.439516)
					(mid 5.268644 -206.146732)
					(end 4.97586 -206.580994)
				)
				(xy 4.867148 -206.689706) (xy 4.56946 -206.689706) (xy 4.56946 -206.794608) (xy 4.86791 -206.794608)
				(arc
					(start 4.97586 -206.902558)
					(mid 5.268644 -207.33682)
					(end 4.834382 -207.044036)
				)
				(xy 4.785106 -206.99476) (xy 4.56946 -206.99476)
				(arc
					(start 4.56946 -207.148176)
					(mid 5.08 -207.658716)
					(end 5.59054 -207.148176)
				)
			)
		)
	)
	(zone
		(net "P3V3")
		(layer "B.Cu")
		(hatch none 0.5)
		(connect_pads
			(clearance 0.5)
		)
		(min_thickness 0.25)
		(fill yes
			(thermal_gap 0.5)
			(thermal_bridge_width 0.5)
			(island_removal_mode 0)
		)
		(polygon
			(pts
				(xy 17.526 -442.214) (xy 17.526 -443.103) (xy 17.7292 -443.3062) (xy 17.7292 -443.9666) (xy 17.8816 -444.119)
				(xy 19.431 -444.119) (xy 19.939 -443.611) (xy 19.939 -442.9506) (xy 19.0754 -442.087) (xy 17.653 -442.087)
			)
		)
	)
	(zone
		(net "GND")
		(layer "B.Cu")
		(hatch none 0.5)
		(connect_pads
			(clearance 0.5)
		)
		(min_thickness 0.25)
		(fill yes
			(thermal_gap 0.5)
			(thermal_bridge_width 0.5)
			(island_removal_mode 0)
		)
		(polygon
			(pts
				(xy 68.707 -165.1) (xy 63.4746 -170.3324) (xy 63.4746 -194.9196) (xy 42.2402 -216.154) (xy 35.179 -216.154)
				(xy 34.036 -217.297) (xy 34.036 -221.5642) (xy 54.991 -242.5192) (xy 54.991 -339.852) (xy 57.023 -341.884)
				(xy 57.023 -382.778) (xy 48.895 -390.906) (xy 48.895 -391.541) (xy 49.403 -392.049) (xy 51.816 -392.049)
				(xy 61.849 -382.016) (xy 61.849 -374.777) (xy 69.469 -367.157) (xy 78.232 -367.157) (xy 79.756 -365.633)
				(xy 79.756 -359.156) (xy 77.089 -356.489) (xy 74.93 -356.489) (xy 71.7804 -353.3394) (xy 71.7804 -350.6216)
				(xy 72.517 -349.885) (xy 72.517 -307.213) (xy 75.184 -304.546) (xy 77.724 -304.546) (xy 80.137 -302.133)
				(xy 80.899 -302.133) (xy 83.693 -299.339) (xy 83.693 -295.2496) (xy 82.6262 -294.1828) (xy 82.6262 -214.7316)
				(xy 76.2 -208.3054) (xy 76.2 -167.64) (xy 73.66 -165.1)
			)
		)
		(polygon
			(pts
				(xy 70.485 -299.593) (xy 67.564 -299.593) (xy 67.183 -299.974) (xy 67.183 -301.371) (xy 68.453 -302.641)
				(xy 68.453 -346.440252) (xy 64.098424 -350.794828) (xy 64.098424 -357.161338) (xy 66.836798 -359.899712)
				(xy 66.836798 -360.550714) (xy 66.399918 -360.987594) (xy 65.858136 -360.987594) (xy 59.848242 -354.9777)
				(xy 59.848242 -325.201534) (xy 62.738 -322.311776) (xy 62.738 -318.643) (xy 62.103 -318.008) (xy 60.706 -318.008)
				(xy 58.42 -320.294) (xy 58.42 -355.64953) (xy 66.75247 -363.982) (xy 69.85 -363.982) (xy 70.485 -363.347)
				(xy 70.485 -358.902) (xy 69.723 -358.14) (xy 67.818 -358.14) (xy 65.913 -356.235) (xy 65.913 -351.197672)
				(xy 70.104 -347.006672) (xy 70.104 -302.26) (xy 71.12 -301.244) (xy 71.12 -300.228)
			)
		)
	)
	(zone
		(layer "B.Cu")
		(hatch none 0.5)
		(connect_pads
			(clearance 0)
		)
		(min_thickness 0.25)
		(keepout
			(tracks not_allowed)
			(vias allowed)
			(pads allowed)
			(copperpour not_allowed)
			(footprints allowed)
		)
		(placement
			(enabled no)
			(sheetname "")
		)
		(fill
			(thermal_gap 0.5)
			(thermal_bridge_width 0.5)
			(island_removal_mode 0)
		)
		(polygon
			(pts
				(arc
					(start 5.59054 -323.535548)
					(mid 5.080127 -323.024754)
					(end 4.56946 -323.535294)
				)
				(xy 4.56946 -323.689472) (xy 4.784344 -323.689472)
				(arc
					(start 4.834382 -323.639434)
					(mid 5.268644 -323.34665)
					(end 4.97586 -323.780912)
				)
				(xy 4.867148 -323.889624) (xy 4.56946 -323.889624) (xy 4.56946 -323.994526) (xy 4.86791 -323.994526)
				(arc
					(start 4.97586 -324.102476)
					(mid 5.268644 -324.536738)
					(end 4.834382 -324.243954)
				)
				(xy 4.785106 -324.194678) (xy 4.56946 -324.194678)
				(arc
					(start 4.56946 -324.348094)
					(mid 5.08 -324.858634)
					(end 5.59054 -324.348094)
				)
			)
		)
	)
	(zone
		(layer "B.Cu")
		(hatch none 0.5)
		(connect_pads
			(clearance 0)
		)
		(min_thickness 0.25)
		(keepout
			(tracks not_allowed)
			(vias allowed)
			(pads allowed)
			(copperpour not_allowed)
			(footprints allowed)
		)
		(placement
			(enabled no)
			(sheetname "")
		)
		(fill
			(thermal_gap 0.5)
			(thermal_bridge_width 0.5)
			(island_removal_mode 0)
		)
		(polygon
			(pts
				(arc
					(start 17.78254 -341.60333)
					(mid 17.272 -341.09279)
					(end 16.76146 -341.60333)
				)
				(arc
					(start 16.76146 -342.415876)
					(mid 17.271873 -342.92667)
					(end 17.78254 -342.41613)
				)
				(xy 17.78254 -342.24341) (xy 17.586198 -342.24341)
				(arc
					(start 17.517618 -342.31199)
					(mid 17.083356 -342.604774)
					(end 17.37614 -342.170512)
				)
				(xy 17.503394 -342.043258) (xy 17.78254 -342.043258) (xy 17.78254 -341.938356) (xy 17.465548 -341.938356)
				(arc
					(start 17.37614 -341.848948)
					(mid 17.083356 -341.414686)
					(end 17.517618 -341.70747)
				)
				(xy 17.548352 -341.738204) (xy 17.78254 -341.738204)
			)
		)
	)
	(zone
		(layer "B.Cu")
		(hatch none 0.5)
		(connect_pads
			(clearance 0)
		)
		(min_thickness 0.25)
		(keepout
			(tracks not_allowed)
			(vias allowed)
			(pads allowed)
			(copperpour not_allowed)
			(footprints allowed)
		)
		(placement
			(enabled no)
			(sheetname "")
		)
		(fill
			(thermal_gap 0.5)
			(thermal_bridge_width 0.5)
			(island_removal_mode 0)
		)
		(polygon
			(pts
				(arc
					(start 233.897424 -472.579446)
					(mid 233.386884 -472.068906)
					(end 232.876344 -472.579446)
				)
				(xy 232.876344 -472.733116) (xy 233.091736 -472.733116)
				(arc
					(start 233.141266 -472.683586)
					(mid 233.575528 -472.390802)
					(end 233.282744 -472.825064)
				)
				(xy 233.17454 -472.933268) (xy 232.876344 -472.933268) (xy 232.876344 -473.03817) (xy 233.174286 -473.03817)
				(arc
					(start 233.282744 -473.146628)
					(mid 233.575528 -473.58089)
					(end 233.141266 -473.288106)
				)
				(xy 233.091482 -473.238322) (xy 232.876344 -473.238322)
				(arc
					(start 232.876344 -473.391992)
					(mid 233.386757 -473.902786)
					(end 233.897424 -473.392246)
				)
			)
		)
	)
	(zone
		(layer "B.Cu")
		(hatch none 0.5)
		(connect_pads
			(clearance 0)
		)
		(min_thickness 0.25)
		(keepout
			(tracks allowed)
			(vias allowed)
			(pads allowed)
			(copperpour allowed)
			(footprints allowed)
		)
		(placement
			(enabled no)
			(sheetname "")
		)
		(fill
			(thermal_gap 0.5)
			(thermal_bridge_width 0.5)
			(island_removal_mode 0)
		)
		(polygon
			(pts
				(xy 1.1684 -383.667) (xy 1.1684 -418.719) (xy 7.239 -418.719) (xy 7.239 -383.667)
			)
		)
	)
	(zone
		(layer "B.Cu")
		(hatch none 0.5)
		(connect_pads
			(clearance 0)
		)
		(min_thickness 0.25)
		(keepout
			(tracks not_allowed)
			(vias allowed)
			(pads allowed)
			(copperpour not_allowed)
			(footprints allowed)
		)
		(placement
			(enabled no)
			(sheetname "")
		)
		(fill
			(thermal_gap 0.5)
			(thermal_bridge_width 0.5)
			(island_removal_mode 0)
		)
		(polygon
			(pts
				(arc
					(start 32.00654 -135.603996)
					(mid 31.496127 -135.093202)
					(end 30.98546 -135.603742)
				)
				(xy 30.98546 -135.757412) (xy 31.200852 -135.757412)
				(arc
					(start 31.250382 -135.707882)
					(mid 31.684644 -135.415098)
					(end 31.39186 -135.84936)
				)
				(xy 31.283656 -135.957564) (xy 30.98546 -135.957564) (xy 30.98546 -136.062466) (xy 31.283402 -136.062466)
				(arc
					(start 31.39186 -136.170924)
					(mid 31.684644 -136.605186)
					(end 31.250382 -136.312402)
				)
				(xy 31.200598 -136.262618) (xy 30.98546 -136.262618)
				(arc
					(start 30.98546 -136.416542)
					(mid 31.496 -136.927082)
					(end 32.00654 -136.416542)
				)
			)
		)
	)
	(zone
		(layer "B.Cu")
		(hatch none 0.5)
		(connect_pads
			(clearance 0)
		)
		(min_thickness 0.25)
		(keepout
			(tracks not_allowed)
			(vias allowed)
			(pads allowed)
			(copperpour not_allowed)
			(footprints allowed)
		)
		(placement
			(enabled no)
			(sheetname "")
		)
		(fill
			(thermal_gap 0.5)
			(thermal_bridge_width 0.5)
			(island_removal_mode 0)
		)
		(polygon
			(pts
				(arc
					(start 74.000106 -272.997422)
					(mid 70.000114 -268.99743)
					(end 66.000122 -272.997422)
				)
				(arc
					(start 66.000122 -276.497542)
					(mid 70.000114 -280.497534)
					(end 74.000106 -276.497542)
				)
			)
		)
	)
	(zone
		(layer "B.Cu")
		(hatch none 0.5)
		(connect_pads
			(clearance 0)
		)
		(min_thickness 0.25)
		(keepout
			(tracks not_allowed)
			(vias allowed)
			(pads allowed)
			(copperpour not_allowed)
			(footprints allowed)
		)
		(placement
			(enabled no)
			(sheetname "")
		)
		(fill
			(thermal_gap 0.5)
			(thermal_bridge_width 0.5)
			(island_removal_mode 0)
		)
		(polygon
			(pts
				(arc
					(start 33.40354 -341.584788)
					(mid 32.893127 -341.073994)
					(end 32.38246 -341.584534)
				)
				(xy 32.38246 -341.738204) (xy 32.597852 -341.738204)
				(arc
					(start 32.647382 -341.688674)
					(mid 33.081644 -341.39589)
					(end 32.78886 -341.830152)
				)
				(xy 32.680656 -341.938356) (xy 32.38246 -341.938356) (xy 32.38246 -342.043258) (xy 32.680402 -342.043258)
				(arc
					(start 32.78886 -342.151716)
					(mid 33.081644 -342.585978)
					(end 32.647382 -342.293194)
				)
				(xy 32.597598 -342.24341) (xy 32.38246 -342.24341)
				(arc
					(start 32.38246 -342.397334)
					(mid 32.893 -342.907874)
					(end 33.40354 -342.397334)
				)
			)
		)
	)
	(zone
		(net "P12V_SSD5")
		(layer "B.Cu")
		(hatch none 0.5)
		(connect_pads
			(clearance 0.5)
		)
		(min_thickness 0.25)
		(fill yes
			(thermal_gap 0.5)
			(thermal_bridge_width 0.5)
			(island_removal_mode 0)
		)
		(polygon
			(pts
				(xy 35.0774 -501.269) (xy 37.9984 -501.269) (xy 38.862 -501.269) (xy 39.1668 -500.9642) (xy 39.1668 -496.3922)
				(xy 39.0144 -496.2398) (xy 38.0492 -496.2398) (xy 35.052 -496.2398) (xy 33.6042 -496.2398) (xy 33.3756 -496.4684)
				(xy 33.3756 -500.888) (xy 33.7566 -501.269)
			)
		)
	)
	(zone
		(layer "B.Cu")
		(hatch none 0.5)
		(connect_pads
			(clearance 0)
		)
		(min_thickness 0.25)
		(keepout
			(tracks not_allowed)
			(vias allowed)
			(pads allowed)
			(copperpour not_allowed)
			(footprints allowed)
		)
		(placement
			(enabled no)
			(sheetname "")
		)
		(fill
			(thermal_gap 0.5)
			(thermal_bridge_width 0.5)
			(island_removal_mode 0)
		)
		(polygon
			(pts
				(arc
					(start 48.89754 -60.579508)
					(mid 48.387127 -60.068714)
					(end 47.87646 -60.579254)
				)
				(xy 47.87646 -60.732924) (xy 48.091852 -60.732924)
				(arc
					(start 48.141382 -60.683394)
					(mid 48.575644 -60.39061)
					(end 48.28286 -60.824872)
				)
				(xy 48.174656 -60.933076) (xy 47.87646 -60.933076) (xy 47.87646 -61.037978) (xy 48.174402 -61.037978)
				(arc
					(start 48.28286 -61.146436)
					(mid 48.575644 -61.580698)
					(end 48.141382 -61.287914)
				)
				(xy 48.091598 -61.23813) (xy 47.87646 -61.23813)
				(arc
					(start 47.87646 -61.392054)
					(mid 48.387 -61.902594)
					(end 48.89754 -61.392054)
				)
			)
		)
	)
	(zone
		(layer "B.Cu")
		(hatch none 0.5)
		(connect_pads
			(clearance 0)
		)
		(min_thickness 0.25)
		(keepout
			(tracks not_allowed)
			(vias allowed)
			(pads allowed)
			(copperpour not_allowed)
			(footprints allowed)
		)
		(placement
			(enabled no)
			(sheetname "")
		)
		(fill
			(thermal_gap 0.5)
			(thermal_bridge_width 0.5)
			(island_removal_mode 0)
		)
		(polygon
			(pts
				(arc
					(start 5.59054 -345.135708)
					(mid 5.080127 -344.624914)
					(end 4.56946 -345.135454)
				)
				(xy 4.56946 -345.289378) (xy 4.784598 -345.289378)
				(arc
					(start 4.834382 -345.239594)
					(mid 5.268644 -344.94681)
					(end 4.97586 -345.381072)
				)
				(xy 4.867402 -345.48953) (xy 4.56946 -345.48953) (xy 4.56946 -345.594432) (xy 4.867656 -345.594432)
				(arc
					(start 4.97586 -345.702636)
					(mid 5.268644 -346.136898)
					(end 4.834382 -345.844114)
				)
				(xy 4.784852 -345.794584) (xy 4.56946 -345.794584)
				(arc
					(start 4.56946 -345.948254)
					(mid 5.08 -346.458794)
					(end 5.59054 -345.948254)
				)
			)
		)
	)
	(zone
		(layer "B.Cu")
		(hatch none 0.5)
		(connect_pads
			(clearance 0)
		)
		(min_thickness 0.25)
		(keepout
			(tracks not_allowed)
			(vias allowed)
			(pads allowed)
			(copperpour not_allowed)
			(footprints allowed)
		)
		(placement
			(enabled no)
			(sheetname "")
		)
		(fill
			(thermal_gap 0.5)
			(thermal_bridge_width 0.5)
			(island_removal_mode 0)
		)
		(polygon
			(pts
				(arc
					(start 5.59054 -231.935782)
					(mid 5.080127 -231.424988)
					(end 4.56946 -231.935528)
				)
				(xy 4.56946 -232.089452) (xy 4.784598 -232.089452)
				(arc
					(start 4.834382 -232.039668)
					(mid 5.268644 -231.746884)
					(end 4.97586 -232.181146)
				)
				(xy 4.867402 -232.289604) (xy 4.56946 -232.289604) (xy 4.56946 -232.394506) (xy 4.867656 -232.394506)
				(arc
					(start 4.97586 -232.50271)
					(mid 5.268644 -232.936972)
					(end 4.834382 -232.644188)
				)
				(xy 4.784852 -232.594658) (xy 4.56946 -232.594658)
				(arc
					(start 4.56946 -232.748328)
					(mid 5.08 -233.258868)
					(end 5.59054 -232.748328)
				)
			)
		)
	)
	(zone
		(layer "B.Cu")
		(hatch none 0.5)
		(connect_pads
			(clearance 0)
		)
		(min_thickness 0.25)
		(keepout
			(tracks allowed)
			(vias allowed)
			(pads allowed)
			(copperpour allowed)
			(footprints allowed)
		)
		(placement
			(enabled no)
			(sheetname "")
		)
		(fill
			(thermal_gap 0.5)
			(thermal_bridge_width 0.5)
			(island_removal_mode 0)
		)
		(polygon
			(pts
				(xy 1.524 -151.638) (xy 1.524 -186.69) (xy 7.239 -186.69) (xy 7.239 -151.638)
			)
		)
	)
	(zone
		(net "GND")
		(layer "B.Cu")
		(hatch none 0.5)
		(connect_pads
			(clearance 0.5)
		)
		(min_thickness 0.25)
		(fill yes
			(thermal_gap 0.5)
			(thermal_bridge_width 0.5)
			(island_removal_mode 0)
		)
		(polygon
			(pts
				(xy 18.194274 -369.089178) (xy 19.941286 -367.342166) (xy 19.941286 -366.123728) (xy 13.843 -360.025442)
				(xy 13.843 -340.741) (xy 17.018 -337.566) (xy 17.018 -335.534) (xy 16.637 -335.153) (xy 8.509 -335.153)
				(xy 7.747 -335.915) (xy 6.35 -335.915) (xy 5.715 -336.55) (xy 5.715 -358.013) (xy 16.791178 -369.089178)
			)
		)
	)
	(zone
		(layer "B.Cu")
		(hatch none 0.5)
		(connect_pads
			(clearance 0)
		)
		(min_thickness 0.25)
		(keepout
			(tracks not_allowed)
			(vias allowed)
			(pads allowed)
			(copperpour not_allowed)
			(footprints allowed)
		)
		(placement
			(enabled no)
			(sheetname "")
		)
		(fill
			(thermal_gap 0.5)
			(thermal_bridge_width 0.5)
			(island_removal_mode 0)
		)
		(polygon
			(pts
				(arc
					(start 5.59054 -338.73567)
					(mid 5.080127 -338.224876)
					(end 4.56946 -338.735416)
				)
				(xy 4.56946 -338.88934) (xy 4.784598 -338.88934)
				(arc
					(start 4.834382 -338.839556)
					(mid 5.268644 -338.546772)
					(end 4.97586 -338.981034)
				)
				(xy 4.867402 -339.089492) (xy 4.56946 -339.089492) (xy 4.56946 -339.194394) (xy 4.867656 -339.194394)
				(arc
					(start 4.97586 -339.302598)
					(mid 5.268644 -339.73686)
					(end 4.834382 -339.444076)
				)
				(xy 4.784852 -339.394546) (xy 4.56946 -339.394546)
				(arc
					(start 4.56946 -339.548216)
					(mid 5.08 -340.058756)
					(end 5.59054 -339.548216)
				)
			)
		)
	)
	(zone
		(net "GND")
		(layer "B.Cu")
		(hatch none 0.5)
		(connect_pads
			(clearance 0.5)
		)
		(min_thickness 0.25)
		(fill yes
			(thermal_gap 0.5)
			(thermal_bridge_width 0.5)
			(island_removal_mode 0)
		)
		(polygon
			(pts
				(xy 35.9918 -493.268) (xy 65.913 -493.268) (xy 66.675 -492.506) (xy 66.675 -489.331) (xy 49.403 -472.059)
				(xy 49.022 -472.059) (xy 48.895 -472.186) (xy 48.895 -473.837) (xy 46.228 -476.504) (xy 27.782012 -476.504)
				(xy 23.79726 -480.488752) (xy 23.79726 -481.50526) (xy 32.8549 -490.5629) (xy 33.2867 -490.5629)
			)
		)
	)
	(zone
		(layer "B.Cu")
		(hatch none 0.5)
		(connect_pads
			(clearance 0)
		)
		(min_thickness 0.25)
		(keepout
			(tracks not_allowed)
			(vias allowed)
			(pads allowed)
			(copperpour not_allowed)
			(footprints allowed)
		)
		(placement
			(enabled no)
			(sheetname "")
		)
		(fill
			(thermal_gap 0.5)
			(thermal_bridge_width 0.5)
			(island_removal_mode 0)
		)
		(polygon
			(pts
				(arc
					(start 5.59054 -212.735668)
					(mid 5.080127 -212.224874)
					(end 4.56946 -212.735414)
				)
				(xy 4.56946 -212.889338) (xy 4.784598 -212.889338)
				(arc
					(start 4.834382 -212.839554)
					(mid 5.268644 -212.54677)
					(end 4.97586 -212.981032)
				)
				(xy 4.867402 -213.08949) (xy 4.56946 -213.08949) (xy 4.56946 -213.194392) (xy 4.867656 -213.194392)
				(arc
					(start 4.97586 -213.302596)
					(mid 5.268644 -213.736858)
					(end 4.834382 -213.444074)
				)
				(xy 4.784852 -213.394544) (xy 4.56946 -213.394544)
				(arc
					(start 4.56946 -213.548214)
					(mid 5.08 -214.058754)
					(end 5.59054 -213.548214)
				)
			)
		)
	)
	(zone
		(net "P3V3")
		(layer "B.Cu")
		(hatch none 0.5)
		(connect_pads
			(clearance 0.5)
		)
		(min_thickness 0.25)
		(fill yes
			(thermal_gap 0.5)
			(thermal_bridge_width 0.5)
			(island_removal_mode 0)
		)
		(polygon
			(pts
				(xy 78.613 -445.262) (xy 77.47 -444.119) (xy 72.517 -444.119) (xy 70.231 -446.405) (xy 48.641 -446.405)
				(xy 46.482 -448.564) (xy 46.482 -451.739) (xy 48.641 -453.898) (xy 73.406 -453.898) (xy 78.613 -448.691)
			)
		)
	)
	(zone
		(layer "B.Cu")
		(hatch none 0.5)
		(connect_pads
			(clearance 0)
		)
		(min_thickness 0.25)
		(keepout
			(tracks not_allowed)
			(vias allowed)
			(pads allowed)
			(copperpour not_allowed)
			(footprints allowed)
		)
		(placement
			(enabled no)
			(sheetname "")
		)
		(fill
			(thermal_gap 0.5)
			(thermal_bridge_width 0.5)
			(island_removal_mode 0)
		)
		(polygon
			(pts
				(arc
					(start 5.59054 -395.135354)
					(mid 5.080127 -394.62456)
					(end 4.56946 -395.1351)
				)
				(xy 4.56946 -395.289278) (xy 4.784344 -395.289278)
				(arc
					(start 4.834382 -395.23924)
					(mid 5.268644 -394.946456)
					(end 4.97586 -395.380718)
				)
				(xy 4.867148 -395.48943) (xy 4.56946 -395.48943) (xy 4.56946 -395.594332) (xy 4.86791 -395.594332)
				(arc
					(start 4.97586 -395.702282)
					(mid 5.268644 -396.136544)
					(end 4.834382 -395.84376)
				)
				(xy 4.785106 -395.794484) (xy 4.56946 -395.794484)
				(arc
					(start 4.56946 -395.9479)
					(mid 5.08 -396.45844)
					(end 5.59054 -395.9479)
				)
			)
		)
	)
	(zone
		(layer "B.Cu")
		(hatch none 0.5)
		(connect_pads
			(clearance 0)
		)
		(min_thickness 0.25)
		(keepout
			(tracks not_allowed)
			(vias allowed)
			(pads allowed)
			(copperpour not_allowed)
			(footprints allowed)
		)
		(placement
			(enabled no)
			(sheetname "")
		)
		(fill
			(thermal_gap 0.5)
			(thermal_bridge_width 0.5)
			(island_removal_mode 0)
		)
		(polygon
			(pts
				(arc
					(start 5.59054 -154.335734)
					(mid 5.080127 -153.82494)
					(end 4.56946 -154.33548)
				)
				(xy 4.56946 -154.489404) (xy 4.784598 -154.489404)
				(arc
					(start 4.834382 -154.43962)
					(mid 5.268644 -154.146836)
					(end 4.97586 -154.581098)
				)
				(xy 4.867402 -154.689556) (xy 4.56946 -154.689556) (xy 4.56946 -154.794458) (xy 4.867656 -154.794458)
				(arc
					(start 4.97586 -154.902662)
					(mid 5.268644 -155.336924)
					(end 4.834382 -155.04414)
				)
				(xy 4.784852 -154.99461) (xy 4.56946 -154.99461)
				(arc
					(start 4.56946 -155.14828)
					(mid 5.08 -155.65882)
					(end 5.59054 -155.14828)
				)
			)
		)
	)
	(zone
		(layer "B.Cu")
		(hatch none 0.5)
		(connect_pads
			(clearance 0)
		)
		(min_thickness 0.25)
		(keepout
			(tracks not_allowed)
			(vias allowed)
			(pads allowed)
			(copperpour not_allowed)
			(footprints allowed)
		)
		(placement
			(enabled no)
			(sheetname "")
		)
		(fill
			(thermal_gap 0.5)
			(thermal_bridge_width 0.5)
			(island_removal_mode 0)
		)
		(polygon
			(pts
				(arc
					(start 5.59054 -215.93556)
					(mid 5.080127 -215.424766)
					(end 4.56946 -215.935306)
				)
				(xy 4.56946 -216.089484) (xy 4.784344 -216.089484)
				(arc
					(start 4.834382 -216.039446)
					(mid 5.268644 -215.746662)
					(end 4.97586 -216.180924)
				)
				(xy 4.867148 -216.289636) (xy 4.56946 -216.289636) (xy 4.56946 -216.394538) (xy 4.86791 -216.394538)
				(arc
					(start 4.97586 -216.502488)
					(mid 5.268644 -216.93675)
					(end 4.834382 -216.643966)
				)
				(xy 4.785106 -216.59469) (xy 4.56946 -216.59469)
				(arc
					(start 4.56946 -216.748106)
					(mid 5.08 -217.258646)
					(end 5.59054 -216.748106)
				)
			)
		)
	)
	(zone
		(layer "B.Cu")
		(hatch none 0.5)
		(connect_pads
			(clearance 0)
		)
		(min_thickness 0.25)
		(keepout
			(tracks not_allowed)
			(vias allowed)
			(pads allowed)
			(copperpour not_allowed)
			(footprints allowed)
		)
		(placement
			(enabled no)
			(sheetname "")
		)
		(fill
			(thermal_gap 0.5)
			(thermal_bridge_width 0.5)
			(island_removal_mode 0)
		)
		(polygon
			(pts
				(arc
					(start 9.500108 -484.89997)
					(mid 5.500116 -480.899978)
					(end 1.500124 -484.89997)
				)
				(arc
					(start 1.500124 -488.40009)
					(mid 5.500116 -492.400082)
					(end 9.500108 -488.40009)
				)
			)
		)
	)
	(zone
		(layer "B.Cu")
		(hatch none 0.5)
		(connect_pads
			(clearance 0)
		)
		(min_thickness 0.25)
		(keepout
			(tracks not_allowed)
			(vias allowed)
			(pads allowed)
			(copperpour not_allowed)
			(footprints allowed)
		)
		(placement
			(enabled no)
			(sheetname "")
		)
		(fill
			(thermal_gap 0.5)
			(thermal_bridge_width 0.5)
			(island_removal_mode 0)
		)
		(polygon
			(pts
				(arc
					(start 5.59054 -426.335444)
					(mid 5.080127 -425.82465)
					(end 4.56946 -426.33519)
				)
				(xy 4.56946 -426.489368) (xy 4.784344 -426.489368)
				(arc
					(start 4.834382 -426.43933)
					(mid 5.268644 -426.146546)
					(end 4.97586 -426.580808)
				)
				(xy 4.867148 -426.68952) (xy 4.56946 -426.68952) (xy 4.56946 -426.794422) (xy 4.86791 -426.794422)
				(arc
					(start 4.97586 -426.902372)
					(mid 5.268644 -427.336634)
					(end 4.834382 -427.04385)
				)
				(xy 4.785106 -426.994574) (xy 4.56946 -426.994574)
				(arc
					(start 4.56946 -427.14799)
					(mid 5.08 -427.65853)
					(end 5.59054 -427.14799)
				)
			)
		)
	)
	(zone
		(layer "B.Cu")
		(hatch none 0.5)
		(connect_pads
			(clearance 0)
		)
		(min_thickness 0.25)
		(keepout
			(tracks allowed)
			(vias allowed)
			(pads allowed)
			(copperpour allowed)
			(footprints allowed)
		)
		(placement
			(enabled no)
			(sheetname "")
		)
		(fill
			(thermal_gap 0.5)
			(thermal_bridge_width 0.5)
			(island_removal_mode 0)
		)
		(polygon
			(pts
				(xy 1.0668 -422.021) (xy 1.0668 -457.073) (xy 7.239 -457.073) (xy 7.239 -422.021)
			)
		)
	)
	(zone
		(net "P12V")
		(layer "B.Cu")
		(hatch none 0.5)
		(connect_pads
			(clearance 0.5)
		)
		(min_thickness 0.25)
		(fill yes
			(thermal_gap 0.5)
			(thermal_bridge_width 0.5)
			(island_removal_mode 0)
		)
		(polygon
			(pts
				(xy 8.1534 -477.73971) (xy 8.1534 -462.97977) (xy 8.03783 -462.8642) (xy 5.135118 -462.8642) (xy 4.373118 -462.1022)
				(xy 1.0668 -462.1022) (xy 1.016 -462.153) (xy 1.016 -475.488) (xy 3.286252 -477.758252) (xy 8.134858 -477.758252)
			)
		)
	)
	(zone
		(net "GND")
		(layer "B.Cu")
		(hatch none 0.5)
		(connect_pads
			(clearance 0.5)
		)
		(min_thickness 0.25)
		(fill yes
			(thermal_gap 0.5)
			(thermal_bridge_width 0.5)
			(island_removal_mode 0)
		)
		(polygon
			(pts
				(xy 83.312 -367.157) (xy 82.677 -367.792) (xy 82.677 -380.8222) (xy 86.106 -384.2512) (xy 86.106 -432.435)
				(xy 83.9216 -434.6194) (xy 78.2574 -434.6194) (xy 78.0669 -434.8099) (xy 77.7621 -434.8099) (xy 76.708 -435.864)
				(xy 76.708 -438.023) (xy 78.0796 -439.3946) (xy 90.5002 -439.3946) (xy 92.2274 -441.1218) (xy 99.187 -441.1218)
				(xy 101.2952 -439.0136) (xy 107.9754 -439.0136) (xy 109.474 -437.515) (xy 109.474 -426.466) (xy 108.585 -425.577)
				(xy 108.585 -422.402) (xy 112.268 -418.719) (xy 112.268 -391.795) (xy 87.63 -367.157)
			)
		)
	)
	(zone
		(layer "B.Cu")
		(hatch none 0.5)
		(connect_pads
			(clearance 0)
		)
		(min_thickness 0.25)
		(keepout
			(tracks not_allowed)
			(vias allowed)
			(pads allowed)
			(copperpour not_allowed)
			(footprints allowed)
		)
		(placement
			(enabled no)
			(sheetname "")
		)
		(fill
			(thermal_gap 0.5)
			(thermal_bridge_width 0.5)
			(island_removal_mode 0)
		)
		(polygon
			(pts
				(arc
					(start 5.59054 -199.935592)
					(mid 5.080127 -199.424798)
					(end 4.56946 -199.935338)
				)
				(xy 4.56946 -200.089516) (xy 4.784344 -200.089516)
				(arc
					(start 4.834382 -200.039478)
					(mid 5.268644 -199.746694)
					(end 4.97586 -200.180956)
				)
				(xy 4.867148 -200.289668) (xy 4.56946 -200.289668) (xy 4.56946 -200.39457) (xy 4.86791 -200.39457)
				(arc
					(start 4.97586 -200.50252)
					(mid 5.268644 -200.936782)
					(end 4.834382 -200.643998)
				)
				(xy 4.785106 -200.594722) (xy 4.56946 -200.594722)
				(arc
					(start 4.56946 -200.748138)
					(mid 5.08 -201.258678)
					(end 5.59054 -200.748138)
				)
			)
		)
	)
	(zone
		(layer "B.Cu")
		(hatch none 0.5)
		(connect_pads
			(clearance 0)
		)
		(min_thickness 0.25)
		(keepout
			(tracks not_allowed)
			(vias allowed)
			(pads allowed)
			(copperpour not_allowed)
			(footprints allowed)
		)
		(placement
			(enabled no)
			(sheetname "")
		)
		(fill
			(thermal_gap 0.5)
			(thermal_bridge_width 0.5)
			(island_removal_mode 0)
		)
		(polygon
			(pts
				(arc
					(start 74.269854 -429.61306)
					(mid 73.75906 -430.123473)
					(end 74.2696 -430.63414)
				)
				(xy 74.42327 -430.63414) (xy 74.42327 -430.418748)
				(arc
					(start 74.37374 -430.369218)
					(mid 74.080956 -429.934956)
					(end 74.515218 -430.22774)
				)
				(xy 74.623422 -430.335944) (xy 74.623422 -430.63414) (xy 74.728324 -430.63414) (xy 74.728324 -430.336198)
				(arc
					(start 74.836782 -430.22774)
					(mid 75.271044 -429.934956)
					(end 74.97826 -430.369218)
				)
				(xy 74.928476 -430.419002) (xy 74.928476 -430.63414)
				(arc
					(start 75.0824 -430.63414)
					(mid 75.59294 -430.1236)
					(end 75.0824 -429.61306)
				)
			)
		)
	)
	(zone
		(layer "B.Cu")
		(hatch none 0.5)
		(connect_pads
			(clearance 0)
		)
		(min_thickness 0.25)
		(keepout
			(tracks not_allowed)
			(vias allowed)
			(pads allowed)
			(copperpour not_allowed)
			(footprints allowed)
		)
		(placement
			(enabled no)
			(sheetname "")
		)
		(fill
			(thermal_gap 0.5)
			(thermal_bridge_width 0.5)
			(island_removal_mode 0)
		)
		(polygon
			(pts
				(arc
					(start 17.78254 -444.603378)
					(mid 17.272 -444.092838)
					(end 16.76146 -444.603378)
				)
				(arc
					(start 16.76146 -445.415924)
					(mid 17.271873 -445.926718)
					(end 17.78254 -445.416178)
				)
				(xy 17.78254 -445.243712) (xy 17.585944 -445.243712)
				(arc
					(start 17.517618 -445.312038)
					(mid 17.083356 -445.604822)
					(end 17.37614 -445.17056)
				)
				(xy 17.50314 -445.04356) (xy 17.78254 -445.04356) (xy 17.78254 -444.938658) (xy 17.465802 -444.938658)
				(arc
					(start 17.37614 -444.848996)
					(mid 17.083356 -444.414734)
					(end 17.517618 -444.707518)
				)
				(xy 17.548606 -444.738506) (xy 17.78254 -444.738506)
			)
		)
	)
	(zone
		(layer "B.Cu")
		(hatch none 0.5)
		(connect_pads
			(clearance 0)
		)
		(min_thickness 0.25)
		(keepout
			(tracks not_allowed)
			(vias allowed)
			(pads allowed)
			(copperpour not_allowed)
			(footprints allowed)
		)
		(placement
			(enabled no)
			(sheetname "")
		)
		(fill
			(thermal_gap 0.5)
			(thermal_bridge_width 0.5)
			(island_removal_mode 0)
		)
		(polygon
			(pts
				(arc
					(start 6.477254 -448.957192)
					(mid 5.96646 -449.467605)
					(end 6.477 -449.978272)
				)
				(arc
					(start 7.2898 -449.978272)
					(mid 7.80034 -449.467732)
					(end 7.2898 -448.957192)
				)
				(xy 7.13613 -448.957192) (xy 7.13613 -449.172584)
				(arc
					(start 7.18566 -449.222114)
					(mid 7.478444 -449.656376)
					(end 7.044182 -449.363592)
				)
				(xy 6.935978 -449.255388) (xy 6.935978 -448.957192) (xy 6.831076 -448.957192) (xy 6.831076 -449.255134)
				(arc
					(start 6.722618 -449.363592)
					(mid 6.288356 -449.656376)
					(end 6.58114 -449.222114)
				)
				(xy 6.630924 -449.17233) (xy 6.630924 -448.957192)
			)
		)
	)
	(zone
		(layer "B.Cu")
		(hatch none 0.5)
		(connect_pads
			(clearance 0)
		)
		(min_thickness 0.25)
		(keepout
			(tracks not_allowed)
			(vias allowed)
			(pads allowed)
			(copperpour not_allowed)
			(footprints allowed)
		)
		(placement
			(enabled no)
			(sheetname "")
		)
		(fill
			(thermal_gap 0.5)
			(thermal_bridge_width 0.5)
			(island_removal_mode 0)
		)
		(polygon
			(pts
				(arc
					(start 48.89754 -163.579556)
					(mid 48.387127 -163.068762)
					(end 47.87646 -163.579302)
				)
				(xy 47.87646 -163.732972) (xy 48.091852 -163.732972)
				(arc
					(start 48.141382 -163.683442)
					(mid 48.575644 -163.390658)
					(end 48.28286 -163.82492)
				)
				(xy 48.174656 -163.933124) (xy 47.87646 -163.933124) (xy 47.87646 -164.038026) (xy 48.174402 -164.038026)
				(arc
					(start 48.28286 -164.146484)
					(mid 48.575644 -164.580746)
					(end 48.141382 -164.287962)
				)
				(xy 48.091598 -164.238178) (xy 47.87646 -164.238178)
				(arc
					(start 47.87646 -164.392102)
					(mid 48.387 -164.902642)
					(end 48.89754 -164.392102)
				)
			)
		)
	)
	(zone
		(layer "B.Cu")
		(hatch none 0.5)
		(connect_pads
			(clearance 0)
		)
		(min_thickness 0.25)
		(keepout
			(tracks not_allowed)
			(vias allowed)
			(pads allowed)
			(copperpour not_allowed)
			(footprints allowed)
		)
		(placement
			(enabled no)
			(sheetname "")
		)
		(fill
			(thermal_gap 0.5)
			(thermal_bridge_width 0.5)
			(island_removal_mode 0)
		)
		(polygon
			(pts
				(arc
					(start 5.59054 -280.335736)
					(mid 5.080127 -279.824942)
					(end 4.56946 -280.335482)
				)
				(xy 4.56946 -280.489406) (xy 4.784598 -280.489406)
				(arc
					(start 4.834382 -280.439622)
					(mid 5.268644 -280.146838)
					(end 4.97586 -280.5811)
				)
				(xy 4.867402 -280.689558) (xy 4.56946 -280.689558) (xy 4.56946 -280.79446) (xy 4.867656 -280.79446)
				(arc
					(start 4.97586 -280.902664)
					(mid 5.268644 -281.336926)
					(end 4.834382 -281.044142)
				)
				(xy 4.784852 -280.994612) (xy 4.56946 -280.994612)
				(arc
					(start 4.56946 -281.148282)
					(mid 5.08 -281.658822)
					(end 5.59054 -281.148282)
				)
			)
		)
	)
	(zone
		(layer "B.Cu")
		(hatch none 0.5)
		(connect_pads
			(clearance 0)
		)
		(min_thickness 0.25)
		(keepout
			(tracks not_allowed)
			(vias allowed)
			(pads allowed)
			(copperpour not_allowed)
			(footprints allowed)
		)
		(placement
			(enabled no)
			(sheetname "")
		)
		(fill
			(thermal_gap 0.5)
			(thermal_bridge_width 0.5)
			(island_removal_mode 0)
		)
		(polygon
			(pts
				(arc
					(start 257.50012 -170.997626)
					(mid 253.500128 -166.997634)
					(end 249.499882 -170.997626)
				)
				(arc
					(start 249.499882 -174.497492)
					(mid 253.500128 -178.497738)
					(end 257.50012 -174.497492)
				)
			)
		)
	)
	(zone
		(layer "B.Cu")
		(hatch none 0.5)
		(connect_pads
			(clearance 0)
		)
		(min_thickness 0.25)
		(keepout
			(tracks not_allowed)
			(vias allowed)
			(pads allowed)
			(copperpour not_allowed)
			(footprints allowed)
		)
		(placement
			(enabled no)
			(sheetname "")
		)
		(fill
			(thermal_gap 0.5)
			(thermal_bridge_width 0.5)
			(island_removal_mode 0)
		)
		(polygon
			(pts
				(arc
					(start 5.59054 -170.335702)
					(mid 5.080127 -169.824908)
					(end 4.56946 -170.335448)
				)
				(xy 4.56946 -170.489372) (xy 4.784598 -170.489372)
				(arc
					(start 4.834382 -170.439588)
					(mid 5.268644 -170.146804)
					(end 4.97586 -170.581066)
				)
				(xy 4.867402 -170.689524) (xy 4.56946 -170.689524) (xy 4.56946 -170.794426) (xy 4.867656 -170.794426)
				(arc
					(start 4.97586 -170.90263)
					(mid 5.268644 -171.336892)
					(end 4.834382 -171.044108)
				)
				(xy 4.784852 -170.994578) (xy 4.56946 -170.994578)
				(arc
					(start 4.56946 -171.148248)
					(mid 5.08 -171.658788)
					(end 5.59054 -171.148248)
				)
			)
		)
	)
	(zone
		(layer "B.Cu")
		(hatch none 0.5)
		(connect_pads
			(clearance 0)
		)
		(min_thickness 0.25)
		(keepout
			(tracks not_allowed)
			(vias allowed)
			(pads allowed)
			(copperpour not_allowed)
			(footprints allowed)
		)
		(placement
			(enabled no)
			(sheetname "")
		)
		(fill
			(thermal_gap 0.5)
			(thermal_bridge_width 0.5)
			(island_removal_mode 0)
		)
		(polygon
			(pts
				(arc
					(start 5.59054 -357.935784)
					(mid 5.080127 -357.42499)
					(end 4.56946 -357.93553)
				)
				(xy 4.56946 -358.089454) (xy 4.784598 -358.089454)
				(arc
					(start 4.834382 -358.03967)
					(mid 5.268644 -357.746886)
					(end 4.97586 -358.181148)
				)
				(xy 4.867402 -358.289606) (xy 4.56946 -358.289606) (xy 4.56946 -358.394508) (xy 4.867656 -358.394508)
				(arc
					(start 4.97586 -358.502712)
					(mid 5.268644 -358.936974)
					(end 4.834382 -358.64419)
				)
				(xy 4.784852 -358.59466) (xy 4.56946 -358.59466)
				(arc
					(start 4.56946 -358.74833)
					(mid 5.08 -359.25887)
					(end 5.59054 -358.74833)
				)
			)
		)
	)
	(zone
		(layer "B.Cu")
		(hatch none 0.5)
		(connect_pads
			(clearance 0)
		)
		(min_thickness 0.25)
		(keepout
			(tracks not_allowed)
			(vias allowed)
			(pads allowed)
			(copperpour not_allowed)
			(footprints allowed)
		)
		(placement
			(enabled no)
			(sheetname "")
		)
		(fill
			(thermal_gap 0.5)
			(thermal_bridge_width 0.5)
			(island_removal_mode 0)
		)
		(polygon
			(pts
				(arc
					(start 5.59054 -435.135274)
					(mid 5.08 -434.624734)
					(end 4.56946 -435.135274)
				)
				(xy 4.56946 -435.289452) (xy 4.784344 -435.289452)
				(arc
					(start 4.834382 -435.239414)
					(mid 5.268644 -434.94663)
					(end 4.97586 -435.380892)
				)
				(xy 4.867148 -435.489604) (xy 4.56946 -435.489604) (xy 4.56946 -435.594506) (xy 4.86791 -435.594506)
				(arc
					(start 4.97586 -435.702456)
					(mid 5.268644 -436.136718)
					(end 4.834382 -435.843934)
				)
				(xy 4.785106 -435.794658) (xy 4.56946 -435.794658)
				(arc
					(start 4.56946 -435.94782)
					(mid 5.079873 -436.458614)
					(end 5.59054 -435.948074)
				)
			)
		)
	)
	(zone
		(layer "B.Cu")
		(hatch none 0.5)
		(connect_pads
			(clearance 0)
		)
		(min_thickness 0.25)
		(keepout
			(tracks not_allowed)
			(vias allowed)
			(pads allowed)
			(copperpour not_allowed)
			(footprints allowed)
		)
		(placement
			(enabled no)
			(sheetname "")
		)
		(fill
			(thermal_gap 0.5)
			(thermal_bridge_width 0.5)
			(island_removal_mode 0)
		)
		(polygon
			(pts
				(arc
					(start 5.59054 -160.735772)
					(mid 5.080127 -160.224978)
					(end 4.56946 -160.735518)
				)
				(xy 4.56946 -160.889442) (xy 4.784598 -160.889442)
				(arc
					(start 4.834382 -160.839658)
					(mid 5.268644 -160.546874)
					(end 4.97586 -160.981136)
				)
				(xy 4.867402 -161.089594) (xy 4.56946 -161.089594) (xy 4.56946 -161.194496) (xy 4.867656 -161.194496)
				(arc
					(start 4.97586 -161.3027)
					(mid 5.268644 -161.736962)
					(end 4.834382 -161.444178)
				)
				(xy 4.784852 -161.394648) (xy 4.56946 -161.394648)
				(arc
					(start 4.56946 -161.548318)
					(mid 5.08 -162.058858)
					(end 5.59054 -161.548318)
				)
			)
		)
	)
	(zone
		(net "GND")
		(layer "B.Cu")
		(hatch none 0.5)
		(connect_pads
			(clearance 0.5)
		)
		(min_thickness 0.25)
		(fill yes
			(thermal_gap 0.5)
			(thermal_bridge_width 0.5)
			(island_removal_mode 0)
		)
		(polygon
			(pts
				(xy 1.016 -461.645) (xy 1.143 -461.772) (xy 6.604 -461.772) (xy 7.493 -460.883) (xy 10.16 -460.883)
				(xy 10.6426 -460.4004) (xy 10.6426 -458.343) (xy 10.2616 -457.962) (xy 6.477 -457.962) (xy 5.842 -457.327)
				(xy 1.143 -457.327) (xy 1.016 -457.454)
			)
		)
	)
	(zone
		(layer "B.Cu")
		(hatch none 0.5)
		(connect_pads
			(clearance 0)
		)
		(min_thickness 0.25)
		(keepout
			(tracks not_allowed)
			(vias allowed)
			(pads allowed)
			(copperpour not_allowed)
			(footprints allowed)
		)
		(placement
			(enabled no)
			(sheetname "")
		)
		(fill
			(thermal_gap 0.5)
			(thermal_bridge_width 0.5)
			(island_removal_mode 0)
		)
		(polygon
			(pts
				(arc
					(start 5.59054 -179.935632)
					(mid 5.080127 -179.424838)
					(end 4.56946 -179.935378)
				)
				(xy 4.56946 -180.089302) (xy 4.784598 -180.089302)
				(arc
					(start 4.834382 -180.039518)
					(mid 5.268644 -179.746734)
					(end 4.97586 -180.180996)
				)
				(xy 4.867402 -180.289454) (xy 4.56946 -180.289454) (xy 4.56946 -180.394356) (xy 4.867656 -180.394356)
				(arc
					(start 4.97586 -180.50256)
					(mid 5.268644 -180.936822)
					(end 4.834382 -180.644038)
				)
				(xy 4.784852 -180.594508) (xy 4.56946 -180.594508)
				(arc
					(start 4.56946 -180.748178)
					(mid 5.08 -181.258718)
					(end 5.59054 -180.748178)
				)
			)
		)
	)
	(zone
		(layer "B.Cu")
		(hatch none 0.5)
		(connect_pads
			(clearance 0)
		)
		(min_thickness 0.25)
		(keepout
			(tracks not_allowed)
			(vias allowed)
			(pads allowed)
			(copperpour not_allowed)
			(footprints allowed)
		)
		(placement
			(enabled no)
			(sheetname "")
		)
		(fill
			(thermal_gap 0.5)
			(thermal_bridge_width 0.5)
			(island_removal_mode 0)
		)
		(polygon
			(pts
				(arc
					(start 257.50012 -37.997638)
					(mid 253.500128 -33.997646)
					(end 249.499882 -37.997638)
				)
				(arc
					(start 249.499882 -41.497504)
					(mid 253.500128 -45.49775)
					(end 257.50012 -41.497504)
				)
			)
		)
	)
	(zone
		(layer "B.Cu")
		(hatch none 0.5)
		(connect_pads
			(clearance 0)
		)
		(min_thickness 0.25)
		(keepout
			(tracks allowed)
			(vias allowed)
			(pads allowed)
			(copperpour allowed)
			(footprints not_allowed)
		)
		(placement
			(enabled no)
			(sheetname "")
		)
		(fill
			(thermal_gap 0.5)
			(thermal_bridge_width 0.5)
			(island_removal_mode 0)
		)
		(polygon
			(pts
				(arc
					(start 263.500108 -0.999998)
					(mid 263.207215 -0.292893)
					(end 262.50011 0)
				)
				(arc
					(start 0.999998 0)
					(mid 0.292893 -0.292893)
					(end 0 -0.999998)
				)
				(xy 0 -186.641994) (xy 0.500126 -187.14212)
				(arc
					(start 4.299966 -187.14212)
					(mid 5.499862 -188.342016)
					(end 4.299966 -189.541912)
				)
				(xy 0.500126 -189.541912) (xy 0 -190.042038) (xy 0 -312.641996) (xy 0.500126 -313.142122)
				(arc
					(start 4.299966 -313.142122)
					(mid 5.499862 -314.342018)
					(end 4.299966 -315.541914)
				)
				(xy 0.500126 -315.541914) (xy 0 -316.04204) (xy 0 -418.642038) (xy 0.500126 -419.14191)
				(arc
					(start 4.299966 -419.14191)
					(mid 5.500116 -420.34206)
					(end 4.299966 -421.541956)
				)
				(xy 0.500126 -421.541956) (xy 0 -422.042082)
				(arc
					(start 0 -505.000006)
					(mid 0.292893 -505.707111)
					(end 0.999998 -506.000004)
				)
				(arc
					(start 262.50011 -506.000004)
					(mid 263.207215 -505.707111)
					(end 263.500108 -505.000006)
				)
				(xy 263.500108 -428.079916) (xy 262.50011 -427.079918)
				(arc
					(start 261.290054 -427.079918)
					(mid 260.307091 -426.672919)
					(end 259.899912 -425.69003)
				)
				(xy 259.899912 -411.48508) (xy 258.899914 -410.485082)
				(arc
					(start 252.394974 -410.485082)
					(mid 251.86005 -409.950158)
					(end 252.394974 -409.41498)
				)
				(xy 258.899914 -409.41498) (xy 259.899912 -408.414982)
				(arc
					(start 259.899912 -364.309914)
					(mid 260.307165 -363.327099)
					(end 261.290054 -362.920026)
				)
				(xy 262.50011 -362.920026) (xy 263.500108 -361.920028)
			)
		)
	)
	(zone
		(layer "B.Cu")
		(hatch none 0.5)
		(connect_pads
			(clearance 0)
		)
		(min_thickness 0.25)
		(keepout
			(tracks not_allowed)
			(vias allowed)
			(pads allowed)
			(copperpour not_allowed)
			(footprints allowed)
		)
		(placement
			(enabled no)
			(sheetname "")
		)
		(fill
			(thermal_gap 0.5)
			(thermal_bridge_width 0.5)
			(island_removal_mode 0)
		)
		(polygon
			(pts
				(arc
					(start 5.59054 -429.535336)
					(mid 5.080127 -429.024542)
					(end 4.56946 -429.535082)
				)
				(xy 4.56946 -429.68926) (xy 4.784344 -429.68926)
				(arc
					(start 4.834382 -429.639222)
					(mid 5.268644 -429.346438)
					(end 4.97586 -429.7807)
				)
				(xy 4.867148 -429.889412) (xy 4.56946 -429.889412) (xy 4.56946 -429.994314) (xy 4.86791 -429.994314)
				(arc
					(start 4.97586 -430.102264)
					(mid 5.268644 -430.536526)
					(end 4.834382 -430.243742)
				)
				(xy 4.785106 -430.194466) (xy 4.56946 -430.194466)
				(arc
					(start 4.56946 -430.347882)
					(mid 5.08 -430.858422)
					(end 5.59054 -430.347882)
				)
			)
		)
	)
	(zone
		(layer "B.Cu")
		(hatch none 0.5)
		(connect_pads
			(clearance 0)
		)
		(min_thickness 0.25)
		(keepout
			(tracks not_allowed)
			(vias allowed)
			(pads allowed)
			(copperpour not_allowed)
			(footprints allowed)
		)
		(placement
			(enabled no)
			(sheetname "")
		)
		(fill
			(thermal_gap 0.5)
			(thermal_bridge_width 0.5)
			(island_removal_mode 0)
		)
		(polygon
			(pts
				(arc
					(start 5.59054 -317.135764)
					(mid 5.080127 -316.62497)
					(end 4.56946 -317.13551)
				)
				(xy 4.56946 -317.289434) (xy 4.784598 -317.289434)
				(arc
					(start 4.834382 -317.23965)
					(mid 5.268644 -316.946866)
					(end 4.97586 -317.381128)
				)
				(xy 4.867402 -317.489586) (xy 4.56946 -317.489586) (xy 4.56946 -317.594488) (xy 4.867656 -317.594488)
				(arc
					(start 4.97586 -317.702692)
					(mid 5.268644 -318.136954)
					(end 4.834382 -317.84417)
				)
				(xy 4.784852 -317.79464) (xy 4.56946 -317.79464)
				(arc
					(start 4.56946 -317.94831)
					(mid 5.08 -318.45885)
					(end 5.59054 -317.94831)
				)
			)
		)
	)
	(zone
		(net "GND")
		(layer "B.Cu")
		(hatch none 0.5)
		(connect_pads
			(clearance 0.5)
		)
		(min_thickness 0.25)
		(fill yes
			(thermal_gap 0.5)
			(thermal_bridge_width 0.5)
			(island_removal_mode 0)
		)
		(polygon
			(pts
				(xy 12.827 -229.87) (xy 6.858 -235.839) (xy 3.556 -235.839) (xy 0.762254 -238.632746) (xy 0.762254 -273.812254)
				(xy 2.032 -275.082) (xy 12.3952 -275.082) (xy 17.907 -269.5702) (xy 17.907 -261.493) (xy 12.827 -256.413)
				(xy 12.827 -237.4392) (xy 16.1798 -234.0864) (xy 16.1798 -232.0798) (xy 13.97 -229.87)
			)
		)
	)
	(zone
		(layer "B.Cu")
		(hatch none 0.5)
		(connect_pads
			(clearance 0)
		)
		(min_thickness 0.25)
		(keepout
			(tracks not_allowed)
			(vias allowed)
			(pads allowed)
			(copperpour not_allowed)
			(footprints allowed)
		)
		(placement
			(enabled no)
			(sheetname "")
		)
		(fill
			(thermal_gap 0.5)
			(thermal_bridge_width 0.5)
			(island_removal_mode 0)
		)
		(polygon
			(pts
				(xy 1.022096 -462.595722) (xy 3.758184 -462.595722) (xy 3.81 -462.647538) (xy 3.81 -462.839054)
				(xy 3.761232 -462.887822) (xy 1.025398 -462.887822) (xy 1.014984 -462.898236) (xy 1.010158 -462.898236)
				(xy 1.005332 -462.89341) (xy 1.005332 -462.877154) (xy 1.005332 -462.60639) (xy 1.005332 -462.590896)
				(xy 1.007872 -462.588356) (xy 1.01473 -462.588356)
			)
		)
	)
	(zone
		(layer "B.Cu")
		(hatch none 0.5)
		(connect_pads
			(clearance 0)
		)
		(min_thickness 0.25)
		(keepout
			(tracks not_allowed)
			(vias allowed)
			(pads allowed)
			(copperpour not_allowed)
			(footprints allowed)
		)
		(placement
			(enabled no)
			(sheetname "")
		)
		(fill
			(thermal_gap 0.5)
			(thermal_bridge_width 0.5)
			(island_removal_mode 0)
		)
		(polygon
			(pts
				(arc
					(start 5.59054 -309.13578)
					(mid 5.080127 -308.624986)
					(end 4.56946 -309.135526)
				)
				(xy 4.56946 -309.28945) (xy 4.784598 -309.28945)
				(arc
					(start 4.834382 -309.239666)
					(mid 5.268644 -308.946882)
					(end 4.97586 -309.381144)
				)
				(xy 4.867402 -309.489602) (xy 4.56946 -309.489602) (xy 4.56946 -309.594504) (xy 4.867656 -309.594504)
				(arc
					(start 4.97586 -309.702708)
					(mid 5.268644 -310.13697)
					(end 4.834382 -309.844186)
				)
				(xy 4.784852 -309.794656) (xy 4.56946 -309.794656)
				(arc
					(start 4.56946 -309.948326)
					(mid 5.08 -310.458866)
					(end 5.59054 -309.948326)
				)
			)
		)
	)
	(zone
		(layer "B.Cu")
		(hatch none 0.5)
		(connect_pads
			(clearance 0)
		)
		(min_thickness 0.25)
		(keepout
			(tracks not_allowed)
			(vias allowed)
			(pads allowed)
			(copperpour not_allowed)
			(footprints allowed)
		)
		(placement
			(enabled no)
			(sheetname "")
		)
		(fill
			(thermal_gap 0.5)
			(thermal_bridge_width 0.5)
			(island_removal_mode 0)
		)
		(polygon
			(pts
				(arc
					(start 5.59054 -183.135778)
					(mid 5.080127 -182.624984)
					(end 4.56946 -183.135524)
				)
				(xy 4.56946 -183.289448) (xy 4.784598 -183.289448)
				(arc
					(start 4.834382 -183.239664)
					(mid 5.268644 -182.94688)
					(end 4.97586 -183.381142)
				)
				(xy 4.867402 -183.4896) (xy 4.56946 -183.4896) (xy 4.56946 -183.594502) (xy 4.867656 -183.594502)
				(arc
					(start 4.97586 -183.702706)
					(mid 5.268644 -184.136968)
					(end 4.834382 -183.844184)
				)
				(xy 4.784852 -183.794654) (xy 4.56946 -183.794654)
				(arc
					(start 4.56946 -183.948324)
					(mid 5.08 -184.458864)
					(end 5.59054 -183.948324)
				)
			)
		)
	)
	(zone
		(layer "B.Cu")
		(hatch none 0.5)
		(connect_pads
			(clearance 0)
		)
		(min_thickness 0.25)
		(keepout
			(tracks not_allowed)
			(vias allowed)
			(pads allowed)
			(copperpour not_allowed)
			(footprints allowed)
		)
		(placement
			(enabled no)
			(sheetname "")
		)
		(fill
			(thermal_gap 0.5)
			(thermal_bridge_width 0.5)
			(island_removal_mode 0)
		)
		(polygon
			(pts
				(arc
					(start 5.59054 -302.735742)
					(mid 5.080127 -302.224948)
					(end 4.56946 -302.735488)
				)
				(xy 4.56946 -302.889412) (xy 4.784598 -302.889412)
				(arc
					(start 4.834382 -302.839628)
					(mid 5.268644 -302.546844)
					(end 4.97586 -302.981106)
				)
				(xy 4.867402 -303.089564) (xy 4.56946 -303.089564) (xy 4.56946 -303.194466) (xy 4.867656 -303.194466)
				(arc
					(start 4.97586 -303.30267)
					(mid 5.268644 -303.736932)
					(end 4.834382 -303.444148)
				)
				(xy 4.784852 -303.394618) (xy 4.56946 -303.394618)
				(arc
					(start 4.56946 -303.548288)
					(mid 5.08 -304.058828)
					(end 5.59054 -303.548288)
				)
			)
		)
	)
	(zone
		(layer "B.Cu")
		(hatch none 0.5)
		(connect_pads
			(clearance 0)
		)
		(min_thickness 0.25)
		(keepout
			(tracks not_allowed)
			(vias allowed)
			(pads allowed)
			(copperpour not_allowed)
			(footprints allowed)
		)
		(placement
			(enabled no)
			(sheetname "")
		)
		(fill
			(thermal_gap 0.5)
			(thermal_bridge_width 0.5)
			(island_removal_mode 0)
		)
		(polygon
			(pts
				(xy 1.022096 -459.39583) (xy 3.758184 -459.39583) (xy 3.81 -459.447646) (xy 3.81 -459.639162) (xy 3.761232 -459.68793)
				(xy 1.025398 -459.68793) (xy 1.014984 -459.698344) (xy 1.010158 -459.698344) (xy 1.005332 -459.693518)
				(xy 1.005332 -459.677262) (xy 1.005332 -459.406498) (xy 1.005332 -459.391004) (xy 1.007872 -459.388464)
				(xy 1.01473 -459.388464)
			)
		)
	)
	(zone
		(layer "B.Cu")
		(hatch none 0.5)
		(connect_pads
			(clearance 0)
		)
		(min_thickness 0.25)
		(keepout
			(tracks not_allowed)
			(vias allowed)
			(pads allowed)
			(copperpour not_allowed)
			(footprints allowed)
		)
		(placement
			(enabled no)
			(sheetname "")
		)
		(fill
			(thermal_gap 0.5)
			(thermal_bridge_width 0.5)
			(island_removal_mode 0)
		)
		(polygon
			(pts
				(xy 1.022096 -463.395822) (xy 3.758184 -463.395822) (xy 3.81 -463.447638) (xy 3.81 -463.639154)
				(xy 3.761232 -463.687922) (xy 1.025398 -463.687922) (xy 1.014984 -463.698336) (xy 1.010158 -463.698336)
				(xy 1.005332 -463.69351) (xy 1.005332 -463.677254) (xy 1.005332 -463.40649) (xy 1.005332 -463.390996)
				(xy 1.007872 -463.388456) (xy 1.01473 -463.388456)
			)
		)
	)
	(zone
		(layer "B.Cu")
		(hatch none 0.5)
		(connect_pads
			(clearance 0)
		)
		(min_thickness 0.25)
		(keepout
			(tracks not_allowed)
			(vias allowed)
			(pads allowed)
			(copperpour not_allowed)
			(footprints allowed)
		)
		(placement
			(enabled no)
			(sheetname "")
		)
		(fill
			(thermal_gap 0.5)
			(thermal_bridge_width 0.5)
			(island_removal_mode 0)
		)
		(polygon
			(pts
				(xy 1.022096 -460.195676) (xy 3.758184 -460.195676) (xy 3.81 -460.247492) (xy 3.81 -460.439008)
				(xy 3.761232 -460.487776) (xy 1.025398 -460.487776) (xy 1.014984 -460.49819) (xy 1.010158 -460.49819)
				(xy 1.005332 -460.493364) (xy 1.005332 -460.477108) (xy 1.005332 -460.206344) (xy 1.005332 -460.19085)
				(xy 1.007872 -460.18831) (xy 1.01473 -460.18831)
			)
		)
	)
	(zone
		(layer "B.Cu")
		(hatch none 0.5)
		(connect_pads
			(clearance 0)
		)
		(min_thickness 0.25)
		(keepout
			(tracks not_allowed)
			(vias allowed)
			(pads allowed)
			(copperpour not_allowed)
			(footprints allowed)
		)
		(placement
			(enabled no)
			(sheetname "")
		)
		(fill
			(thermal_gap 0.5)
			(thermal_bridge_width 0.5)
			(island_removal_mode 0)
		)
		(polygon
			(pts
				(arc
					(start 5.59054 -176.73574)
					(mid 5.080127 -176.224946)
					(end 4.56946 -176.735486)
				)
				(xy 4.56946 -176.88941) (xy 4.784598 -176.88941)
				(arc
					(start 4.834382 -176.839626)
					(mid 5.268644 -176.546842)
					(end 4.97586 -176.981104)
				)
				(xy 4.867402 -177.089562) (xy 4.56946 -177.089562) (xy 4.56946 -177.194464) (xy 4.867656 -177.194464)
				(arc
					(start 4.97586 -177.302668)
					(mid 5.268644 -177.73693)
					(end 4.834382 -177.444146)
				)
				(xy 4.784852 -177.394616) (xy 4.56946 -177.394616)
				(arc
					(start 4.56946 -177.548286)
					(mid 5.08 -178.058826)
					(end 5.59054 -177.548286)
				)
			)
		)
	)
	(zone
		(net "GND")
		(layer "B.Cu")
		(hatch none 0.5)
		(connect_pads
			(clearance 0.5)
		)
		(min_thickness 0.25)
		(fill yes
			(thermal_gap 0.5)
			(thermal_bridge_width 0.5)
			(island_removal_mode 0)
		)
		(polygon
			(pts
				(xy 34.29 -422.275) (xy 34.29 -429.133) (xy 37.211 -432.054) (xy 43.053 -432.054) (xy 53.721 -442.722)
				(xy 56.896 -442.722) (xy 58.801 -440.817) (xy 58.801 -402.463) (xy 57.404 -401.066) (xy 55.499 -401.066)
			)
		)
	)
	(zone
		(layer "B.Cu")
		(hatch none 0.5)
		(connect_pads
			(clearance 0)
		)
		(min_thickness 0.25)
		(keepout
			(tracks allowed)
			(vias allowed)
			(pads allowed)
			(copperpour allowed)
			(footprints allowed)
		)
		(placement
			(enabled no)
			(sheetname "")
		)
		(fill
			(thermal_gap 0.5)
			(thermal_bridge_width 0.5)
			(island_removal_mode 0)
		)
		(polygon
			(pts
				(xy 1.524 -315.976) (xy 1.524 -360.68) (xy 7.239 -360.68) (xy 7.239 -315.976)
			)
		)
	)
	(zone
		(layer "B.Cu")
		(hatch none 0.5)
		(connect_pads
			(clearance 0)
		)
		(min_thickness 0.25)
		(keepout
			(tracks not_allowed)
			(vias allowed)
			(pads allowed)
			(copperpour not_allowed)
			(footprints allowed)
		)
		(placement
			(enabled no)
			(sheetname "")
		)
		(fill
			(thermal_gap 0.5)
			(thermal_bridge_width 0.5)
			(island_removal_mode 0)
		)
		(polygon
			(pts
				(arc
					(start 5.59054 -305.935634)
					(mid 5.080127 -305.42484)
					(end 4.56946 -305.93538)
				)
				(xy 4.56946 -306.089304) (xy 4.784598 -306.089304)
				(arc
					(start 4.834382 -306.03952)
					(mid 5.268644 -305.746736)
					(end 4.97586 -306.180998)
				)
				(xy 4.867402 -306.289456) (xy 4.56946 -306.289456) (xy 4.56946 -306.394358) (xy 4.867656 -306.394358)
				(arc
					(start 4.97586 -306.502562)
					(mid 5.268644 -306.936824)
					(end 4.834382 -306.64404)
				)
				(xy 4.784852 -306.59451) (xy 4.56946 -306.59451)
				(arc
					(start 4.56946 -306.74818)
					(mid 5.08 -307.25872)
					(end 5.59054 -306.74818)
				)
			)
		)
	)
	(zone
		(layer "B.Cu")
		(hatch none 0.5)
		(connect_pads
			(clearance 0)
		)
		(min_thickness 0.25)
		(keepout
			(tracks not_allowed)
			(vias allowed)
			(pads allowed)
			(copperpour not_allowed)
			(footprints allowed)
		)
		(placement
			(enabled no)
			(sheetname "")
		)
		(fill
			(thermal_gap 0.5)
			(thermal_bridge_width 0.5)
			(island_removal_mode 0)
		)
		(polygon
			(pts
				(arc
					(start 5.59054 -320.335656)
					(mid 5.080127 -319.824862)
					(end 4.56946 -320.335402)
				)
				(xy 4.56946 -320.489326) (xy 4.784598 -320.489326)
				(arc
					(start 4.834382 -320.439542)
					(mid 5.268644 -320.146758)
					(end 4.97586 -320.58102)
				)
				(xy 4.867402 -320.689478) (xy 4.56946 -320.689478) (xy 4.56946 -320.79438) (xy 4.867656 -320.79438)
				(arc
					(start 4.97586 -320.902584)
					(mid 5.268644 -321.336846)
					(end 4.834382 -321.044062)
				)
				(xy 4.784852 -320.994532) (xy 4.56946 -320.994532)
				(arc
					(start 4.56946 -321.148202)
					(mid 5.08 -321.658742)
					(end 5.59054 -321.148202)
				)
			)
		)
	)
	(zone
		(layer "B.Cu")
		(hatch none 0.5)
		(connect_pads
			(clearance 0)
		)
		(min_thickness 0.25)
		(keepout
			(tracks not_allowed)
			(vias allowed)
			(pads allowed)
			(copperpour not_allowed)
			(footprints allowed)
		)
		(placement
			(enabled no)
			(sheetname "")
		)
		(fill
			(thermal_gap 0.5)
			(thermal_bridge_width 0.5)
			(island_removal_mode 0)
		)
		(polygon
			(pts
				(arc
					(start 5.59054 -191.135762)
					(mid 5.080127 -190.624968)
					(end 4.56946 -191.135508)
				)
				(xy 4.56946 -191.289432) (xy 4.784598 -191.289432)
				(arc
					(start 4.834382 -191.239648)
					(mid 5.268644 -190.946864)
					(end 4.97586 -191.381126)
				)
				(xy 4.867402 -191.489584) (xy 4.56946 -191.489584) (xy 4.56946 -191.594486) (xy 4.867656 -191.594486)
				(arc
					(start 4.97586 -191.70269)
					(mid 5.268644 -192.136952)
					(end 4.834382 -191.844168)
				)
				(xy 4.784852 -191.794638) (xy 4.56946 -191.794638)
				(arc
					(start 4.56946 -191.948308)
					(mid 5.08 -192.458848)
					(end 5.59054 -191.948308)
				)
			)
		)
	)
	(zone
		(layer "B.Cu")
		(hatch none 0.5)
		(connect_pads
			(clearance 0)
		)
		(min_thickness 0.25)
		(keepout
			(tracks not_allowed)
			(vias allowed)
			(pads allowed)
			(copperpour not_allowed)
			(footprints allowed)
		)
		(placement
			(enabled no)
			(sheetname "")
		)
		(fill
			(thermal_gap 0.5)
			(thermal_bridge_width 0.5)
			(island_removal_mode 0)
		)
		(polygon
			(pts
				(xy 1.022096 -460.995776) (xy 3.758184 -460.995776) (xy 3.81 -461.047592) (xy 3.81 -461.239108)
				(xy 3.761232 -461.287876) (xy 1.025398 -461.287876) (xy 1.014984 -461.29829) (xy 1.010158 -461.29829)
				(xy 1.005332 -461.293464) (xy 1.005332 -461.277208) (xy 1.005332 -461.006444) (xy 1.005332 -460.99095)
				(xy 1.007872 -460.98841) (xy 1.01473 -460.98841)
			)
		)
	)
	(zone
		(layer "B.Cu")
		(hatch none 0.5)
		(connect_pads
			(clearance 0)
		)
		(min_thickness 0.25)
		(keepout
			(tracks not_allowed)
			(vias allowed)
			(pads allowed)
			(copperpour not_allowed)
			(footprints allowed)
		)
		(placement
			(enabled no)
			(sheetname "")
		)
		(fill
			(thermal_gap 0.5)
			(thermal_bridge_width 0.5)
			(island_removal_mode 0)
		)
		(polygon
			(pts
				(arc
					(start 5.59054 -163.935664)
					(mid 5.080127 -163.42487)
					(end 4.56946 -163.93541)
				)
				(xy 4.56946 -164.089334) (xy 4.784598 -164.089334)
				(arc
					(start 4.834382 -164.03955)
					(mid 5.268644 -163.746766)
					(end 4.97586 -164.181028)
				)
				(xy 4.867402 -164.289486) (xy 4.56946 -164.289486) (xy 4.56946 -164.394388) (xy 4.867656 -164.394388)
				(arc
					(start 4.97586 -164.502592)
					(mid 5.268644 -164.936854)
					(end 4.834382 -164.64407)
				)
				(xy 4.784852 -164.59454) (xy 4.56946 -164.59454)
				(arc
					(start 4.56946 -164.74821)
					(mid 5.08 -165.25875)
					(end 5.59054 -164.74821)
				)
			)
		)
	)
	(zone
		(layer "B.Cu")
		(hatch none 0.5)
		(connect_pads
			(clearance 0)
		)
		(min_thickness 0.25)
		(keepout
			(tracks allowed)
			(vias allowed)
			(pads allowed)
			(copperpour allowed)
			(footprints allowed)
		)
		(placement
			(enabled no)
			(sheetname "")
		)
		(fill
			(thermal_gap 0.5)
			(thermal_bridge_width 0.5)
			(island_removal_mode 0)
		)
		(polygon
			(pts
				(xy 1.524 -277.622) (xy 1.524 -312.674) (xy 7.239 -312.674) (xy 7.239 -277.622)
			)
		)
	)
	(zone
		(layer "B.Cu")
		(hatch none 0.5)
		(connect_pads
			(clearance 0)
		)
		(min_thickness 0.25)
		(keepout
			(tracks not_allowed)
			(vias allowed)
			(pads allowed)
			(copperpour not_allowed)
			(footprints allowed)
		)
		(placement
			(enabled no)
			(sheetname "")
		)
		(fill
			(thermal_gap 0.5)
			(thermal_bridge_width 0.5)
			(island_removal_mode 0)
		)
		(polygon
			(pts
				(arc
					(start 5.59054 -438.335166)
					(mid 5.08 -437.824626)
					(end 4.56946 -438.335166)
				)
				(xy 4.56946 -438.489344) (xy 4.784344 -438.489344)
				(arc
					(start 4.834382 -438.439306)
					(mid 5.268644 -438.146522)
					(end 4.97586 -438.580784)
				)
				(xy 4.867148 -438.689496) (xy 4.56946 -438.689496) (xy 4.56946 -438.794398) (xy 4.86791 -438.794398)
				(arc
					(start 4.97586 -438.902348)
					(mid 5.268644 -439.33661)
					(end 4.834382 -439.043826)
				)
				(xy 4.785106 -438.99455) (xy 4.56946 -438.99455)
				(arc
					(start 4.56946 -439.147712)
					(mid 5.079873 -439.658506)
					(end 5.59054 -439.147966)
				)
			)
		)
	)
	(zone
		(net "GND")
		(layer "B.Cu")
		(hatch none 0.5)
		(connect_pads
			(clearance 0.5)
		)
		(min_thickness 0.25)
		(fill yes
			(thermal_gap 0.5)
			(thermal_bridge_width 0.5)
			(island_removal_mode 0)
		)
		(polygon
			(pts
				(xy 242.062 -420.116) (xy 239.035844 -423.142156) (xy 239.035844 -425.401486) (xy 241.173 -427.538642)
				(xy 241.173 -442.849) (xy 237.5408 -446.4812) (xy 230.0478 -446.4812) (xy 222.25 -454.279) (xy 222.25 -459.867)
				(xy 184.785 -497.332) (xy 38.8112 -497.332) (xy 38.6588 -497.4844) (xy 38.6588 -500.9134) (xy 38.1254 -501.4468)
				(xy 34.8996 -501.4468) (xy 34.2646 -500.8118) (xy 34.2646 -497.0526) (xy 17.907 -480.695) (xy 12.573 -480.695)
				(xy 11.7348 -479.8568) (xy 11.7348 -462.358994) (xy 11.27887 -461.903064) (xy 9.776714 -461.903064)
				(xy 9.4742 -462.205578) (xy 9.4742 -477.922844) (xy 8.60933 -478.787714) (xy 2.032 -478.787714)
				(xy 2.032 -477.971612) (xy 1.494282 -477.433894) (xy 0.763016 -477.433894)
				(arc
					(start 0.763016 -505.000006)
					(mid 0.832426 -505.167578)
					(end 0.999998 -505.236988)
				)
				(arc
					(start 262.50011 -505.236988)
					(mid 262.667682 -505.167578)
					(end 262.737092 -505.000006)
				)
				(xy 262.737092 -434.587904) (xy 262.255 -434.587904) (xy 262.255 -429.006) (xy 261.112 -427.863)
				(xy 260.27888 -427.863) (xy 259.08 -426.66412) (xy 259.08 -425.323) (xy 252.984 -425.323) (xy 252.73 -425.069)
				(xy 248.539 -425.069) (xy 247.269 -423.799) (xy 247.269 -422.148) (xy 245.237 -420.116)
			)
		)
	)
	(zone
		(layer "B.Cu")
		(hatch none 0.5)
		(connect_pads
			(clearance 0)
		)
		(min_thickness 0.25)
		(keepout
			(tracks not_allowed)
			(vias allowed)
			(pads allowed)
			(copperpour not_allowed)
			(footprints allowed)
		)
		(placement
			(enabled no)
			(sheetname "")
		)
		(fill
			(thermal_gap 0.5)
			(thermal_bridge_width 0.5)
			(island_removal_mode 0)
		)
		(polygon
			(pts
				(arc
					(start 12.500102 -68.000118)
					(mid 8.50011 -64.000126)
					(end 4.500118 -68.000118)
				)
				(arc
					(start 4.500118 -71.499984)
					(mid 8.50011 -75.499976)
					(end 12.500102 -71.499984)
				)
			)
		)
	)
	(zone
		(net "P12V")
		(layer "B.Cu")
		(hatch none 0.5)
		(connect_pads
			(clearance 0.5)
		)
		(min_thickness 0.25)
		(fill yes
			(thermal_gap 0.5)
			(thermal_bridge_width 0.5)
			(island_removal_mode 0)
		)
		(polygon
			(pts
				(xy 253.5682 -361.315) (xy 237.363 -361.315) (xy 236.728 -361.95) (xy 236.728 -383.413) (xy 236.9058 -383.5908)
				(xy 249.174 -383.5908) (xy 249.3772 -383.794) (xy 258.953 -383.794) (xy 259.08 -383.667) (xy 259.08 -364.236)
				(xy 256.3114 -361.4674) (xy 253.7206 -361.4674)
			)
		)
	)
	(zone
		(layer "B.Cu")
		(hatch none 0.5)
		(connect_pads
			(clearance 0)
		)
		(min_thickness 0.25)
		(keepout
			(tracks not_allowed)
			(vias allowed)
			(pads allowed)
			(copperpour not_allowed)
			(footprints allowed)
		)
		(placement
			(enabled no)
			(sheetname "")
		)
		(fill
			(thermal_gap 0.5)
			(thermal_bridge_width 0.5)
			(island_removal_mode 0)
		)
		(polygon
			(pts
				(arc
					(start 48.89754 -266.579604)
					(mid 48.387127 -266.06881)
					(end 47.87646 -266.57935)
				)
				(xy 47.87646 -266.73302) (xy 48.091852 -266.73302)
				(arc
					(start 48.141382 -266.68349)
					(mid 48.575644 -266.390706)
					(end 48.28286 -266.824968)
				)
				(xy 48.174656 -266.933172) (xy 47.87646 -266.933172) (xy 47.87646 -267.038074) (xy 48.174402 -267.038074)
				(arc
					(start 48.28286 -267.146532)
					(mid 48.575644 -267.580794)
					(end 48.141382 -267.28801)
				)
				(xy 48.091598 -267.238226) (xy 47.87646 -267.238226)
				(arc
					(start 47.87646 -267.39215)
					(mid 48.387 -267.90269)
					(end 48.89754 -267.39215)
				)
			)
		)
	)
	(zone
		(layer "B.Cu")
		(hatch none 0.5)
		(connect_pads
			(clearance 0)
		)
		(min_thickness 0.25)
		(keepout
			(tracks not_allowed)
			(vias allowed)
			(pads allowed)
			(copperpour not_allowed)
			(footprints allowed)
		)
		(placement
			(enabled no)
			(sheetname "")
		)
		(fill
			(thermal_gap 0.5)
			(thermal_bridge_width 0.5)
			(island_removal_mode 0)
		)
		(polygon
			(pts
				(arc
					(start 17.78254 -238.603282)
					(mid 17.272 -238.092742)
					(end 16.76146 -238.603282)
				)
				(arc
					(start 16.76146 -239.415828)
					(mid 17.271873 -239.926622)
					(end 17.78254 -239.416082)
				)
				(xy 17.78254 -239.243362) (xy 17.586198 -239.243362)
				(arc
					(start 17.517618 -239.311942)
					(mid 17.083356 -239.604726)
					(end 17.37614 -239.170464)
				)
				(xy 17.503394 -239.04321) (xy 17.78254 -239.04321) (xy 17.78254 -238.938308) (xy 17.465548 -238.938308)
				(arc
					(start 17.37614 -238.8489)
					(mid 17.083356 -238.414638)
					(end 17.517618 -238.707422)
				)
				(xy 17.548352 -238.738156) (xy 17.78254 -238.738156)
			)
		)
	)
	(zone
		(layer "B.Cu")
		(hatch none 0.5)
		(connect_pads
			(clearance 0)
		)
		(min_thickness 0.25)
		(keepout
			(tracks not_allowed)
			(vias allowed)
			(pads allowed)
			(copperpour not_allowed)
			(footprints allowed)
		)
		(placement
			(enabled no)
			(sheetname "")
		)
		(fill
			(thermal_gap 0.5)
			(thermal_bridge_width 0.5)
			(island_removal_mode 0)
		)
		(polygon
			(pts
				(arc
					(start 233.897424 -266.57935)
					(mid 233.386884 -266.06881)
					(end 232.876344 -266.57935)
				)
				(xy 232.876344 -266.73302) (xy 233.091736 -266.73302)
				(arc
					(start 233.141266 -266.68349)
					(mid 233.575528 -266.390706)
					(end 233.282744 -266.824968)
				)
				(xy 233.17454 -266.933172) (xy 232.876344 -266.933172) (xy 232.876344 -267.038074) (xy 233.174286 -267.038074)
				(arc
					(start 233.282744 -267.146532)
					(mid 233.575528 -267.580794)
					(end 233.141266 -267.28801)
				)
				(xy 233.091482 -267.238226) (xy 232.876344 -267.238226)
				(arc
					(start 232.876344 -267.391896)
					(mid 233.386757 -267.90269)
					(end 233.897424 -267.39215)
				)
			)
		)
	)
	(zone
		(layer "B.Cu")
		(hatch none 0.5)
		(connect_pads
			(clearance 0)
		)
		(min_thickness 0.25)
		(keepout
			(tracks not_allowed)
			(vias allowed)
			(pads allowed)
			(copperpour not_allowed)
			(footprints allowed)
		)
		(placement
			(enabled no)
			(sheetname "")
		)
		(fill
			(thermal_gap 0.5)
			(thermal_bridge_width 0.5)
			(island_removal_mode 0)
		)
		(polygon
			(pts
				(arc
					(start 72.90054 -431.139854)
					(mid 72.390127 -430.62906)
					(end 71.87946 -431.1396)
				)
				(arc
					(start 71.87946 -431.9524)
					(mid 72.39 -432.46294)
					(end 72.90054 -431.9524)
				)
				(xy 72.90054 -431.798476) (xy 72.685402 -431.798476)
				(arc
					(start 72.635618 -431.84826)
					(mid 72.201356 -432.141044)
					(end 72.49414 -431.706782)
				)
				(xy 72.602598 -431.598324) (xy 72.90054 -431.598324) (xy 72.90054 -431.493422) (xy 72.602344 -431.493422)
				(arc
					(start 72.49414 -431.385218)
					(mid 72.201356 -430.950956)
					(end 72.635618 -431.24374)
				)
				(xy 72.685148 -431.29327) (xy 72.90054 -431.29327)
			)
		)
	)
	(zone
		(layer "B.Cu")
		(hatch none 0.5)
		(connect_pads
			(clearance 0)
		)
		(min_thickness 0.25)
		(keepout
			(tracks not_allowed)
			(vias allowed)
			(pads allowed)
			(copperpour not_allowed)
			(footprints allowed)
		)
		(placement
			(enabled no)
			(sheetname "")
		)
		(fill
			(thermal_gap 0.5)
			(thermal_bridge_width 0.5)
			(island_removal_mode 0)
		)
		(polygon
			(pts
				(arc
					(start 5.59054 -341.935562)
					(mid 5.080127 -341.424768)
					(end 4.56946 -341.935308)
				)
				(xy 4.56946 -342.089486) (xy 4.784344 -342.089486)
				(arc
					(start 4.834382 -342.039448)
					(mid 5.268644 -341.746664)
					(end 4.97586 -342.180926)
				)
				(xy 4.867148 -342.289638) (xy 4.56946 -342.289638) (xy 4.56946 -342.39454) (xy 4.86791 -342.39454)
				(arc
					(start 4.97586 -342.50249)
					(mid 5.268644 -342.936752)
					(end 4.834382 -342.643968)
				)
				(xy 4.785106 -342.594692) (xy 4.56946 -342.594692)
				(arc
					(start 4.56946 -342.748108)
					(mid 5.08 -343.258648)
					(end 5.59054 -342.748108)
				)
			)
		)
	)
	(zone
		(layer "B.Cu")
		(hatch none 0.5)
		(connect_pads
			(clearance 0)
		)
		(min_thickness 0.25)
		(keepout
			(tracks not_allowed)
			(vias allowed)
			(pads allowed)
			(copperpour not_allowed)
			(footprints allowed)
		)
		(placement
			(enabled no)
			(sheetname "")
		)
		(fill
			(thermal_gap 0.5)
			(thermal_bridge_width 0.5)
			(island_removal_mode 0)
		)
		(polygon
			(pts
				(arc
					(start 5.59054 -222.335598)
					(mid 5.080127 -221.824804)
					(end 4.56946 -222.335344)
				)
				(xy 4.56946 -222.489522) (xy 4.784344 -222.489522)
				(arc
					(start 4.834382 -222.439484)
					(mid 5.268644 -222.1467)
					(end 4.97586 -222.580962)
				)
				(xy 4.867148 -222.689674) (xy 4.56946 -222.689674) (xy 4.56946 -222.794576) (xy 4.86791 -222.794576)
				(arc
					(start 4.97586 -222.902526)
					(mid 5.268644 -223.336788)
					(end 4.834382 -223.044004)
				)
				(xy 4.785106 -222.994728) (xy 4.56946 -222.994728)
				(arc
					(start 4.56946 -223.148144)
					(mid 5.08 -223.658684)
					(end 5.59054 -223.148144)
				)
			)
		)
	)
	(zone
		(layer "B.Cu")
		(hatch none 0.5)
		(connect_pads
			(clearance 0)
		)
		(min_thickness 0.25)
		(keepout
			(tracks not_allowed)
			(vias allowed)
			(pads allowed)
			(copperpour not_allowed)
			(footprints allowed)
		)
		(placement
			(enabled no)
			(sheetname "")
		)
		(fill
			(thermal_gap 0.5)
			(thermal_bridge_width 0.5)
			(island_removal_mode 0)
		)
		(polygon
			(pts
				(arc
					(start 5.59054 -354.735638)
					(mid 5.080127 -354.224844)
					(end 4.56946 -354.735384)
				)
				(xy 4.56946 -354.889308) (xy 4.784598 -354.889308)
				(arc
					(start 4.834382 -354.839524)
					(mid 5.268644 -354.54674)
					(end 4.97586 -354.981002)
				)
				(xy 4.867402 -355.08946) (xy 4.56946 -355.08946) (xy 4.56946 -355.194362) (xy 4.867656 -355.194362)
				(arc
					(start 4.97586 -355.302566)
					(mid 5.268644 -355.736828)
					(end 4.834382 -355.444044)
				)
				(xy 4.784852 -355.394514) (xy 4.56946 -355.394514)
				(arc
					(start 4.56946 -355.548184)
					(mid 5.08 -356.058724)
					(end 5.59054 -355.548184)
				)
			)
		)
	)
	(zone
		(net "GND")
		(layer "B.Cu")
		(hatch none 0.5)
		(connect_pads
			(clearance 0.5)
		)
		(min_thickness 0.25)
		(fill yes
			(thermal_gap 0.5)
			(thermal_bridge_width 0.5)
			(island_removal_mode 0)
		)
		(polygon
			(pts
				(xy 35.184842 -393.959842) (xy 34.024316 -392.799316) (xy 29.198316 -392.799316) (xy 27.178 -390.779)
				(xy 23.495 -390.779) (xy 22.225 -392.049) (xy 22.225 -410.680154) (xy 26.5684 -415.023554) (xy 26.5684 -423.0624)
				(xy 27.94 -424.434) (xy 29.718 -424.434) (xy 75.565 -378.587) (xy 75.565 -374.65) (xy 72.644 -371.729)
				(xy 67.564 -371.729) (xy 63.20028 -376.09272) (xy 63.20028 -382.690624) (xy 51.931062 -393.959842)
			)
		)
	)
	(zone
		(layer "B.Cu")
		(hatch none 0.5)
		(connect_pads
			(clearance 0)
		)
		(min_thickness 0.25)
		(keepout
			(tracks not_allowed)
			(vias allowed)
			(pads allowed)
			(copperpour not_allowed)
			(footprints allowed)
		)
		(placement
			(enabled no)
			(sheetname "")
		)
		(fill
			(thermal_gap 0.5)
			(thermal_bridge_width 0.5)
			(island_removal_mode 0)
		)
		(polygon
			(pts
				(xy 1.022096 -464.195922) (xy 3.758184 -464.195922) (xy 3.81 -464.247738) (xy 3.81 -464.439254)
				(xy 3.761232 -464.488022) (xy 1.025398 -464.488022) (xy 1.014984 -464.498436) (xy 1.010158 -464.498436)
				(xy 1.005332 -464.49361) (xy 1.005332 -464.477354) (xy 1.005332 -464.20659) (xy 1.005332 -464.191096)
				(xy 1.007872 -464.188556) (xy 1.01473 -464.188556)
			)
		)
	)
	(zone
		(layer "B.Cu")
		(hatch none 0.5)
		(connect_pads
			(clearance 0)
		)
		(min_thickness 0.25)
		(keepout
			(tracks not_allowed)
			(vias allowed)
			(pads allowed)
			(copperpour not_allowed)
			(footprints allowed)
		)
		(placement
			(enabled no)
			(sheetname "")
		)
		(fill
			(thermal_gap 0.5)
			(thermal_bridge_width 0.5)
			(island_removal_mode 0)
		)
		(polygon
			(pts
				(arc
					(start 257.50012 -479.997516)
					(mid 253.500128 -475.997524)
					(end 249.499882 -479.997516)
				)
				(arc
					(start 249.499882 -483.497636)
					(mid 253.500128 -487.497882)
					(end 257.50012 -483.497636)
				)
			)
		)
	)
	(zone
		(layer "B.Cu")
		(hatch none 0.5)
		(connect_pads
			(clearance 0)
		)
		(min_thickness 0.25)
		(keepout
			(tracks not_allowed)
			(vias allowed)
			(pads allowed)
			(copperpour not_allowed)
			(footprints allowed)
		)
		(placement
			(enabled no)
			(sheetname "")
		)
		(fill
			(thermal_gap 0.5)
			(thermal_bridge_width 0.5)
			(island_removal_mode 0)
		)
		(polygon
			(pts
				(arc
					(start 74.000106 -170.4975)
					(mid 70.000114 -166.497508)
					(end 66.000122 -170.4975)
				)
				(arc
					(start 66.000122 -173.99762)
					(mid 70.000114 -177.997612)
					(end 74.000106 -173.99762)
				)
			)
		)
	)
	(zone
		(layer "B.Cu")
		(hatch none 0.5)
		(connect_pads
			(clearance 0)
		)
		(min_thickness 0.25)
		(keepout
			(tracks not_allowed)
			(vias allowed)
			(pads allowed)
			(copperpour not_allowed)
			(footprints allowed)
		)
		(placement
			(enabled no)
			(sheetname "")
		)
		(fill
			(thermal_gap 0.5)
			(thermal_bridge_width 0.5)
			(island_removal_mode 0)
		)
		(polygon
			(pts
				(arc
					(start 5.59054 -351.535746)
					(mid 5.080127 -351.024952)
					(end 4.56946 -351.535492)
				)
				(xy 4.56946 -351.689416) (xy 4.784598 -351.689416)
				(arc
					(start 4.834382 -351.639632)
					(mid 5.268644 -351.346848)
					(end 4.97586 -351.78111)
				)
				(xy 4.867402 -351.889568) (xy 4.56946 -351.889568) (xy 4.56946 -351.99447) (xy 4.867656 -351.99447)
				(arc
					(start 4.97586 -352.102674)
					(mid 5.268644 -352.536936)
					(end 4.834382 -352.244152)
				)
				(xy 4.784852 -352.194622) (xy 4.56946 -352.194622)
				(arc
					(start 4.56946 -352.348292)
					(mid 5.08 -352.858832)
					(end 5.59054 -352.348292)
				)
			)
		)
	)
	(zone
		(layer "B.Cu")
		(hatch none 0.5)
		(connect_pads
			(clearance 0)
		)
		(min_thickness 0.25)
		(keepout
			(tracks not_allowed)
			(vias allowed)
			(pads allowed)
			(copperpour not_allowed)
			(footprints allowed)
		)
		(placement
			(enabled no)
			(sheetname "")
		)
		(fill
			(thermal_gap 0.5)
			(thermal_bridge_width 0.5)
			(island_removal_mode 0)
		)
		(polygon
			(pts
				(arc
					(start 74.000106 -479.997516)
					(mid 70.000114 -475.997524)
					(end 66.000122 -479.997516)
				)
				(arc
					(start 66.000122 -483.497636)
					(mid 70.000114 -487.497628)
					(end 74.000106 -483.497636)
				)
			)
		)
	)
	(zone
		(layer "B.Cu")
		(hatch none 0.5)
		(connect_pads
			(clearance 0)
		)
		(min_thickness 0.25)
		(keepout
			(tracks not_allowed)
			(vias allowed)
			(pads allowed)
			(copperpour not_allowed)
			(footprints allowed)
		)
		(placement
			(enabled no)
			(sheetname "")
		)
		(fill
			(thermal_gap 0.5)
			(thermal_bridge_width 0.5)
			(island_removal_mode 0)
		)
		(polygon
			(pts
				(arc
					(start 17.78254 -135.603234)
					(mid 17.272 -135.092694)
					(end 16.76146 -135.603234)
				)
				(arc
					(start 16.76146 -136.41578)
					(mid 17.271873 -136.926574)
					(end 17.78254 -136.416034)
				)
				(xy 17.78254 -136.262618) (xy 17.566894 -136.262618)
				(arc
					(start 17.517618 -136.311894)
					(mid 17.083356 -136.604678)
					(end 17.37614 -136.170416)
				)
				(xy 17.48409 -136.062466) (xy 17.78254 -136.062466) (xy 17.78254 -135.957564) (xy 17.484852 -135.957564)
				(arc
					(start 17.37614 -135.848852)
					(mid 17.083356 -135.41459)
					(end 17.517618 -135.707374)
				)
				(xy 17.567656 -135.757412) (xy 17.78254 -135.757412)
			)
		)
	)
	(zone
		(layer "B.Cu")
		(hatch none 0.5)
		(connect_pads
			(clearance 0)
		)
		(min_thickness 0.25)
		(keepout
			(tracks not_allowed)
			(vias allowed)
			(pads allowed)
			(copperpour not_allowed)
			(footprints allowed)
		)
		(placement
			(enabled no)
			(sheetname "")
		)
		(fill
			(thermal_gap 0.5)
			(thermal_bridge_width 0.5)
			(island_removal_mode 0)
		)
		(polygon
			(pts
				(arc
					(start 74.000106 -67.499992)
					(mid 70.000114 -63.5)
					(end 66.000122 -67.499992)
				)
				(arc
					(start 66.000122 -71.000112)
					(mid 70.000114 -75.000104)
					(end 74.000106 -71.000112)
				)
			)
		)
	)
	(zone
		(layer "B.Cu")
		(hatch none 0.5)
		(connect_pads
			(clearance 0)
		)
		(min_thickness 0.25)
		(keepout
			(tracks not_allowed)
			(vias allowed)
			(pads allowed)
			(copperpour not_allowed)
			(footprints allowed)
		)
		(placement
			(enabled no)
			(sheetname "")
		)
		(fill
			(thermal_gap 0.5)
			(thermal_bridge_width 0.5)
			(island_removal_mode 0)
		)
		(polygon
			(pts
				(arc
					(start 8.382254 -385.092702)
					(mid 7.871714 -385.603242)
					(end 8.382254 -386.113782)
				)
				(arc
					(start 9.1948 -386.113782)
					(mid 9.705594 -385.603369)
					(end 9.195054 -385.092702)
				)
				(xy 9.04113 -385.092702) (xy 9.04113 -385.30784)
				(arc
					(start 9.090914 -385.357624)
					(mid 9.383698 -385.791886)
					(end 8.949436 -385.499102)
				)
				(xy 8.840978 -385.390644) (xy 8.840978 -385.092702) (xy 8.736076 -385.092702) (xy 8.736076 -385.390898)
				(arc
					(start 8.627872 -385.499102)
					(mid 8.19361 -385.791886)
					(end 8.486394 -385.357624)
				)
				(xy 8.535924 -385.308094) (xy 8.535924 -385.092702)
			)
		)
	)
	(zone
		(layer "B.Cu")
		(hatch none 0.5)
		(connect_pads
			(clearance 0)
		)
		(min_thickness 0.25)
		(keepout
			(tracks not_allowed)
			(vias allowed)
			(pads allowed)
			(copperpour not_allowed)
			(footprints allowed)
		)
		(placement
			(enabled no)
			(sheetname "")
		)
		(fill
			(thermal_gap 0.5)
			(thermal_bridge_width 0.5)
			(island_removal_mode 0)
		)
		(polygon
			(pts
				(arc
					(start 5.59054 -203.135738)
					(mid 5.080127 -202.624944)
					(end 4.56946 -203.135484)
				)
				(xy 4.56946 -203.289408) (xy 4.784598 -203.289408)
				(arc
					(start 4.834382 -203.239624)
					(mid 5.268644 -202.94684)
					(end 4.97586 -203.381102)
				)
				(xy 4.867402 -203.48956) (xy 4.56946 -203.48956) (xy 4.56946 -203.594462) (xy 4.867656 -203.594462)
				(arc
					(start 4.97586 -203.702666)
					(mid 5.268644 -204.136928)
					(end 4.834382 -203.844144)
				)
				(xy 4.784852 -203.794614) (xy 4.56946 -203.794614)
				(arc
					(start 4.56946 -203.948284)
					(mid 5.08 -204.458824)
					(end 5.59054 -203.948284)
				)
			)
		)
	)
	(zone
		(layer "B.Cu")
		(hatch none 0.5)
		(connect_pads
			(clearance 0)
		)
		(min_thickness 0.25)
		(keepout
			(tracks not_allowed)
			(vias allowed)
			(pads allowed)
			(copperpour not_allowed)
			(footprints allowed)
		)
		(placement
			(enabled no)
			(sheetname "")
		)
		(fill
			(thermal_gap 0.5)
			(thermal_bridge_width 0.5)
			(island_removal_mode 0)
		)
		(polygon
			(pts
				(arc
					(start 5.59054 -335.535778)
					(mid 5.080127 -335.024984)
					(end 4.56946 -335.535524)
				)
				(xy 4.56946 -335.689448) (xy 4.784598 -335.689448)
				(arc
					(start 4.834382 -335.639664)
					(mid 5.268644 -335.34688)
					(end 4.97586 -335.781142)
				)
				(xy 4.867402 -335.8896) (xy 4.56946 -335.8896) (xy 4.56946 -335.994502) (xy 4.867656 -335.994502)
				(arc
					(start 4.97586 -336.102706)
					(mid 5.268644 -336.536968)
					(end 4.834382 -336.244184)
				)
				(xy 4.784852 -336.194654) (xy 4.56946 -336.194654)
				(arc
					(start 4.56946 -336.348324)
					(mid 5.08 -336.858864)
					(end 5.59054 -336.348324)
				)
			)
		)
	)
	(zone
		(layer "B.Cu")
		(hatch none 0.5)
		(connect_pads
			(clearance 0)
		)
		(min_thickness 0.25)
		(keepout
			(tracks not_allowed)
			(vias allowed)
			(pads allowed)
			(copperpour not_allowed)
			(footprints allowed)
		)
		(placement
			(enabled no)
			(sheetname "")
		)
		(fill
			(thermal_gap 0.5)
			(thermal_bridge_width 0.5)
			(island_removal_mode 0)
		)
		(polygon
			(pts
				(xy 1.022096 -457.795884) (xy 3.758184 -457.795884) (xy 3.81 -457.8477) (xy 3.81 -458.039216) (xy 3.761232 -458.087984)
				(xy 1.025398 -458.087984) (xy 1.014984 -458.098398) (xy 1.010158 -458.098398) (xy 1.005332 -458.093572)
				(xy 1.005332 -458.077316) (xy 1.005332 -457.806552) (xy 1.005332 -457.791058) (xy 1.007872 -457.788518)
				(xy 1.01473 -457.788518)
			)
		)
	)
	(zone
		(net "GND")
		(layer "B.Cu")
		(hatch none 0.5)
		(connect_pads
			(clearance 0.5)
		)
		(min_thickness 0.25)
		(fill yes
			(thermal_gap 0.5)
			(thermal_bridge_width 0.5)
			(island_removal_mode 0)
		)
		(polygon
			(pts
				(xy 77.47 -353.314) (xy 77.47 -352.171) (xy 78.359 -351.282) (xy 78.359 -346.837) (xy 82.296 -342.9)
				(xy 82.296 -317.5) (xy 79.883 -315.087) (xy 79.883 -307.086) (xy 79.121 -306.324) (xy 75.946 -306.324)
				(xy 74.168 -308.102) (xy 74.168 -349.9104) (xy 75.057 -350.7994) (xy 75.057 -353.822) (xy 75.311 -354.076)
				(xy 76.708 -354.076)
			)
		)
	)
	(zone
		(layer "B.Cu")
		(hatch none 0.5)
		(connect_pads
			(clearance 0)
		)
		(min_thickness 0.25)
		(keepout
			(tracks not_allowed)
			(vias allowed)
			(pads allowed)
			(copperpour not_allowed)
			(footprints allowed)
		)
		(placement
			(enabled no)
			(sheetname "")
		)
		(fill
			(thermal_gap 0.5)
			(thermal_bridge_width 0.5)
			(island_removal_mode 0)
		)
		(polygon
			(pts
				(arc
					(start 5.59054 -403.935184)
					(mid 5.08 -403.424644)
					(end 4.56946 -403.935184)
				)
				(xy 4.56946 -404.089108) (xy 4.784598 -404.089108)
				(arc
					(start 4.834382 -404.039324)
					(mid 5.268644 -403.74654)
					(end 4.97586 -404.180802)
				)
				(xy 4.867402 -404.28926) (xy 4.56946 -404.28926) (xy 4.56946 -404.394162) (xy 4.867656 -404.394162)
				(arc
					(start 4.97586 -404.502366)
					(mid 5.268644 -404.936628)
					(end 4.834382 -404.643844)
				)
				(xy 4.784852 -404.594314) (xy 4.56946 -404.594314)
				(arc
					(start 4.56946 -404.74773)
					(mid 5.079873 -405.258524)
					(end 5.59054 -404.747984)
				)
			)
		)
	)
	(zone
		(net "P12V_SSD0")
		(layer "B.Cu")
		(hatch none 0.5)
		(connect_pads
			(clearance 0.5)
		)
		(min_thickness 0.25)
		(fill yes
			(thermal_gap 0.5)
			(thermal_bridge_width 0.5)
			(island_removal_mode 0)
		)
		(polygon
			(pts
				(xy 219.5576 -496.316) (xy 218.313 -496.316) (xy 218.186 -496.443) (xy 218.186 -501.015) (xy 218.313 -501.142)
				(xy 219.7354 -501.142) (xy 222.5294 -501.142) (xy 223.901 -501.142) (xy 224.155 -500.888) (xy 224.155 -496.4938)
				(xy 223.9772 -496.316)
			)
		)
	)
	(zone
		(net "GND")
		(layer "B.Cu")
		(hatch none 0.5)
		(connect_pads
			(clearance 0.5)
		)
		(min_thickness 0.25)
		(fill yes
			(thermal_gap 0.5)
			(thermal_bridge_width 0.5)
			(island_removal_mode 0)
		)
		(polygon
			(pts
				(arc
					(start 0.999998 -0.763016)
					(mid 0.832426 -0.832426)
					(end 0.763016 -0.999998)
				)
				(xy 0.763016 -141.135608) (xy 2.032 -141.135608) (xy 2.032 -141.097) (xy 4.191 -141.097) (xy 5.334 -139.954)
				(xy 5.334 -90.3224) (xy 14.6304 -81.026) (xy 14.6304 -71.6788) (xy 22.239478 -64.069722) (xy 22.239478 -62.262766)
				(xy 19.603212 -59.6265) (xy 19.603212 -56.745632) (xy 13.9446 -51.08702) (xy 13.9446 -13.462) (xy 16.7259 -10.6807)
				(xy 16.7259 -3.6195) (xy 17.1704 -3.175) (xy 19.5834 -3.175) (xy 20.9042 -4.4958) (xy 24.8666 -4.4958)
				(xy 25.6032 -5.2324) (xy 25.6032 -6.5024) (xy 25.8064 -6.7056) (xy 29.8704 -6.7056) (xy 31.496 -8.3312)
				(xy 33.528 -8.3312) (xy 33.528 -7.976362) (xy 32.10306 -7.976362) (xy 29.912818 -5.78612) (xy 29.912818 -2.40792)
				(xy 30.288738 -2.032) (xy 37.78123 -2.032) (xy 37.78123 -2.22631) (xy 37.6682 -2.33934) (xy 37.6682 -6.051804)
				(xy 35.743642 -7.976362) (xy 33.909 -7.976362) (xy 33.909 -8.3312) (xy 36.6776 -8.3312) (xy 40.7162 -4.2926)
				(xy 53.395118 -4.2926) (xy 54.835298 -5.73278) (xy 54.835298 -7.39902) (xy 53.20411 -9.030208) (xy 52.489354 -9.030208)
				(xy 49.84877 -6.389624) (xy 41.870376 -6.389624) (xy 39.0144 -9.2456) (xy 39.0144 -10.1346) (xy 39.7256 -10.8458)
				(xy 39.7256 -11.8872) (xy 39.624 -11.9888) (xy 36.576 -11.9888) (xy 33.8074 -14.7574) (xy 31.4452 -14.7574)
				(xy 31.0134 -14.3256) (xy 31.0134 -13.5636) (xy 30.607 -13.1572) (xy 28.7782 -13.1572) (xy 28.0543 -12.4333)
				(xy 17.1069 -12.4333) (xy 14.991842 -14.548358) (xy 15.01394 -28.46959) (xy 15.439898 -28.895548)
				(xy 18.481548 -28.895548) (xy 21.59 -32.004) (xy 31.877 -32.004) (xy 32.385 -32.512) (xy 32.385 -33.655)
				(xy 32.004 -34.036) (xy 30.734 -34.036) (xy 30.353 -33.655) (xy 18.887186 -33.655) (xy 18.506186 -34.036)
				(xy 16.256 -34.036) (xy 15.494 -34.798) (xy 15.494 -49.981866) (xy 22.872446 -57.360312) (xy 23.593298 -57.360312)
				(xy 23.753318 -57.200292) (xy 23.753318 -55.678578) (xy 24.42591 -55.005986) (xy 25.739344 -55.005986)
				(xy 27.052524 -53.692806) (xy 27.052524 -52.068476) (xy 36.83 -42.291) (xy 198.501 -42.291) (xy 203.962 -36.83)
				(xy 225.2218 -36.83) (xy 236.474 -48.0822) (xy 236.474 -63.246) (xy 231.14 -68.58) (xy 231.14 -90.532966)
				(xy 226.381564 -95.291402) (xy 206.812388 -95.291402) (xy 205.457806 -96.645984) (xy 204.852524 -96.645984)
				(xy 204.491844 -96.285304) (xy 204.491844 -95.07474) (xy 206.363824 -93.20276) (xy 206.891636 -93.20276)
				(xy 207.426306 -93.73743) (xy 209.125312 -93.73743) (xy 211.397342 -91.4654) (xy 215.5444 -91.4654)
				(xy 218.44 -94.361) (xy 225.101912 -94.361) (xy 226.441 -93.021912) (xy 226.441 -88.9) (xy 230.124 -85.217)
				(xy 230.124 -68.6308) (xy 227.33 -65.8368) (xy 227.33 -61.595) (xy 229.743 -59.182) (xy 232.918 -59.182)
				(xy 234.2134 -57.8866) (xy 234.2134 -49.1744) (xy 228.2571 -43.2181) (xy 225.4631 -43.2181) (xy 221.8182 -39.5732)
				(xy 205.6638 -39.5732) (xy 200.152 -45.085) (xy 38.551866 -45.085) (xy 30.7594 -52.877466) (xy 30.7594 -54.781704)
				(xy 26.234136 -59.306968) (xy 26.234136 -66.427858) (xy 19.558 -73.103994) (xy 19.558 -82.6516)
				(xy 10.4394 -91.7702) (xy 10.4394 -193.7004) (xy 11.049 -194.31) (xy 12.319 -194.31) (xy 21.971 -184.658)
				(xy 37.1602 -184.658) (xy 40.7924 -181.0258) (xy 40.7924 -172.1866) (xy 33.1724 -164.5666) (xy 33.1724 -156.6672)
				(xy 35.433 -154.4066) (xy 35.433 -149.8854) (xy 38.163246 -147.155154) (xy 38.163246 -140.180822)
				(xy 38.685978 -139.65809) (xy 39.32809 -139.65809) (xy 39.8526 -140.1826) (xy 39.8526 -147.43684)
				(xy 37.4142 -149.87524) (xy 37.4142 -165.9128) (xy 37.77615 -166.27475) (xy 41.29786 -166.27475)
				(xy 41.71061 -165.862) (xy 44.196 -165.862) (xy 44.611798 -166.277798) (xy 44.611798 -167.682418)
				(xy 43.23334 -169.060876) (xy 43.23334 -181.50586) (xy 39.878 -184.8612) (xy 39.878 -197.231) (xy 37.592 -199.517)
				(xy 23.876 -199.517) (xy 20.9804 -202.4126) (xy 20.9804 -203.2508) (xy 21.844 -204.1144) (xy 36.6522 -204.1144)
				(xy 37.2618 -204.724) (xy 37.2618 -205.486) (xy 36.9824 -205.7654) (xy 36.2458 -205.7654) (xy 35.941 -205.4606)
				(xy 18.8214 -205.4606) (xy 14.1224 -210.1596) (xy 14.1224 -227.838) (xy 19.2532 -232.9688) (xy 19.2532 -236.4994)
				(xy 20.7518 -237.998) (xy 42.926 -237.998) (xy 43.18 -238.252) (xy 43.18 -239.903) (xy 43.053 -240.03)
				(xy 42.164 -240.03) (xy 41.783 -240.411) (xy 41.783 -242.189) (xy 42.545 -242.951) (xy 42.545 -245.11)
				(xy 36.1442 -251.5108) (xy 36.1442 -262.001) (xy 34.163 -263.9822) (xy 34.163 -267.975588) (xy 34.155888 -267.9827)
				(xy 34.155888 -268.923262) (xy 34.962338 -269.729712) (xy 38.221412 -269.729712) (xy 38.75913 -269.191994)
				(xy 42.166794 -269.191994) (xy 43.815 -267.543788) (xy 43.815 -265.684) (xy 44.323 -265.176) (xy 48.006 -265.176)
				(xy 49.022 -266.192) (xy 49.022 -267.716) (xy 44.831 -271.907) (xy 32.0548 -271.907) (xy 10.287 -293.6748)
				(xy 10.287 -310.134) (xy 11.43 -311.277) (xy 13.843 -311.277) (xy 21.0058 -304.1142) (xy 21.0058 -299.7962)
				(xy 21.2598 -299.5422) (xy 21.9964 -299.5422) (xy 22.2758 -299.8216) (xy 22.2758 -305.1302) (xy 10.668 -316.738)
				(xy 6.985 -316.738) (xy 5.715 -318.008) (xy 5.715 -329.946) (xy 6.223 -330.454) (xy 7.366 -330.454)
				(xy 7.874 -329.946) (xy 13.867638 -329.946) (xy 16.280638 -332.359) (xy 19.177 -332.359) (xy 19.812 -331.724)
				(xy 19.812 -327.787) (xy 17.78 -325.755) (xy 17.78 -324.485) (xy 18.288 -323.977) (xy 19.177 -323.977)
				(xy 21.463 -326.263) (xy 21.463 -339.217) (xy 23.241 -340.995) (xy 33.274 -340.995) (xy 33.528 -341.249)
				(xy 33.528 -342.773) (xy 33.274 -343.027) (xy 25.4 -343.027) (xy 25.146 -342.773) (xy 17.907 -342.773)
				(xy 17.653 -343.027) (xy 16.256 -343.027) (xy 15.494 -343.789) (xy 15.494 -359.283) (xy 21.6154 -365.4044)
				(xy 21.6154 -368.5794) (xy 22.098 -369.062) (xy 25.7556 -369.062) (xy 39.7764 -355.0412) (xy 39.7764 -345.44)
				(xy 38.1254 -343.789) (xy 38.1254 -342.9) (xy 38.5064 -342.519) (xy 39.9034 -342.519) (xy 43.1546 -345.7702)
				(xy 43.1546 -347.8022) (xy 42.291 -348.6658) (xy 42.291 -354.584) (xy 31.734506 -365.140494) (xy 31.734506 -369.57254)
				(xy 34.678366 -372.5164) (xy 43.053 -372.5164) (xy 43.7134 -371.856) (xy 44.4246 -371.856) (xy 44.6786 -372.11)
				(xy 44.6786 -372.7196) (xy 43.815 -373.5832) (xy 33.926526 -373.5832) (xy 33.462976 -373.11965)
				(xy 32.92475 -373.11965) (xy 32.8168 -373.2276) (xy 32.8168 -375.0818) (xy 33.401 -375.666) (xy 33.401 -383.032)
				(xy 32.893 -383.54) (xy 32.131 -383.54) (xy 31.75 -383.159) (xy 31.75 -376.809) (xy 31.1658 -376.2248)
				(xy 31.1658 -372.4148) (xy 30.7086 -371.9576) (xy 17.2466 -371.9576) (xy 6.35 -361.061) (xy 1.905 -361.061)
				(xy 1.397 -361.569) (xy 1.397 -384.175) (xy 3.683 -384.175) (xy 3.689096 -384.181096) (xy 3.810254 -384.181096)
				(xy 4.058158 -384.429) (xy 4.318 -384.429) (xy 4.41706 -384.429) (xy 4.506722 -384.339338) (xy 4.506722 -384.121152)
				(xy 5.03936 -383.588514) (xy 9.312148 -383.588514) (xy 9.68248 -383.958846) (xy 9.689846 -383.958846)
				(xy 9.695434 -383.964434) (xy 12.237212 -383.964434) (xy 12.646406 -384.373628) (xy 12.646406 -388.23265)
				(xy 12.287504 -388.591552) (xy 10.262362 -388.591552) (xy 10.033 -388.820914) (xy 10.033 -395.88821)
				(xy 16.58239 -402.4376) (xy 20.15998 -402.4376) (xy 20.2692 -402.32838) (xy 20.2692 -389.4328) (xy 22.098 -387.604)
				(xy 32.639 -387.604) (xy 35.814 -390.779) (xy 46.863 -390.779) (xy 55.5244 -382.1176) (xy 55.5244 -342.9762)
				(xy 53.5178 -340.9696) (xy 53.5178 -270.129) (xy 53.34 -269.9512) (xy 52.9082 -269.9512) (xy 50.2666 -272.5928)
				(xy 49.53 -272.5928) (xy 49.0982 -272.161) (xy 49.0982 -271.5006) (xy 52.4256 -268.1732) (xy 52.4256 -242.5446)
				(xy 28.956 -219.075) (xy 28.956 -213.4362) (xy 30.226 -212.1662) (xy 39.9288 -212.1662) (xy 43.815 -208.28)
				(xy 43.815 -202.3364) (xy 51.816 -194.3354) (xy 51.816 -151.2062) (xy 44.831 -144.2212) (xy 44.831 -135.001)
				(xy 49.022 -130.81) (xy 49.022 -94.488) (xy 68.199 -75.311) (xy 69.596 -75.311) (xy 69.596 -74.93)
				(xy 69.723 -74.803) (xy 69.85 -74.93) (xy 69.85 -75.311) (xy 107.315 -75.311) (xy 108.331 -74.295)
				(xy 114.046 -74.295) (xy 139.446 -48.895) (xy 201.93 -48.895) (xy 202.565 -49.53) (xy 202.565 -50.292)
				(xy 201.93 -50.927) (xy 200.025 -50.927) (xy 199.644 -50.546) (xy 140.335 -50.546) (xy 112.522 -78.359)
				(xy 68.199 -78.359) (xy 50.546 -96.012) (xy 50.546 -133.604) (xy 47.625 -136.525) (xy 47.625 -144.399)
				(xy 53.721 -150.495) (xy 53.721 -187.198) (xy 55.372 -188.849) (xy 58.547 -188.849) (xy 60.325 -187.071)
				(xy 60.325 -155.575) (xy 62.357 -153.543) (xy 62.357 -147.574) (xy 56.261 -141.478) (xy 56.261 -113.792)
				(xy 54.864 -112.395) (xy 54.864 -110.109) (xy 58.166 -106.807) (xy 58.166 -97.028) (xy 59.69 -95.504)
				(xy 62.23 -95.504) (xy 63.119 -96.393) (xy 63.119 -98.552) (xy 62.484 -99.187) (xy 62.484 -140.589)
				(xy 64.262 -142.367) (xy 69.215 -142.367) (xy 70.104 -143.256) (xy 70.104 -151.638) (xy 69.596 -152.146)
				(xy 65.913 -152.146) (xy 62.23 -155.829) (xy 62.23 -163.449) (xy 63.119 -164.338) (xy 66.294 -164.338)
				(xy 71.755 -158.877) (xy 71.755 -155.575) (xy 72.644 -154.686) (xy 74.549 -154.686) (xy 78.359 -150.876)
				(xy 81.915 -150.876) (xy 84.455 -148.336) (xy 84.455 -144.653) (xy 84.836 -144.272) (xy 88.519 -144.272)
				(xy 89.662 -143.129) (xy 89.662 -135.0772) (xy 79.629 -125.0442) (xy 79.629 -102.87) (xy 79.502 -102.743)
				(xy 79.502 -99.441) (xy 80.264 -98.679) (xy 82.931 -98.679) (xy 83.693 -99.441) (xy 83.693 -101.219)
				(xy 84.709 -102.235) (xy 84.709 -125.3998) (xy 93.345 -134.0358) (xy 93.345 -145.288) (xy 85.471 -153.162)
				(xy 83.185 -153.162) (xy 81.915 -154.432) (xy 81.915 -156.718) (xy 83.185 -157.988) (xy 123.317 -157.988)
				(xy 125.984 -155.321) (xy 137.16 -155.321) (xy 142.494 -149.987) (xy 142.494 -136.906) (xy 142.113 -136.525)
				(xy 141.224 -136.525) (xy 139.954 -135.255) (xy 139.954 -132.588) (xy 140.589 -131.953) (xy 141.986 -131.953)
				(xy 144.018 -133.985) (xy 144.018 -151.13) (xy 133.35 -161.798) (xy 81.153 -161.798) (xy 78.359 -164.592)
				(xy 78.359 -202.311) (xy 78.486 -202.438) (xy 85.979 -202.438) (xy 86.0298 -202.3872) (xy 88.6968 -202.3872)
				(xy 83.185 -207.899) (xy 83.185 -210.566) (xy 84.8614 -212.2424) (xy 84.8614 -292.2524) (xy 86.3092 -293.7002)
				(xy 86.3092 -307.9496) (xy 84.201 -310.0578) (xy 84.201 -344.678) (xy 82.677 -346.202) (xy 82.677 -355.219)
				(xy 83.947 -356.489) (xy 86.487 -356.489) (xy 112.141 -330.835) (xy 112.141 -294.613838) (xy 108.357162 -290.83)
				(xy 104.902 -290.83) (xy 103.251 -289.179) (xy 103.251 -286.893) (xy 104.521 -285.623) (xy 107.188 -285.623)
				(xy 114.173 -292.608) (xy 114.173 -332.486) (xy 92.202 -354.457) (xy 92.202 -367.6142) (xy 114.3508 -389.763)
				(xy 114.3508 -438.0738) (xy 117.983 -441.706) (xy 117.983 -444.119) (xy 116.84 -445.262) (xy 113.411 -445.262)
				(xy 112.424464 -444.275464) (xy 112.424464 -440.882278) (xy 111.814864 -440.272678) (xy 102.017322 -440.272678)
				(xy 99.937824 -442.352176) (xy 93.816932 -442.352176) (xy 93.435932 -442.733176) (xy 93.435932 -444.407544)
				(xy 93.953076 -444.924688) (xy 96.335088 -444.924688) (xy 96.647 -445.2366) (xy 96.647 -446.659)
				(xy 94.488 -448.818) (xy 92.578428 -448.818) (xy 90.468196 -446.707768) (xy 90.468196 -444.733934)
				(xy 89.88298 -444.148718) (xy 79.932784 -444.148718) (xy 79.502 -444.579502) (xy 79.502 -449.199)
				(xy 74.168 -454.533) (xy 48.768 -454.533) (xy 46.101 -451.866) (xy 46.101 -447.929) (xy 48.641 -445.389)
				(xy 50.673 -445.389) (xy 51.308 -444.754) (xy 51.308 -443.357) (xy 41.8592 -433.9082) (xy 35.1028 -433.9082)
				(xy 25.146 -423.9514) (xy 25.146 -415.69767) (xy 20.32 -410.87167) (xy 20.32 -403.1488) (xy 17.907 -403.1488)
				(xy 17.479772 -403.576028) (xy 17.479772 -405.150828) (xy 16.51 -406.1206) (xy 16.51 -430.53) (xy 17.653 -431.673)
				(xy 17.653 -434.721) (xy 19.304 -436.372) (xy 22.479 -436.372) (xy 23.241 -437.134) (xy 25.527 -437.134)
				(xy 26.162 -436.499) (xy 28.702 -436.499) (xy 29.464 -437.261) (xy 36.83 -437.261) (xy 37.846 -438.277)
				(xy 37.846 -444.1444) (xy 40.9702 -447.2686) (xy 40.9702 -452.2724) (xy 39.2938 -453.9488) (xy 39.2938 -460.375)
				(xy 38.9128 -460.756) (xy 38.1 -460.756) (xy 37.846 -460.502) (xy 37.846 -448.056) (xy 35.814 -446.024)
				(xy 30.607 -446.024) (xy 30.226 -445.643) (xy 23.495 -445.643) (xy 23.114 -446.024) (xy 17.018 -446.024)
				(xy 16.383 -446.659) (xy 16.383 -449.0974) (xy 18.288 -451.0024) (xy 20.5994 -451.0024) (xy 27.4066 -457.8096)
				(xy 27.4066 -464.2358) (xy 24.9174 -466.725) (xy 24.9174 -470.705942) (xy 24.707342 -470.916) (xy 18.9992 -470.916)
				(xy 18.4658 -471.4494) (xy 18.4658 -473.0496) (xy 19.8882 -474.472) (xy 31.496 -474.472) (xy 35.2806 -470.6874)
				(xy 41.4528 -470.6874) (xy 42.9514 -469.1888) (xy 49.4538 -469.1888) (xy 66.675 -486.41) (xy 67.183 -485.902)
				(xy 67.437 -485.902) (xy 67.691 -486.156) (xy 67.691 -486.283) (xy 67.183 -486.791) (xy 67.183 -486.918)
				(xy 73.646792 -493.381792) (xy 183.274208 -493.381792) (xy 183.9976 -492.6584) (xy 183.9976 -489.6104)
				(xy 210.82 -462.788) (xy 210.82 -460.121) (xy 205.74 -455.041) (xy 205.74 -453.771) (xy 194.945 -442.976)
				(xy 194.945 -427.99) (xy 190.5 -423.545) (xy 190.5 -422.021) (xy 191.389 -421.132) (xy 195.834 -421.132)
				(xy 196.977 -422.275) (xy 196.977 -442.087) (xy 207.772 -452.882) (xy 207.772 -453.771) (xy 213.236302 -459.235302)
				(xy 215.053926 -459.235302) (xy 218.101164 -456.188064) (xy 218.101164 -450.680836) (xy 226.06 -442.722)
				(xy 236.060996 -442.722) (xy 237.28172 -441.501276) (xy 237.28172 -430.2633) (xy 234.188 -427.16958)
				(xy 234.188 -420.751) (xy 237.49 -417.449) (xy 237.49 -416.179) (xy 236.982 -415.671) (xy 204.597 -415.671)
				(xy 203.581 -414.655) (xy 203.581 -410.972) (xy 205.232 -409.321) (xy 251.079 -409.321) (xy 251.841 -408.559)
				(xy 258.572 -408.559) (xy 259.08 -408.051) (xy 259.08 -384.683) (xy 258.8768 -384.4798) (xy 249.0978 -384.4798)
				(xy 248.92 -384.6576) (xy 236.2708 -384.6576) (xy 235.6104 -383.9972) (xy 235.6104 -361.5436) (xy 237.236 -359.918)
				(xy 255.397 -359.918) (xy 259.969 -355.346) (xy 261.468108 -355.346) (xy 261.468108 -355.416104)
				(xy 262.737092 -355.416104)
				(arc
					(start 262.737092 -0.999998)
					(mid 262.667682 -0.832426)
					(end 262.50011 -0.763016)
				)
			)
		)
	)
	(zone
		(layer "B.Cu")
		(hatch none 0.5)
		(connect_pads
			(clearance 0)
		)
		(min_thickness 0.25)
		(keepout
			(tracks not_allowed)
			(vias allowed)
			(pads allowed)
			(copperpour not_allowed)
			(footprints allowed)
		)
		(placement
			(enabled no)
			(sheetname "")
		)
		(fill
			(thermal_gap 0.5)
			(thermal_bridge_width 0.5)
			(island_removal_mode 0)
		)
		(polygon
			(pts
				(arc
					(start 5.59054 -410.335222)
					(mid 5.08 -409.824682)
					(end 4.56946 -410.335222)
				)
				(xy 4.56946 -410.489146) (xy 4.784598 -410.489146)
				(arc
					(start 4.834382 -410.439362)
					(mid 5.268644 -410.146578)
					(end 4.97586 -410.58084)
				)
				(xy 4.867402 -410.689298) (xy 4.56946 -410.689298) (xy 4.56946 -410.7942) (xy 4.867656 -410.7942)
				(arc
					(start 4.97586 -410.902404)
					(mid 5.268644 -411.336666)
					(end 4.834382 -411.043882)
				)
				(xy 4.784852 -410.994352) (xy 4.56946 -410.994352)
				(arc
					(start 4.56946 -411.147768)
					(mid 5.079873 -411.658562)
					(end 5.59054 -411.148022)
				)
			)
		)
	)
	(zone
		(layer "B.Cu")
		(hatch none 0.5)
		(connect_pads
			(clearance 0)
		)
		(min_thickness 0.25)
		(keepout
			(tracks not_allowed)
			(vias allowed)
			(pads allowed)
			(copperpour not_allowed)
			(footprints allowed)
		)
		(placement
			(enabled no)
			(sheetname "")
		)
		(fill
			(thermal_gap 0.5)
			(thermal_bridge_width 0.5)
			(island_removal_mode 0)
		)
		(polygon
			(pts
				(arc
					(start 48.89754 -472.5797)
					(mid 48.387127 -472.068906)
					(end 47.87646 -472.579446)
				)
				(xy 47.87646 -472.733116) (xy 48.091852 -472.733116)
				(arc
					(start 48.141382 -472.683586)
					(mid 48.575644 -472.390802)
					(end 48.28286 -472.825064)
				)
				(xy 48.174656 -472.933268) (xy 47.87646 -472.933268) (xy 47.87646 -473.03817) (xy 48.174402 -473.03817)
				(arc
					(start 48.28286 -473.146628)
					(mid 48.575644 -473.58089)
					(end 48.141382 -473.288106)
				)
				(xy 48.091598 -473.238322) (xy 47.87646 -473.238322)
				(arc
					(start 47.87646 -473.392246)
					(mid 48.387 -473.902786)
					(end 48.89754 -473.392246)
				)
			)
		)
	)
	(zone
		(net "P12V_SSD14")
		(layer "B.Cu")
		(hatch none 0.5)
		(connect_pads
			(clearance 0.5)
		)
		(min_thickness 0.25)
		(fill yes
			(thermal_gap 0.5)
			(thermal_bridge_width 0.5)
			(island_removal_mode 0)
		)
		(polygon
			(pts
				(xy 18.6436 -12.3444) (xy 20.9042 -12.3444) (xy 21.1582 -12.0904) (xy 21.1582 -10.3378) (xy 22.098 -9.398)
				(xy 24.0538 -9.398) (xy 25.9842 -11.3284) (xy 28.6004 -11.3284) (xy 28.7274 -11.2014) (xy 28.7274 -10.7188)
				(xy 28.9814 -10.4648) (xy 29.9466 -10.4648) (xy 30.9118 -11.43) (xy 32.3342 -11.43) (xy 32.5374 -11.6332)
				(xy 32.5374 -12.1666) (xy 32.6644 -12.2936) (xy 34.6202 -12.2936) (xy 36.068 -10.8458) (xy 36.068 -9.017)
				(xy 35.56 -8.509) (xy 31.4198 -8.509) (xy 29.9212 -7.0104) (xy 25.527 -7.0104) (xy 25.273 -6.7564)
				(xy 25.273 -5.4102) (xy 24.6888 -4.826) (xy 20.066 -4.826) (xy 17.272 -7.62) (xy 17.272 -10.9728)
			)
		)
	)
	(zone
		(layer "B.Cu")
		(hatch none 0.5)
		(connect_pads
			(clearance 0)
		)
		(min_thickness 0.25)
		(keepout
			(tracks not_allowed)
			(vias allowed)
			(pads allowed)
			(copperpour not_allowed)
			(footprints allowed)
		)
		(placement
			(enabled no)
			(sheetname "")
		)
		(fill
			(thermal_gap 0.5)
			(thermal_bridge_width 0.5)
			(island_removal_mode 0)
		)
		(polygon
			(pts
				(arc
					(start 5.59054 -299.535596)
					(mid 5.080127 -299.024802)
					(end 4.56946 -299.535342)
				)
				(xy 4.56946 -299.68952) (xy 4.784344 -299.68952)
				(arc
					(start 4.834382 -299.639482)
					(mid 5.268644 -299.346698)
					(end 4.97586 -299.78096)
				)
				(xy 4.867148 -299.889672) (xy 4.56946 -299.889672) (xy 4.56946 -299.994574) (xy 4.86791 -299.994574)
				(arc
					(start 4.97586 -300.102524)
					(mid 5.268644 -300.536786)
					(end 4.834382 -300.244002)
				)
				(xy 4.785106 -300.194726) (xy 4.56946 -300.194726)
				(arc
					(start 4.56946 -300.348142)
					(mid 5.08 -300.858682)
					(end 5.59054 -300.348142)
				)
			)
		)
	)
	(zone
		(layer "B.Cu")
		(hatch none 0.5)
		(connect_pads
			(clearance 0)
		)
		(min_thickness 0.25)
		(keepout
			(tracks not_allowed)
			(vias allowed)
			(pads allowed)
			(copperpour not_allowed)
			(footprints allowed)
		)
		(placement
			(enabled no)
			(sheetname "")
		)
		(fill
			(thermal_gap 0.5)
			(thermal_bridge_width 0.5)
			(island_removal_mode 0)
		)
		(polygon
			(pts
				(arc
					(start 5.59054 -293.135558)
					(mid 5.080127 -292.624764)
					(end 4.56946 -293.135304)
				)
				(xy 4.56946 -293.289482) (xy 4.784344 -293.289482)
				(arc
					(start 4.834382 -293.239444)
					(mid 5.268644 -292.94666)
					(end 4.97586 -293.380922)
				)
				(xy 4.867148 -293.489634) (xy 4.56946 -293.489634) (xy 4.56946 -293.594536) (xy 4.86791 -293.594536)
				(arc
					(start 4.97586 -293.702486)
					(mid 5.268644 -294.136748)
					(end 4.834382 -293.843964)
				)
				(xy 4.785106 -293.794688) (xy 4.56946 -293.794688)
				(arc
					(start 4.56946 -293.948104)
					(mid 5.08 -294.458644)
					(end 5.59054 -293.948104)
				)
			)
		)
	)
	(zone
		(layer "B.Cu")
		(hatch none 0.5)
		(connect_pads
			(clearance 0)
		)
		(min_thickness 0.25)
		(keepout
			(tracks not_allowed)
			(vias allowed)
			(pads allowed)
			(copperpour not_allowed)
			(footprints allowed)
		)
		(placement
			(enabled no)
			(sheetname "")
		)
		(fill
			(thermal_gap 0.5)
			(thermal_bridge_width 0.5)
			(island_removal_mode 0)
		)
		(polygon
			(pts
				(arc
					(start 32.26054 -444.58509)
					(mid 31.750127 -444.074296)
					(end 31.23946 -444.584836)
				)
				(xy 31.23946 -444.738506) (xy 31.454852 -444.738506)
				(arc
					(start 31.504382 -444.688976)
					(mid 31.938644 -444.396192)
					(end 31.64586 -444.830454)
				)
				(xy 31.537656 -444.938658) (xy 31.23946 -444.938658) (xy 31.23946 -445.04356) (xy 31.537402 -445.04356)
				(arc
					(start 31.64586 -445.152018)
					(mid 31.938644 -445.58628)
					(end 31.504382 -445.293496)
				)
				(xy 31.454598 -445.243712) (xy 31.23946 -445.243712)
				(arc
					(start 31.23946 -445.397636)
					(mid 31.75 -445.908176)
					(end 32.26054 -445.397636)
				)
			)
		)
	)
	(zone
		(layer "B.Cu")
		(hatch none 0.5)
		(connect_pads
			(clearance 0)
		)
		(min_thickness 0.25)
		(keepout
			(tracks not_allowed)
			(vias allowed)
			(pads allowed)
			(copperpour not_allowed)
			(footprints allowed)
		)
		(placement
			(enabled no)
			(sheetname "")
		)
		(fill
			(thermal_gap 0.5)
			(thermal_bridge_width 0.5)
			(island_removal_mode 0)
		)
		(polygon
			(pts
				(arc
					(start 5.59054 -289.935666)
					(mid 5.080127 -289.424872)
					(end 4.56946 -289.935412)
				)
				(xy 4.56946 -290.089336) (xy 4.784598 -290.089336)
				(arc
					(start 4.834382 -290.039552)
					(mid 5.268644 -289.746768)
					(end 4.97586 -290.18103)
				)
				(xy 4.867402 -290.289488) (xy 4.56946 -290.289488) (xy 4.56946 -290.39439) (xy 4.867656 -290.39439)
				(arc
					(start 4.97586 -290.502594)
					(mid 5.268644 -290.936856)
					(end 4.834382 -290.644072)
				)
				(xy 4.784852 -290.594542) (xy 4.56946 -290.594542)
				(arc
					(start 4.56946 -290.748212)
					(mid 5.08 -291.258752)
					(end 5.59054 -290.748212)
				)
			)
		)
	)
	(zone
		(layer "B.Cu")
		(hatch none 0.5)
		(connect_pads
			(clearance 0)
		)
		(min_thickness 0.25)
		(keepout
			(tracks not_allowed)
			(vias allowed)
			(pads allowed)
			(copperpour not_allowed)
			(footprints allowed)
		)
		(placement
			(enabled no)
			(sheetname "")
		)
		(fill
			(thermal_gap 0.5)
			(thermal_bridge_width 0.5)
			(island_removal_mode 0)
		)
		(polygon
			(pts
				(arc
					(start 5.59054 -391.935462)
					(mid 5.080127 -391.424668)
					(end 4.56946 -391.935208)
				)
				(xy 4.56946 -392.089132) (xy 4.784598 -392.089132)
				(arc
					(start 4.834382 -392.039348)
					(mid 5.268644 -391.746564)
					(end 4.97586 -392.180826)
				)
				(xy 4.867402 -392.289284) (xy 4.56946 -392.289284) (xy 4.56946 -392.394186) (xy 4.867656 -392.394186)
				(arc
					(start 4.97586 -392.50239)
					(mid 5.268644 -392.936652)
					(end 4.834382 -392.643868)
				)
				(xy 4.784852 -392.594338) (xy 4.56946 -392.594338)
				(arc
					(start 4.56946 -392.748008)
					(mid 5.08 -393.258548)
					(end 5.59054 -392.748008)
				)
			)
		)
	)
	(zone
		(layer "B.Cu")
		(hatch none 0.5)
		(connect_pads
			(clearance 0)
		)
		(min_thickness 0.25)
		(keepout
			(tracks not_allowed)
			(vias allowed)
			(pads allowed)
			(copperpour not_allowed)
			(footprints allowed)
		)
		(placement
			(enabled no)
			(sheetname "")
		)
		(fill
			(thermal_gap 0.5)
			(thermal_bridge_width 0.5)
			(island_removal_mode 0)
		)
		(polygon
			(pts
				(arc
					(start 5.59054 -416.735514)
					(mid 5.080127 -416.22472)
					(end 4.56946 -416.73526)
				)
				(xy 4.56946 -416.889184) (xy 4.784598 -416.889184)
				(arc
					(start 4.834382 -416.8394)
					(mid 5.268644 -416.546616)
					(end 4.97586 -416.980878)
				)
				(xy 4.867402 -417.089336) (xy 4.56946 -417.089336) (xy 4.56946 -417.194238) (xy 4.867656 -417.194238)
				(arc
					(start 4.97586 -417.302442)
					(mid 5.268644 -417.736704)
					(end 4.834382 -417.44392)
				)
				(xy 4.784852 -417.39439) (xy 4.56946 -417.39439)
				(arc
					(start 4.56946 -417.54806)
					(mid 5.08 -418.0586)
					(end 5.59054 -417.54806)
				)
			)
		)
	)
	(zone
		(layer "B.Cu")
		(hatch none 0.5)
		(connect_pads
			(clearance 0)
		)
		(min_thickness 0.25)
		(keepout
			(tracks not_allowed)
			(vias allowed)
			(pads allowed)
			(copperpour not_allowed)
			(footprints allowed)
		)
		(placement
			(enabled no)
			(sheetname "")
		)
		(fill
			(thermal_gap 0.5)
			(thermal_bridge_width 0.5)
			(island_removal_mode 0)
		)
		(polygon
			(pts
				(xy 1.022096 -458.59573) (xy 3.758184 -458.59573) (xy 3.81 -458.647546) (xy 3.81 -458.839062) (xy 3.761232 -458.88783)
				(xy 1.025398 -458.88783) (xy 1.014984 -458.898244) (xy 1.010158 -458.898244) (xy 1.005332 -458.893418)
				(xy 1.005332 -458.877162) (xy 1.005332 -458.606398) (xy 1.005332 -458.590904) (xy 1.007872 -458.588364)
				(xy 1.01473 -458.588364)
			)
		)
	)
	(zone
		(layer "B.Cu")
		(hatch none 0.5)
		(connect_pads
			(clearance 0)
		)
		(min_thickness 0.25)
		(keepout
			(tracks not_allowed)
			(vias allowed)
			(pads allowed)
			(copperpour not_allowed)
			(footprints allowed)
		)
		(placement
			(enabled no)
			(sheetname "")
		)
		(fill
			(thermal_gap 0.5)
			(thermal_bridge_width 0.5)
			(island_removal_mode 0)
		)
		(polygon
			(pts
				(arc
					(start 5.59054 -326.735694)
					(mid 5.080127 -326.2249)
					(end 4.56946 -326.73544)
				)
				(xy 4.56946 -326.889364) (xy 4.784598 -326.889364)
				(arc
					(start 4.834382 -326.83958)
					(mid 5.268644 -326.546796)
					(end 4.97586 -326.981058)
				)
				(xy 4.867402 -327.089516) (xy 4.56946 -327.089516) (xy 4.56946 -327.194418) (xy 4.867656 -327.194418)
				(arc
					(start 4.97586 -327.302622)
					(mid 5.268644 -327.736884)
					(end 4.834382 -327.4441)
				)
				(xy 4.784852 -327.39457) (xy 4.56946 -327.39457)
				(arc
					(start 4.56946 -327.54824)
					(mid 5.08 -328.05878)
					(end 5.59054 -327.54824)
				)
			)
		)
	)
	(zone
		(layer "B.Cu")
		(hatch none 0.5)
		(connect_pads
			(clearance 0)
		)
		(min_thickness 0.25)
		(keepout
			(tracks not_allowed)
			(vias allowed)
			(pads allowed)
			(copperpour not_allowed)
			(footprints allowed)
		)
		(placement
			(enabled no)
			(sheetname "")
		)
		(fill
			(thermal_gap 0.5)
			(thermal_bridge_width 0.5)
			(island_removal_mode 0)
		)
		(polygon
			(pts
				(arc
					(start 5.59054 -441.535312)
					(mid 5.08 -441.024772)
					(end 4.56946 -441.535312)
				)
				(xy 4.56946 -441.68949) (xy 4.784344 -441.68949)
				(arc
					(start 4.834382 -441.639452)
					(mid 5.268644 -441.346668)
					(end 4.97586 -441.78093)
				)
				(xy 4.867148 -441.889642) (xy 4.56946 -441.889642) (xy 4.56946 -441.994544) (xy 4.86791 -441.994544)
				(arc
					(start 4.97586 -442.102494)
					(mid 5.268644 -442.536756)
					(end 4.834382 -442.243972)
				)
				(xy 4.785106 -442.194696) (xy 4.56946 -442.194696)
				(arc
					(start 4.56946 -442.347858)
					(mid 5.079873 -442.858652)
					(end 5.59054 -442.348112)
				)
			)
		)
	)
	(zone
		(net "P3V3")
		(layer "B.Cu")
		(hatch none 0.5)
		(connect_pads
			(clearance 0.5)
		)
		(min_thickness 0.25)
		(fill yes
			(thermal_gap 0.5)
			(thermal_bridge_width 0.5)
			(island_removal_mode 0)
		)
		(polygon
			(pts
				(xy 258.826 -412.496) (xy 251.587 -412.496) (xy 250.19 -411.099) (xy 204.851 -411.099) (xy 204.597 -411.353)
				(xy 204.597 -414.655) (xy 204.851 -414.909) (xy 258.826 -414.909) (xy 259.08 -414.655) (xy 259.08 -412.75)
			)
		)
	)
	(zone
		(layer "B.Cu")
		(hatch none 0.5)
		(connect_pads
			(clearance 0)
		)
		(min_thickness 0.25)
		(keepout
			(tracks not_allowed)
			(vias allowed)
			(pads allowed)
			(copperpour not_allowed)
			(footprints allowed)
		)
		(placement
			(enabled no)
			(sheetname "")
		)
		(fill
			(thermal_gap 0.5)
			(thermal_bridge_width 0.5)
			(island_removal_mode 0)
		)
		(polygon
			(pts
				(arc
					(start 5.59054 -173.535594)
					(mid 5.080127 -173.0248)
					(end 4.56946 -173.53534)
				)
				(xy 4.56946 -173.689518) (xy 4.784344 -173.689518)
				(arc
					(start 4.834382 -173.63948)
					(mid 5.268644 -173.346696)
					(end 4.97586 -173.780958)
				)
				(xy 4.867148 -173.88967) (xy 4.56946 -173.88967) (xy 4.56946 -173.994572) (xy 4.86791 -173.994572)
				(arc
					(start 4.97586 -174.102522)
					(mid 5.268644 -174.536784)
					(end 4.834382 -174.244)
				)
				(xy 4.785106 -174.194724) (xy 4.56946 -174.194724)
				(arc
					(start 4.56946 -174.34814)
					(mid 5.08 -174.85868)
					(end 5.59054 -174.34814)
				)
			)
		)
	)
	(zone
		(layer "B.Cu")
		(hatch none 0.5)
		(connect_pads
			(clearance 0)
		)
		(min_thickness 0.25)
		(keepout
			(tracks not_allowed)
			(vias allowed)
			(pads allowed)
			(copperpour not_allowed)
			(footprints allowed)
		)
		(placement
			(enabled no)
			(sheetname "")
		)
		(fill
			(thermal_gap 0.5)
			(thermal_bridge_width 0.5)
			(island_removal_mode 0)
		)
		(polygon
			(pts
				(arc
					(start 5.59054 -423.135552)
					(mid 5.080127 -422.624758)
					(end 4.56946 -423.135298)
				)
				(xy 4.56946 -423.289476) (xy 4.784344 -423.289476)
				(arc
					(start 4.834382 -423.239438)
					(mid 5.268644 -422.946654)
					(end 4.97586 -423.380916)
				)
				(xy 4.867148 -423.489628) (xy 4.56946 -423.489628) (xy 4.56946 -423.59453) (xy 4.86791 -423.59453)
				(arc
					(start 4.97586 -423.70248)
					(mid 5.268644 -424.136742)
					(end 4.834382 -423.843958)
				)
				(xy 4.785106 -423.794682) (xy 4.56946 -423.794682)
				(arc
					(start 4.56946 -423.948098)
					(mid 5.08 -424.458638)
					(end 5.59054 -423.948098)
				)
			)
		)
	)
	(zone
		(layer "B.Cu")
		(hatch none 0.5)
		(connect_pads
			(clearance 0)
		)
		(min_thickness 0.25)
		(keepout
			(tracks not_allowed)
			(vias allowed)
			(pads allowed)
			(copperpour not_allowed)
			(footprints allowed)
		)
		(placement
			(enabled no)
			(sheetname "")
		)
		(fill
			(thermal_gap 0.5)
			(thermal_bridge_width 0.5)
			(island_removal_mode 0)
		)
		(polygon
			(pts
				(arc
					(start 5.59054 -157.535626)
					(mid 5.080127 -157.024832)
					(end 4.56946 -157.535372)
				)
				(xy 4.56946 -157.68955) (xy 4.784344 -157.68955)
				(arc
					(start 4.834382 -157.639512)
					(mid 5.268644 -157.346728)
					(end 4.97586 -157.78099)
				)
				(xy 4.867148 -157.889702) (xy 4.56946 -157.889702) (xy 4.56946 -157.994604) (xy 4.86791 -157.994604)
				(arc
					(start 4.97586 -158.102554)
					(mid 5.268644 -158.536816)
					(end 4.834382 -158.244032)
				)
				(xy 4.785106 -158.194756) (xy 4.56946 -158.194756)
				(arc
					(start 4.56946 -158.348172)
					(mid 5.08 -158.858712)
					(end 5.59054 -158.348172)
				)
			)
		)
	)
	(zone
		(layer "B.Cu")
		(hatch none 0.5)
		(connect_pads
			(clearance 0)
		)
		(min_thickness 0.25)
		(keepout
			(tracks not_allowed)
			(vias allowed)
			(pads allowed)
			(copperpour not_allowed)
			(footprints allowed)
		)
		(placement
			(enabled no)
			(sheetname "")
		)
		(fill
			(thermal_gap 0.5)
			(thermal_bridge_width 0.5)
			(island_removal_mode 0)
		)
		(polygon
			(pts
				(arc
					(start 5.59054 -194.335654)
					(mid 5.080127 -193.82486)
					(end 4.56946 -194.3354)
				)
				(xy 4.56946 -194.489324) (xy 4.784598 -194.489324)
				(arc
					(start 4.834382 -194.43954)
					(mid 5.268644 -194.146756)
					(end 4.97586 -194.581018)
				)
				(xy 4.867402 -194.689476) (xy 4.56946 -194.689476) (xy 4.56946 -194.794378) (xy 4.867656 -194.794378)
				(arc
					(start 4.97586 -194.902582)
					(mid 5.268644 -195.336844)
					(end 4.834382 -195.04406)
				)
				(xy 4.784852 -194.99453) (xy 4.56946 -194.99453)
				(arc
					(start 4.56946 -195.1482)
					(mid 5.08 -195.65874)
					(end 5.59054 -195.1482)
				)
			)
		)
	)
	(zone
		(layer "B.Cu")
		(hatch none 0.5)
		(connect_pads
			(clearance 0)
		)
		(min_thickness 0.25)
		(keepout
			(tracks not_allowed)
			(vias allowed)
			(pads allowed)
			(copperpour not_allowed)
			(footprints allowed)
		)
		(placement
			(enabled no)
			(sheetname "")
		)
		(fill
			(thermal_gap 0.5)
			(thermal_bridge_width 0.5)
			(island_removal_mode 0)
		)
		(polygon
			(pts
				(xy 1.022096 -464.995768) (xy 3.758184 -464.995768) (xy 3.81 -465.047584) (xy 3.81 -465.2391) (xy 3.761232 -465.287868)
				(xy 1.025398 -465.287868) (xy 1.014984 -465.298282) (xy 1.010158 -465.298282) (xy 1.005332 -465.293456)
				(xy 1.005332 -465.2772) (xy 1.005332 -465.006436) (xy 1.005332 -464.990942) (xy 1.007872 -464.988402)
				(xy 1.01473 -464.988402)
			)
		)
	)
	(zone
		(layer "B.Cu")
		(hatch none 0.5)
		(connect_pads
			(clearance 0)
		)
		(min_thickness 0.25)
		(keepout
			(tracks not_allowed)
			(vias allowed)
			(pads allowed)
			(copperpour not_allowed)
			(footprints allowed)
		)
		(placement
			(enabled no)
			(sheetname "")
		)
		(fill
			(thermal_gap 0.5)
			(thermal_bridge_width 0.5)
			(island_removal_mode 0)
		)
		(polygon
			(pts
				(arc
					(start 5.59054 -388.73557)
					(mid 5.080127 -388.224776)
					(end 4.56946 -388.735316)
				)
				(xy 4.56946 -388.88924) (xy 4.784598 -388.88924)
				(arc
					(start 4.834382 -388.839456)
					(mid 5.268644 -388.546672)
					(end 4.97586 -388.980934)
				)
				(xy 4.867402 -389.089392) (xy 4.56946 -389.089392) (xy 4.56946 -389.194294) (xy 4.867656 -389.194294)
				(arc
					(start 4.97586 -389.302498)
					(mid 5.268644 -389.73676)
					(end 4.834382 -389.443976)
				)
				(xy 4.784852 -389.394446) (xy 4.56946 -389.394446)
				(arc
					(start 4.56946 -389.548116)
					(mid 5.08 -390.058656)
					(end 5.59054 -389.548116)
				)
			)
		)
	)
	(zone
		(layer "B.Cu")
		(hatch none 0.5)
		(connect_pads
			(clearance 0)
		)
		(min_thickness 0.25)
		(keepout
			(tracks not_allowed)
			(vias allowed)
			(pads allowed)
			(copperpour not_allowed)
			(footprints allowed)
		)
		(placement
			(enabled no)
			(sheetname "")
		)
		(fill
			(thermal_gap 0.5)
			(thermal_bridge_width 0.5)
			(island_removal_mode 0)
		)
		(polygon
			(pts
				(arc
					(start 5.59054 -444.735204)
					(mid 5.08 -444.224664)
					(end 4.56946 -444.735204)
				)
				(xy 4.56946 -444.888874) (xy 4.784852 -444.888874)
				(arc
					(start 4.834382 -444.839344)
					(mid 5.268644 -444.54656)
					(end 4.97586 -444.980822)
				)
				(xy 4.867656 -445.089026) (xy 4.56946 -445.089026) (xy 4.56946 -445.193928) (xy 4.867402 -445.193928)
				(arc
					(start 4.97586 -445.302386)
					(mid 5.268644 -445.736648)
					(end 4.834382 -445.443864)
				)
				(xy 4.784598 -445.39408) (xy 4.56946 -445.39408)
				(arc
					(start 4.56946 -445.54775)
					(mid 5.079873 -446.058544)
					(end 5.59054 -445.548004)
				)
			)
		)
	)
	(zone
		(layer "B.Cu")
		(hatch none 0.5)
		(connect_pads
			(clearance 0)
		)
		(min_thickness 0.25)
		(keepout
			(tracks not_allowed)
			(vias allowed)
			(pads allowed)
			(copperpour not_allowed)
			(footprints allowed)
		)
		(placement
			(enabled no)
			(sheetname "")
		)
		(fill
			(thermal_gap 0.5)
			(thermal_bridge_width 0.5)
			(island_removal_mode 0)
		)
		(polygon
			(pts
				(arc
					(start 5.59054 -283.535628)
					(mid 5.080127 -283.024834)
					(end 4.56946 -283.535374)
				)
				(xy 4.56946 -283.689552) (xy 4.784344 -283.689552)
				(arc
					(start 4.834382 -283.639514)
					(mid 5.268644 -283.34673)
					(end 4.97586 -283.780992)
				)
				(xy 4.867148 -283.889704) (xy 4.56946 -283.889704) (xy 4.56946 -283.994606) (xy 4.86791 -283.994606)
				(arc
					(start 4.97586 -284.102556)
					(mid 5.268644 -284.536818)
					(end 4.834382 -284.244034)
				)
				(xy 4.785106 -284.194758) (xy 4.56946 -284.194758)
				(arc
					(start 4.56946 -284.348174)
					(mid 5.08 -284.858714)
					(end 5.59054 -284.348174)
				)
			)
		)
	)
	(zone
		(layer "B.Cu")
		(hatch none 0.5)
		(connect_pads
			(clearance 0)
		)
		(min_thickness 0.25)
		(keepout
			(tracks not_allowed)
			(vias allowed)
			(pads allowed)
			(copperpour not_allowed)
			(footprints allowed)
		)
		(placement
			(enabled no)
			(sheetname "")
		)
		(fill
			(thermal_gap 0.5)
			(thermal_bridge_width 0.5)
			(island_removal_mode 0)
		)
		(polygon
			(pts
				(arc
					(start 5.59054 -329.935586)
					(mid 5.080127 -329.424792)
					(end 4.56946 -329.935332)
				)
				(xy 4.56946 -330.08951) (xy 4.784344 -330.08951)
				(arc
					(start 4.834382 -330.039472)
					(mid 5.268644 -329.746688)
					(end 4.97586 -330.18095)
				)
				(xy 4.867148 -330.289662) (xy 4.56946 -330.289662) (xy 4.56946 -330.394564) (xy 4.86791 -330.394564)
				(arc
					(start 4.97586 -330.502514)
					(mid 5.268644 -330.936776)
					(end 4.834382 -330.643992)
				)
				(xy 4.785106 -330.594716) (xy 4.56946 -330.594716)
				(arc
					(start 4.56946 -330.748132)
					(mid 5.08 -331.258672)
					(end 5.59054 -330.748132)
				)
			)
		)
	)
	(zone
		(layer "B.Cu")
		(hatch none 0.5)
		(connect_pads
			(clearance 0)
		)
		(min_thickness 0.25)
		(keepout
			(tracks not_allowed)
			(vias allowed)
			(pads allowed)
			(copperpour not_allowed)
			(footprints allowed)
		)
		(placement
			(enabled no)
			(sheetname "")
		)
		(fill
			(thermal_gap 0.5)
			(thermal_bridge_width 0.5)
			(island_removal_mode 0)
		)
		(polygon
			(pts
				(arc
					(start 42.92854 -238.58474)
					(mid 42.418127 -238.073946)
					(end 41.90746 -238.584486)
				)
				(xy 41.90746 -238.738156) (xy 42.122852 -238.738156)
				(arc
					(start 42.172382 -238.688626)
					(mid 42.606644 -238.395842)
					(end 42.31386 -238.830104)
				)
				(xy 42.205656 -238.938308) (xy 41.90746 -238.938308) (xy 41.90746 -239.04321) (xy 42.205402 -239.04321)
				(arc
					(start 42.31386 -239.151668)
					(mid 42.606644 -239.58593)
					(end 42.172382 -239.293146)
				)
				(xy 42.122598 -239.243362) (xy 41.90746 -239.243362)
				(arc
					(start 41.90746 -239.397286)
					(mid 42.418 -239.907826)
					(end 42.92854 -239.397286)
				)
			)
		)
	)
	(zone
		(layer "B.Cu")
		(hatch none 0.5)
		(connect_pads
			(clearance 0)
		)
		(min_thickness 0.25)
		(keepout
			(tracks not_allowed)
			(vias allowed)
			(pads allowed)
			(copperpour not_allowed)
			(footprints allowed)
		)
		(placement
			(enabled no)
			(sheetname "")
		)
		(fill
			(thermal_gap 0.5)
			(thermal_bridge_width 0.5)
			(island_removal_mode 0)
		)
		(polygon
			(pts
				(arc
					(start 5.59054 -209.535776)
					(mid 5.080127 -209.024982)
					(end 4.56946 -209.535522)
				)
				(xy 4.56946 -209.689446) (xy 4.784598 -209.689446)
				(arc
					(start 4.834382 -209.639662)
					(mid 5.268644 -209.346878)
					(end 4.97586 -209.78114)
				)
				(xy 4.867402 -209.889598) (xy 4.56946 -209.889598) (xy 4.56946 -209.9945) (xy 4.867656 -209.9945)
				(arc
					(start 4.97586 -210.102704)
					(mid 5.268644 -210.536966)
					(end 4.834382 -210.244182)
				)
				(xy 4.784852 -210.194652) (xy 4.56946 -210.194652)
				(arc
					(start 4.56946 -210.348322)
					(mid 5.08 -210.858862)
					(end 5.59054 -210.348322)
				)
			)
		)
	)
	(zone
		(layer "B.Cu")
		(hatch none 0.5)
		(connect_pads
			(clearance 0)
		)
		(min_thickness 0.25)
		(keepout
			(tracks not_allowed)
			(vias allowed)
			(pads allowed)
			(copperpour not_allowed)
			(footprints allowed)
		)
		(placement
			(enabled no)
			(sheetname "")
		)
		(fill
			(thermal_gap 0.5)
			(thermal_bridge_width 0.5)
			(island_removal_mode 0)
		)
		(polygon
			(pts
				(arc
					(start 5.59054 -296.335704)
					(mid 5.080127 -295.82491)
					(end 4.56946 -296.33545)
				)
				(xy 4.56946 -296.489374) (xy 4.784598 -296.489374)
				(arc
					(start 4.834382 -296.43959)
					(mid 5.268644 -296.146806)
					(end 4.97586 -296.581068)
				)
				(xy 4.867402 -296.689526) (xy 4.56946 -296.689526) (xy 4.56946 -296.794428) (xy 4.867656 -296.794428)
				(arc
					(start 4.97586 -296.902632)
					(mid 5.268644 -297.336894)
					(end 4.834382 -297.04411)
				)
				(xy 4.784852 -296.99458) (xy 4.56946 -296.99458)
				(arc
					(start 4.56946 -297.14825)
					(mid 5.08 -297.65879)
					(end 5.59054 -297.14825)
				)
			)
		)
	)
	(zone
		(layer "B.Cu")
		(hatch none 0.5)
		(connect_pads
			(clearance 0)
		)
		(min_thickness 0.25)
		(keepout
			(tracks not_allowed)
			(vias allowed)
			(pads allowed)
			(copperpour not_allowed)
			(footprints allowed)
		)
		(placement
			(enabled no)
			(sheetname "")
		)
		(fill
			(thermal_gap 0.5)
			(thermal_bridge_width 0.5)
			(island_removal_mode 0)
		)
		(polygon
			(pts
				(arc
					(start 5.59054 -407.135076)
					(mid 5.08 -406.624536)
					(end 4.56946 -407.135076)
				)
				(xy 4.56946 -407.289254) (xy 4.784344 -407.289254)
				(arc
					(start 4.834382 -407.239216)
					(mid 5.268644 -406.946432)
					(end 4.97586 -407.380694)
				)
				(xy 4.867148 -407.489406) (xy 4.56946 -407.489406) (xy 4.56946 -407.594308) (xy 4.86791 -407.594308)
				(arc
					(start 4.97586 -407.702258)
					(mid 5.268644 -408.13652)
					(end 4.834382 -407.843736)
				)
				(xy 4.785106 -407.79446) (xy 4.56946 -407.79446)
				(arc
					(start 4.56946 -407.947622)
					(mid 5.079873 -408.458416)
					(end 5.59054 -407.947876)
				)
			)
		)
	)
	(zone
		(net "GND")
		(layer "B.Cu")
		(hatch none 0.5)
		(connect_pads
			(clearance 0.5)
		)
		(min_thickness 0.25)
		(fill yes
			(thermal_gap 0.5)
			(thermal_bridge_width 0.5)
			(island_removal_mode 0)
		)
		(polygon
			(pts
				(xy 37.084 -186.563) (xy 24.892 -186.563) (xy 11.43 -200.025) (xy 11.43 -206.502) (xy 12.192 -207.264)
				(xy 13.081 -207.264) (xy 19.5072 -200.8378) (xy 19.5072 -197.0024) (xy 19.9898 -196.5198) (xy 20.828 -196.5198)
				(xy 21.2598 -196.9516) (xy 21.2598 -197.6882) (xy 21.5392 -197.9676) (xy 36.8554 -197.9676) (xy 38.354 -196.469)
				(xy 38.354 -186.309) (xy 38.227 -186.182) (xy 37.465 -186.182)
			)
		)
	)
	(zone
		(layer "B.Cu")
		(hatch none 0.5)
		(connect_pads
			(clearance 0)
		)
		(min_thickness 0.25)
		(keepout
			(tracks not_allowed)
			(vias allowed)
			(pads allowed)
			(copperpour not_allowed)
			(footprints allowed)
		)
		(placement
			(enabled no)
			(sheetname "")
		)
		(fill
			(thermal_gap 0.5)
			(thermal_bridge_width 0.5)
			(island_removal_mode 0)
		)
		(polygon
			(pts
				(arc
					(start 5.59054 -413.535114)
					(mid 5.08 -413.024574)
					(end 4.56946 -413.535114)
				)
				(xy 4.56946 -413.689292) (xy 4.784344 -413.689292)
				(arc
					(start 4.834382 -413.639254)
					(mid 5.268644 -413.34647)
					(end 4.97586 -413.780732)
				)
				(xy 4.867148 -413.889444) (xy 4.56946 -413.889444) (xy 4.56946 -413.994346) (xy 4.86791 -413.994346)
				(arc
					(start 4.97586 -414.102296)
					(mid 5.268644 -414.536558)
					(end 4.834382 -414.243774)
				)
				(xy 4.785106 -414.194498) (xy 4.56946 -414.194498)
				(arc
					(start 4.56946 -414.34766)
					(mid 5.079873 -414.858454)
					(end 5.59054 -414.347914)
				)
			)
		)
	)
	(zone
		(layer "B.Cu")
		(hatch none 0.5)
		(connect_pads
			(clearance 0)
		)
		(min_thickness 0.25)
		(keepout
			(tracks not_allowed)
			(vias allowed)
			(pads allowed)
			(copperpour not_allowed)
			(footprints allowed)
		)
		(placement
			(enabled no)
			(sheetname "")
		)
		(fill
			(thermal_gap 0.5)
			(thermal_bridge_width 0.5)
			(island_removal_mode 0)
		)
		(polygon
			(pts
				(arc
					(start 233.897424 -369.579398)
					(mid 233.386884 -369.068858)
					(end 232.876344 -369.579398)
				)
				(xy 232.876344 -369.733068) (xy 233.091736 -369.733068)
				(arc
					(start 233.141266 -369.683538)
					(mid 233.575528 -369.390754)
					(end 233.282744 -369.825016)
				)
				(xy 233.17454 -369.93322) (xy 232.876344 -369.93322) (xy 232.876344 -370.038122) (xy 233.174286 -370.038122)
				(arc
					(start 233.282744 -370.14658)
					(mid 233.575528 -370.580842)
					(end 233.141266 -370.288058)
				)
				(xy 233.091482 -370.238274) (xy 232.876344 -370.238274)
				(arc
					(start 232.876344 -370.391944)
					(mid 233.386757 -370.902738)
					(end 233.897424 -370.392198)
				)
			)
		)
	)
	(zone
		(layer "B.Cu")
		(hatch none 0.5)
		(connect_pads
			(clearance 0)
		)
		(min_thickness 0.25)
		(keepout
			(tracks not_allowed)
			(vias allowed)
			(pads allowed)
			(copperpour not_allowed)
			(footprints allowed)
		)
		(placement
			(enabled no)
			(sheetname "")
		)
		(fill
			(thermal_gap 0.5)
			(thermal_bridge_width 0.5)
			(island_removal_mode 0)
		)
		(polygon
			(pts
				(arc
					(start 257.50012 -271.497552)
					(mid 253.500128 -267.49756)
					(end 249.499882 -271.497552)
				)
				(arc
					(start 249.499882 -274.997418)
					(mid 253.500128 -278.997664)
					(end 257.50012 -274.997418)
				)
			)
		)
	)
	(zone
		(layer "B.Cu")
		(hatch none 0.5)
		(connect_pads
			(clearance 0)
		)
		(min_thickness 0.25)
		(keepout
			(tracks allowed)
			(vias allowed)
			(pads allowed)
			(copperpour allowed)
			(footprints allowed)
		)
		(placement
			(enabled no)
			(sheetname "")
		)
		(fill
			(thermal_gap 0.5)
			(thermal_bridge_width 0.5)
			(island_removal_mode 0)
		)
		(polygon
			(pts
				(xy 1.524 -189.992) (xy 1.524 -234.696) (xy 7.239 -234.696) (xy 7.239 -189.992)
			)
		)
	)
	(zone
		(layer "B.Cu")
		(hatch none 0.5)
		(connect_pads
			(clearance 0)
		)
		(min_thickness 0.25)
		(keepout
			(tracks not_allowed)
			(vias allowed)
			(pads allowed)
			(copperpour not_allowed)
			(footprints allowed)
		)
		(placement
			(enabled no)
			(sheetname "")
		)
		(fill
			(thermal_gap 0.5)
			(thermal_bridge_width 0.5)
			(island_removal_mode 0)
		)
		(polygon
			(pts
				(arc
					(start 32.00654 -32.60344)
					(mid 31.496127 -32.092646)
					(end 30.98546 -32.603186)
				)
				(xy 30.98546 -32.756856) (xy 31.200852 -32.756856)
				(arc
					(start 31.250382 -32.707326)
					(mid 31.684644 -32.414542)
					(end 31.39186 -32.848804)
				)
				(xy 31.283656 -32.957008) (xy 30.98546 -32.957008) (xy 30.98546 -33.06191) (xy 31.283402 -33.06191)
				(arc
					(start 31.39186 -33.170368)
					(mid 31.684644 -33.60463)
					(end 31.250382 -33.311846)
				)
				(xy 31.200598 -33.262062) (xy 30.98546 -33.262062)
				(arc
					(start 30.98546 -33.415986)
					(mid 31.496 -33.926526)
					(end 32.00654 -33.415986)
				)
			)
		)
	)
	(zone
		(layer "B.Cu")
		(hatch none 0.5)
		(connect_pads
			(clearance 0)
		)
		(min_thickness 0.25)
		(keepout
			(tracks not_allowed)
			(vias allowed)
			(pads allowed)
			(copperpour not_allowed)
			(footprints allowed)
		)
		(placement
			(enabled no)
			(sheetname "")
		)
		(fill
			(thermal_gap 0.5)
			(thermal_bridge_width 0.5)
			(island_removal_mode 0)
		)
		(polygon
			(pts
				(arc
					(start 5.59054 -167.135556)
					(mid 5.080127 -166.624762)
					(end 4.56946 -167.135302)
				)
				(xy 4.56946 -167.28948) (xy 4.784344 -167.28948)
				(arc
					(start 4.834382 -167.239442)
					(mid 5.268644 -166.946658)
					(end 4.97586 -167.38092)
				)
				(xy 4.867148 -167.489632) (xy 4.56946 -167.489632) (xy 4.56946 -167.594534) (xy 4.86791 -167.594534)
				(arc
					(start 4.97586 -167.702484)
					(mid 5.268644 -168.136746)
					(end 4.834382 -167.843962)
				)
				(xy 4.785106 -167.794686) (xy 4.56946 -167.794686)
				(arc
					(start 4.56946 -167.948102)
					(mid 5.08 -168.458642)
					(end 5.59054 -167.948102)
				)
			)
		)
	)
	(zone
		(layer "B.Cu")
		(hatch none 0.5)
		(connect_pads
			(clearance 0)
		)
		(min_thickness 0.25)
		(keepout
			(tracks not_allowed)
			(vias allowed)
			(pads allowed)
			(copperpour not_allowed)
			(footprints allowed)
		)
		(placement
			(enabled no)
			(sheetname "")
		)
		(fill
			(thermal_gap 0.5)
			(thermal_bridge_width 0.5)
			(island_removal_mode 0)
		)
		(polygon
			(pts
				(arc
					(start 5.59054 -398.3355)
					(mid 5.080127 -397.824706)
					(end 4.56946 -398.335246)
				)
				(xy 4.56946 -398.48917) (xy 4.784598 -398.48917)
				(arc
					(start 4.834382 -398.439386)
					(mid 5.268644 -398.146602)
					(end 4.97586 -398.580864)
				)
				(xy 4.867402 -398.689322) (xy 4.56946 -398.689322) (xy 4.56946 -398.794224) (xy 4.867656 -398.794224)
				(arc
					(start 4.97586 -398.902428)
					(mid 5.268644 -399.33669)
					(end 4.834382 -399.043906)
				)
				(xy 4.784852 -398.994376) (xy 4.56946 -398.994376)
				(arc
					(start 4.56946 -399.148046)
					(mid 5.08 -399.658586)
					(end 5.59054 -399.148046)
				)
			)
		)
	)
	(zone
		(layer "B.Cu")
		(hatch none 0.5)
		(connect_pads
			(clearance 0)
		)
		(min_thickness 0.25)
		(keepout
			(tracks not_allowed)
			(vias allowed)
			(pads allowed)
			(copperpour not_allowed)
			(footprints allowed)
		)
		(placement
			(enabled no)
			(sheetname "")
		)
		(fill
			(thermal_gap 0.5)
			(thermal_bridge_width 0.5)
			(island_removal_mode 0)
		)
		(polygon
			(pts
				(arc
					(start 5.59054 -348.3356)
					(mid 5.080127 -347.824806)
					(end 4.56946 -348.335346)
				)
				(xy 4.56946 -348.489524) (xy 4.784344 -348.489524)
				(arc
					(start 4.834382 -348.439486)
					(mid 5.268644 -348.146702)
					(end 4.97586 -348.580964)
				)
				(xy 4.867148 -348.689676) (xy 4.56946 -348.689676) (xy 4.56946 -348.794578) (xy 4.86791 -348.794578)
				(arc
					(start 4.97586 -348.902528)
					(mid 5.268644 -349.33679)
					(end 4.834382 -349.044006)
				)
				(xy 4.785106 -348.99473) (xy 4.56946 -348.99473)
				(arc
					(start 4.56946 -349.148146)
					(mid 5.08 -349.658686)
					(end 5.59054 -349.148146)
				)
			)
		)
	)
	(zone
		(layer "B.Cu")
		(hatch none 0.5)
		(connect_pads
			(clearance 0)
		)
		(min_thickness 0.25)
		(keepout
			(tracks not_allowed)
			(vias allowed)
			(pads allowed)
			(copperpour not_allowed)
			(footprints allowed)
		)
		(placement
			(enabled no)
			(sheetname "")
		)
		(fill
			(thermal_gap 0.5)
			(thermal_bridge_width 0.5)
			(island_removal_mode 0)
		)
		(polygon
			(pts
				(arc
					(start 5.59054 -228.735636)
					(mid 5.080127 -228.224842)
					(end 4.56946 -228.735382)
				)
				(xy 4.56946 -228.889306) (xy 4.784598 -228.889306)
				(arc
					(start 4.834382 -228.839522)
					(mid 5.268644 -228.546738)
					(end 4.97586 -228.981)
				)
				(xy 4.867402 -229.089458) (xy 4.56946 -229.089458) (xy 4.56946 -229.19436) (xy 4.867656 -229.19436)
				(arc
					(start 4.97586 -229.302564)
					(mid 5.268644 -229.736826)
					(end 4.834382 -229.444042)
				)
				(xy 4.784852 -229.394512) (xy 4.56946 -229.394512)
				(arc
					(start 4.56946 -229.548182)
					(mid 5.08 -230.058722)
					(end 5.59054 -229.548182)
				)
			)
		)
	)
	(zone
		(layer "B.Cu")
		(hatch none 0.5)
		(connect_pads
			(clearance 0)
		)
		(min_thickness 0.25)
		(keepout
			(tracks not_allowed)
			(vias allowed)
			(pads allowed)
			(copperpour not_allowed)
			(footprints allowed)
		)
		(placement
			(enabled no)
			(sheetname "")
		)
		(fill
			(thermal_gap 0.5)
			(thermal_bridge_width 0.5)
			(island_removal_mode 0)
		)
		(polygon
			(pts
				(arc
					(start 233.897424 -163.579302)
					(mid 233.386884 -163.068762)
					(end 232.876344 -163.579302)
				)
				(xy 232.876344 -163.732972) (xy 233.091736 -163.732972)
				(arc
					(start 233.141266 -163.683442)
					(mid 233.575528 -163.390658)
					(end 233.282744 -163.82492)
				)
				(xy 233.17454 -163.933124) (xy 232.876344 -163.933124) (xy 232.876344 -164.038026) (xy 233.174286 -164.038026)
				(arc
					(start 233.282744 -164.146484)
					(mid 233.575528 -164.580746)
					(end 233.141266 -164.287962)
				)
				(xy 233.091482 -164.238178) (xy 232.876344 -164.238178)
				(arc
					(start 232.876344 -164.391848)
					(mid 233.386757 -164.902642)
					(end 233.897424 -164.392102)
				)
			)
		)
	)
	(zone
		(net "GND")
		(layer "B.Cu")
		(hatch none 0.5)
		(connect_pads
			(clearance 0.5)
		)
		(min_thickness 0.25)
		(fill yes
			(thermal_gap 0.5)
			(thermal_bridge_width 0.5)
			(island_removal_mode 0)
		)
		(polygon
			(pts
				(xy 22.479 -268.605) (xy 25.4 -268.605) (xy 26.393902 -267.611098) (xy 26.393902 -261.388098) (xy 29.464 -258.318)
				(xy 29.464 -249.301) (xy 32.385 -246.38) (xy 32.385 -241.3) (xy 30.861 -239.776) (xy 18.796 -239.776)
				(xy 15.9512 -242.6208) (xy 15.9512 -255.6256) (xy 21.209 -260.8834) (xy 21.209 -267.335)
			)
		)
	)
	(zone
		(layer "B.Cu")
		(hatch none 0.5)
		(connect_pads
			(clearance 0)
		)
		(min_thickness 0.25)
		(keepout
			(tracks not_allowed)
			(vias allowed)
			(pads allowed)
			(copperpour not_allowed)
			(footprints allowed)
		)
		(placement
			(enabled no)
			(sheetname "")
		)
		(fill
			(thermal_gap 0.5)
			(thermal_bridge_width 0.5)
			(island_removal_mode 0)
		)
		(polygon
			(pts
				(arc
					(start 5.59054 -219.135706)
					(mid 5.080127 -218.624912)
					(end 4.56946 -219.135452)
				)
				(xy 4.56946 -219.289376) (xy 4.784598 -219.289376)
				(arc
					(start 4.834382 -219.239592)
					(mid 5.268644 -218.946808)
					(end 4.97586 -219.38107)
				)
				(xy 4.867402 -219.489528) (xy 4.56946 -219.489528) (xy 4.56946 -219.59443) (xy 4.867656 -219.59443)
				(arc
					(start 4.97586 -219.702634)
					(mid 5.268644 -220.136896)
					(end 4.834382 -219.844112)
				)
				(xy 4.784852 -219.794582) (xy 4.56946 -219.794582)
				(arc
					(start 4.56946 -219.948252)
					(mid 5.08 -220.458792)
					(end 5.59054 -219.948252)
				)
			)
		)
	)
	(zone
		(layer "B.Cu")
		(hatch none 0.5)
		(connect_pads
			(clearance 0)
		)
		(min_thickness 0.25)
		(keepout
			(tracks not_allowed)
			(vias allowed)
			(pads allowed)
			(copperpour not_allowed)
			(footprints allowed)
		)
		(placement
			(enabled no)
			(sheetname "")
		)
		(fill
			(thermal_gap 0.5)
			(thermal_bridge_width 0.5)
			(island_removal_mode 0)
		)
		(polygon
			(pts
				(xy 1.022096 -465.795868) (xy 3.758184 -465.795868) (xy 3.81 -465.847684) (xy 3.81 -466.0392) (xy 3.761232 -466.087968)
				(xy 1.025398 -466.087968) (xy 1.014984 -466.098382) (xy 1.010158 -466.098382) (xy 1.005332 -466.093556)
				(xy 1.005332 -466.0773) (xy 1.005332 -465.806536) (xy 1.005332 -465.791042) (xy 1.007872 -465.788502)
				(xy 1.01473 -465.788502)
			)
		)
	)
	(zone
		(layers "B.Cu" "In2.Cu")
		(hatch none 0.5)
		(connect_pads
			(clearance 0)
		)
		(min_thickness 0.25)
		(keepout
			(tracks not_allowed)
			(vias allowed)
			(pads allowed)
			(copperpour not_allowed)
			(footprints allowed)
		)
		(placement
			(enabled no)
			(sheetname "")
		)
		(fill yes
			(thermal_gap 0.5)
			(thermal_bridge_width 0.5)
			(island_removal_mode 0)
		)
		(polygon
			(pts
				(arc
					(start 7.502906 -343.586816)
					(mid 6.992366 -343.076276)
					(end 6.481826 -343.586816)
				)
				(arc
					(start 6.481826 -344.399616)
					(mid 6.991096 -344.910154)
					(end 7.502906 -344.402156)
				)
				(arc
					(start 7.259066 -344.402156)
					(mid 6.992366 -344.666328)
					(end 6.725666 -344.402156)
				)
				(arc
					(start 6.725666 -344.399616)
					(mid 6.992366 -344.132916)
					(end 7.259066 -344.399616)
				)
				(xy 7.502906 -344.399616) (xy 7.502906 -343.589356)
				(arc
					(start 7.259066 -343.589356)
					(mid 6.992366 -343.853528)
					(end 6.725666 -343.589356)
				)
				(arc
					(start 6.725666 -343.586816)
					(mid 6.992366 -343.320116)
					(end 7.259066 -343.586816)
				)
			)
		)
	)
	(zone
		(layers "B.Cu" "In2.Cu")
		(hatch none 0.5)
		(connect_pads
			(clearance 0)
		)
		(min_thickness 0.25)
		(keepout
			(tracks not_allowed)
			(vias allowed)
			(pads allowed)
			(copperpour not_allowed)
			(footprints allowed)
		)
		(placement
			(enabled no)
			(sheetname "")
		)
		(fill yes
			(thermal_gap 0.5)
			(thermal_bridge_width 0.5)
			(island_removal_mode 0)
		)
		(polygon
			(pts
				(arc
					(start 27.18054 -124.003562)
					(mid 26.67 -123.493022)
					(end 26.15946 -124.003562)
				)
				(arc
					(start 26.15946 -124.816108)
					(mid 26.668603 -125.3269)
					(end 27.18054 -124.818902)
				)
				(arc
					(start 26.9367 -124.818902)
					(mid 26.67 -125.083074)
					(end 26.4033 -124.818902)
				)
				(arc
					(start 26.4033 -124.816362)
					(mid 26.67 -124.549662)
					(end 26.9367 -124.816362)
				)
				(xy 27.18054 -124.816362) (xy 27.18054 -124.006102)
				(arc
					(start 26.9367 -124.006102)
					(mid 26.67 -124.270274)
					(end 26.4033 -124.006102)
				)
				(arc
					(start 26.4033 -124.003562)
					(mid 26.67 -123.736862)
					(end 26.9367 -124.003562)
				)
			)
		)
	)
	(zone
		(layers "B.Cu" "In2.Cu")
		(hatch none 0.5)
		(connect_pads
			(clearance 0)
		)
		(min_thickness 0.25)
		(keepout
			(tracks not_allowed)
			(vias allowed)
			(pads allowed)
			(copperpour not_allowed)
			(footprints allowed)
		)
		(placement
			(enabled no)
			(sheetname "")
		)
		(fill yes
			(thermal_gap 0.5)
			(thermal_bridge_width 0.5)
			(island_removal_mode 0)
		)
		(polygon
			(pts
				(arc
					(start 7.502906 -393.535662)
					(mid 6.992366 -393.025122)
					(end 6.481826 -393.535662)
				)
				(arc
					(start 6.481826 -394.348462)
					(mid 6.991096 -394.859)
					(end 7.502906 -394.351002)
				)
				(arc
					(start 7.259066 -394.351002)
					(mid 6.992366 -394.615174)
					(end 6.725666 -394.351002)
				)
				(arc
					(start 6.725666 -394.348462)
					(mid 6.992366 -394.081762)
					(end 7.259066 -394.348462)
				)
				(xy 7.502906 -394.348462) (xy 7.502906 -393.538202)
				(arc
					(start 7.259066 -393.538202)
					(mid 6.992366 -393.802374)
					(end 6.725666 -393.538202)
				)
				(arc
					(start 6.725666 -393.535662)
					(mid 6.992366 -393.268962)
					(end 7.259066 -393.535662)
				)
			)
		)
	)
	(zone
		(layers "B.Cu" "In2.Cu")
		(hatch none 0.5)
		(connect_pads
			(clearance 0)
		)
		(min_thickness 0.25)
		(keepout
			(tracks not_allowed)
			(vias allowed)
			(pads allowed)
			(copperpour not_allowed)
			(footprints allowed)
		)
		(placement
			(enabled no)
			(sheetname "")
		)
		(fill yes
			(thermal_gap 0.5)
			(thermal_bridge_width 0.5)
			(island_removal_mode 0)
		)
		(polygon
			(pts
				(arc
					(start 7.502906 -211.135976)
					(mid 6.992366 -210.625436)
					(end 6.481826 -211.135976)
				)
				(arc
					(start 6.481826 -211.948776)
					(mid 6.991096 -212.459314)
					(end 7.502906 -211.951316)
				)
				(arc
					(start 7.259066 -211.951316)
					(mid 6.992366 -212.215488)
					(end 6.725666 -211.951316)
				)
				(arc
					(start 6.725666 -211.948776)
					(mid 6.992366 -211.682076)
					(end 7.259066 -211.948776)
				)
				(xy 7.502906 -211.948776) (xy 7.502906 -211.138516)
				(arc
					(start 7.259066 -211.138516)
					(mid 6.992366 -211.402688)
					(end 6.725666 -211.138516)
				)
				(arc
					(start 6.725666 -211.135976)
					(mid 6.992366 -210.869276)
					(end 7.259066 -211.135976)
				)
			)
		)
	)
	(zone
		(layers "B.Cu" "In2.Cu")
		(hatch none 0.5)
		(connect_pads
			(clearance 0)
		)
		(min_thickness 0.25)
		(keepout
			(tracks not_allowed)
			(vias allowed)
			(pads allowed)
			(copperpour not_allowed)
			(footprints allowed)
		)
		(placement
			(enabled no)
			(sheetname "")
		)
		(fill yes
			(thermal_gap 0.5)
			(thermal_bridge_width 0.5)
			(island_removal_mode 0)
		)
		(polygon
			(pts
				(arc
					(start 220.840554 -381.183642)
					(mid 220.330014 -380.673102)
					(end 219.819474 -381.183642)
				)
				(arc
					(start 219.819474 -381.996442)
					(mid 220.328744 -382.50698)
					(end 220.840554 -381.998982)
				)
				(arc
					(start 220.596714 -381.998982)
					(mid 220.330014 -382.263154)
					(end 220.063314 -381.998982)
				)
				(arc
					(start 220.063314 -381.996442)
					(mid 220.330014 -381.729742)
					(end 220.596714 -381.996442)
				)
				(xy 220.840554 -381.996442) (xy 220.840554 -381.186182)
				(arc
					(start 220.596714 -381.186182)
					(mid 220.330014 -381.450354)
					(end 220.063314 -381.186182)
				)
				(arc
					(start 220.063314 -381.183642)
					(mid 220.330014 -380.916942)
					(end 220.596714 -381.183642)
				)
			)
		)
	)
	(zone
		(layers "B.Cu" "In2.Cu")
		(hatch none 0.5)
		(connect_pads
			(clearance 0)
		)
		(min_thickness 0.25)
		(keepout
			(tracks not_allowed)
			(vias allowed)
			(pads allowed)
			(copperpour not_allowed)
			(footprints allowed)
		)
		(placement
			(enabled no)
			(sheetname "")
		)
		(fill yes
			(thermal_gap 0.5)
			(thermal_bridge_width 0.5)
			(island_removal_mode 0)
		)
		(polygon
			(pts
				(arc
					(start 7.502906 -443.18428)
					(mid 6.992366 -442.67374)
					(end 6.481826 -443.18428)
				)
				(arc
					(start 6.481826 -443.996826)
					(mid 6.990969 -444.507618)
					(end 7.502906 -443.99962)
				)
				(arc
					(start 7.259066 -443.99962)
					(mid 6.992366 -444.263792)
					(end 6.725666 -443.99962)
				)
				(arc
					(start 6.725666 -443.99708)
					(mid 6.992366 -443.73038)
					(end 7.259066 -443.99708)
				)
				(xy 7.502906 -443.99708) (xy 7.502906 -443.18682)
				(arc
					(start 7.259066 -443.18682)
					(mid 6.992366 -443.450992)
					(end 6.725666 -443.18682)
				)
				(arc
					(start 6.725666 -443.18428)
					(mid 6.992366 -442.91758)
					(end 7.259066 -443.18428)
				)
			)
		)
	)
	(zone
		(layers "B.Cu" "In2.Cu")
		(hatch none 0.5)
		(connect_pads
			(clearance 0)
		)
		(min_thickness 0.25)
		(keepout
			(tracks not_allowed)
			(vias allowed)
			(pads allowed)
			(copperpour not_allowed)
			(footprints allowed)
		)
		(placement
			(enabled no)
			(sheetname "")
		)
		(fill yes
			(thermal_gap 0.5)
			(thermal_bridge_width 0.5)
			(island_removal_mode 0)
		)
		(polygon
			(pts
				(arc
					(start 7.502906 -230.335836)
					(mid 6.992366 -229.825296)
					(end 6.481826 -230.335836)
				)
				(arc
					(start 6.481826 -231.148636)
					(mid 6.991096 -231.659174)
					(end 7.502906 -231.151176)
				)
				(arc
					(start 7.259066 -231.151176)
					(mid 6.992366 -231.415348)
					(end 6.725666 -231.151176)
				)
				(arc
					(start 6.725666 -231.148636)
					(mid 6.992366 -230.881936)
					(end 7.259066 -231.148636)
				)
				(xy 7.502906 -231.148636) (xy 7.502906 -230.338376)
				(arc
					(start 7.259066 -230.338376)
					(mid 6.992366 -230.602548)
					(end 6.725666 -230.338376)
				)
				(arc
					(start 6.725666 -230.335836)
					(mid 6.992366 -230.069136)
					(end 7.259066 -230.335836)
				)
			)
		)
	)
	(zone
		(layers "B.Cu" "In2.Cu")
		(hatch none 0.5)
		(connect_pads
			(clearance 0)
		)
		(min_thickness 0.25)
		(keepout
			(tracks not_allowed)
			(vias allowed)
			(pads allowed)
			(copperpour not_allowed)
			(footprints allowed)
		)
		(placement
			(enabled no)
			(sheetname "")
		)
		(fill yes
			(thermal_gap 0.5)
			(thermal_bridge_width 0.5)
			(island_removal_mode 0)
		)
		(polygon
			(pts
				(arc
					(start 7.502906 -178.38674)
					(mid 6.992366 -177.8762)
					(end 6.481826 -178.38674)
				)
				(arc
					(start 6.481826 -179.19954)
					(mid 6.991096 -179.710078)
					(end 7.502906 -179.20208)
				)
				(arc
					(start 7.259066 -179.20208)
					(mid 6.992366 -179.466252)
					(end 6.725666 -179.20208)
				)
				(arc
					(start 6.725666 -179.19954)
					(mid 6.992366 -178.93284)
					(end 7.259066 -179.19954)
				)
				(xy 7.502906 -179.19954) (xy 7.502906 -178.38928)
				(arc
					(start 7.259066 -178.38928)
					(mid 6.992366 -178.653452)
					(end 6.725666 -178.38928)
				)
				(arc
					(start 6.725666 -178.38674)
					(mid 6.992366 -178.12004)
					(end 7.259066 -178.38674)
				)
			)
		)
	)
	(zone
		(layers "B.Cu" "In2.Cu")
		(hatch none 0.5)
		(connect_pads
			(clearance 0)
		)
		(min_thickness 0.25)
		(keepout
			(tracks not_allowed)
			(vias allowed)
			(pads allowed)
			(copperpour not_allowed)
			(footprints allowed)
		)
		(placement
			(enabled no)
			(sheetname "")
		)
		(fill yes
			(thermal_gap 0.5)
			(thermal_bridge_width 0.5)
			(island_removal_mode 0)
		)
		(polygon
			(pts
				(arc
					(start 27.18054 -38.603428)
					(mid 26.67 -38.092888)
					(end 26.15946 -38.603428)
				)
				(arc
					(start 26.15946 -39.415974)
					(mid 26.668603 -39.926766)
					(end 27.18054 -39.418768)
				)
				(arc
					(start 26.9367 -39.418768)
					(mid 26.67 -39.68294)
					(end 26.4033 -39.418768)
				)
				(arc
					(start 26.4033 -39.416228)
					(mid 26.67 -39.149528)
					(end 26.9367 -39.416228)
				)
				(xy 27.18054 -39.416228) (xy 27.18054 -38.605968)
				(arc
					(start 26.9367 -38.605968)
					(mid 26.67 -38.87014)
					(end 26.4033 -38.605968)
				)
				(arc
					(start 26.4033 -38.603428)
					(mid 26.67 -38.336728)
					(end 26.9367 -38.603428)
				)
			)
		)
	)
	(zone
		(layers "B.Cu" "In2.Cu")
		(hatch none 0.5)
		(connect_pads
			(clearance 0)
		)
		(min_thickness 0.25)
		(keepout
			(tracks not_allowed)
			(vias allowed)
			(pads allowed)
			(copperpour not_allowed)
			(footprints allowed)
		)
		(placement
			(enabled no)
			(sheetname "")
		)
		(fill yes
			(thermal_gap 0.5)
			(thermal_bridge_width 0.5)
			(island_removal_mode 0)
		)
		(polygon
			(pts
				(arc
					(start 27.18054 -244.603524)
					(mid 26.67 -244.092984)
					(end 26.15946 -244.603524)
				)
				(arc
					(start 26.15946 -245.41607)
					(mid 26.668603 -245.926862)
					(end 27.18054 -245.418864)
				)
				(arc
					(start 26.9367 -245.418864)
					(mid 26.67 -245.683036)
					(end 26.4033 -245.418864)
				)
				(arc
					(start 26.4033 -245.416324)
					(mid 26.67 -245.149624)
					(end 26.9367 -245.416324)
				)
				(xy 27.18054 -245.416324) (xy 27.18054 -244.606064)
				(arc
					(start 26.9367 -244.606064)
					(mid 26.67 -244.870236)
					(end 26.4033 -244.606064)
				)
				(arc
					(start 26.4033 -244.603524)
					(mid 26.67 -244.336824)
					(end 26.9367 -244.603524)
				)
			)
		)
	)
	(zone
		(layers "B.Cu" "In2.Cu")
		(hatch none 0.5)
		(connect_pads
			(clearance 0)
		)
		(min_thickness 0.25)
		(keepout
			(tracks not_allowed)
			(vias allowed)
			(pads allowed)
			(copperpour not_allowed)
			(footprints allowed)
		)
		(placement
			(enabled no)
			(sheetname "")
		)
		(fill yes
			(thermal_gap 0.5)
			(thermal_bridge_width 0.5)
			(island_removal_mode 0)
		)
		(polygon
			(pts
				(arc
					(start 7.502906 -424.784266)
					(mid 6.992366 -424.273726)
					(end 6.481826 -424.784266)
				)
				(arc
					(start 6.481826 -425.597066)
					(mid 6.991096 -426.107604)
					(end 7.502906 -425.599606)
				)
				(arc
					(start 7.259066 -425.599606)
					(mid 6.992366 -425.863778)
					(end 6.725666 -425.599606)
				)
				(arc
					(start 6.725666 -425.597066)
					(mid 6.992366 -425.330366)
					(end 7.259066 -425.597066)
				)
				(xy 7.502906 -425.597066) (xy 7.502906 -424.786806)
				(arc
					(start 7.259066 -424.786806)
					(mid 6.992366 -425.050978)
					(end 6.725666 -424.786806)
				)
				(arc
					(start 6.725666 -424.784266)
					(mid 6.992366 -424.517566)
					(end 7.259066 -424.784266)
				)
			)
		)
	)
	(zone
		(layers "B.Cu" "In2.Cu")
		(hatch none 0.5)
		(connect_pads
			(clearance 0)
		)
		(min_thickness 0.25)
		(keepout
			(tracks not_allowed)
			(vias allowed)
			(pads allowed)
			(copperpour not_allowed)
			(footprints allowed)
		)
		(placement
			(enabled no)
			(sheetname "")
		)
		(fill yes
			(thermal_gap 0.5)
			(thermal_bridge_width 0.5)
			(island_removal_mode 0)
		)
		(polygon
			(pts
				(arc
					(start 35.84067 -54.583584)
					(mid 35.33013 -54.073044)
					(end 34.81959 -54.583584)
				)
				(arc
					(start 34.81959 -55.396384)
					(mid 35.32886 -55.906922)
					(end 35.84067 -55.398924)
				)
				(arc
					(start 35.59683 -55.398924)
					(mid 35.33013 -55.663096)
					(end 35.06343 -55.398924)
				)
				(arc
					(start 35.06343 -55.396384)
					(mid 35.33013 -55.129684)
					(end 35.59683 -55.396384)
				)
				(xy 35.84067 -55.396384) (xy 35.84067 -54.586124)
				(arc
					(start 35.59683 -54.586124)
					(mid 35.33013 -54.850296)
					(end 35.06343 -54.586124)
				)
				(arc
					(start 35.06343 -54.583584)
					(mid 35.33013 -54.316884)
					(end 35.59683 -54.583584)
				)
			)
		)
	)
	(zone
		(layers "B.Cu" "In2.Cu")
		(hatch none 0.5)
		(connect_pads
			(clearance 0)
		)
		(min_thickness 0.25)
		(keepout
			(tracks not_allowed)
			(vias allowed)
			(pads allowed)
			(copperpour not_allowed)
			(footprints allowed)
		)
		(placement
			(enabled no)
			(sheetname "")
		)
		(fill yes
			(thermal_gap 0.5)
			(thermal_bridge_width 0.5)
			(island_removal_mode 0)
		)
		(polygon
			(pts
				(arc
					(start 7.502906 -318.735964)
					(mid 6.992366 -318.225424)
					(end 6.481826 -318.735964)
				)
				(arc
					(start 6.481826 -319.54851)
					(mid 6.990969 -320.059302)
					(end 7.502906 -319.551304)
				)
				(arc
					(start 7.259066 -319.551304)
					(mid 6.992366 -319.815476)
					(end 6.725666 -319.551304)
				)
				(arc
					(start 6.725666 -319.548764)
					(mid 6.992366 -319.282064)
					(end 7.259066 -319.548764)
				)
				(xy 7.502906 -319.548764) (xy 7.502906 -318.738504)
				(arc
					(start 7.259066 -318.738504)
					(mid 6.992366 -319.002676)
					(end 6.725666 -318.738504)
				)
				(arc
					(start 6.725666 -318.735964)
					(mid 6.992366 -318.469264)
					(end 7.259066 -318.735964)
				)
			)
		)
	)
	(zone
		(layers "B.Cu" "In2.Cu")
		(hatch none 0.5)
		(connect_pads
			(clearance 0)
		)
		(min_thickness 0.25)
		(keepout
			(tracks not_allowed)
			(vias allowed)
			(pads allowed)
			(copperpour not_allowed)
			(footprints allowed)
		)
		(placement
			(enabled no)
			(sheetname "")
		)
		(fill yes
			(thermal_gap 0.5)
			(thermal_bridge_width 0.5)
			(island_removal_mode 0)
		)
		(polygon
			(pts
				(arc
					(start 220.840554 -76.98359)
					(mid 220.330014 -76.47305)
					(end 219.819474 -76.98359)
				)
				(arc
					(start 219.819474 -77.79639)
					(mid 220.328744 -78.306928)
					(end 220.840554 -77.79893)
				)
				(arc
					(start 220.596714 -77.79893)
					(mid 220.330014 -78.063102)
					(end 220.063314 -77.79893)
				)
				(arc
					(start 220.063314 -77.79639)
					(mid 220.330014 -77.52969)
					(end 220.596714 -77.79639)
				)
				(xy 220.840554 -77.79639) (xy 220.840554 -76.98613)
				(arc
					(start 220.596714 -76.98613)
					(mid 220.330014 -77.250302)
					(end 220.063314 -76.98613)
				)
				(arc
					(start 220.063314 -76.98359)
					(mid 220.330014 -76.71689)
					(end 220.596714 -76.98359)
				)
			)
		)
	)
	(zone
		(layers "B.Cu" "In2.Cu")
		(hatch none 0.5)
		(connect_pads
			(clearance 0)
		)
		(min_thickness 0.25)
		(keepout
			(tracks not_allowed)
			(vias allowed)
			(pads allowed)
			(copperpour not_allowed)
			(footprints allowed)
		)
		(placement
			(enabled no)
			(sheetname "")
		)
		(fill yes
			(thermal_gap 0.5)
			(thermal_bridge_width 0.5)
			(island_removal_mode 0)
		)
		(polygon
			(pts
				(arc
					(start 7.502906 -333.986632)
					(mid 6.992366 -333.476092)
					(end 6.481826 -333.986632)
				)
				(arc
					(start 6.481826 -334.799432)
					(mid 6.991096 -335.30997)
					(end 7.502906 -334.801972)
				)
				(arc
					(start 7.259066 -334.801972)
					(mid 6.992366 -335.066144)
					(end 6.725666 -334.801972)
				)
				(arc
					(start 6.725666 -334.799432)
					(mid 6.992366 -334.532732)
					(end 7.259066 -334.799432)
				)
				(xy 7.502906 -334.799432) (xy 7.502906 -333.989172)
				(arc
					(start 7.259066 -333.989172)
					(mid 6.992366 -334.253344)
					(end 6.725666 -333.989172)
				)
				(arc
					(start 6.725666 -333.986632)
					(mid 6.992366 -333.719932)
					(end 7.259066 -333.986632)
				)
			)
		)
	)
	(zone
		(layers "B.Cu" "In2.Cu")
		(hatch none 0.5)
		(connect_pads
			(clearance 0)
		)
		(min_thickness 0.25)
		(keepout
			(tracks not_allowed)
			(vias allowed)
			(pads allowed)
			(copperpour not_allowed)
			(footprints allowed)
		)
		(placement
			(enabled no)
			(sheetname "")
		)
		(fill yes
			(thermal_gap 0.5)
			(thermal_bridge_width 0.5)
			(island_removal_mode 0)
		)
		(polygon
			(pts
				(arc
					(start 7.502906 -411.935676)
					(mid 6.992366 -411.425136)
					(end 6.481826 -411.935676)
				)
				(arc
					(start 6.481826 -412.748222)
					(mid 6.990969 -413.259014)
					(end 7.502906 -412.751016)
				)
				(arc
					(start 7.259066 -412.751016)
					(mid 6.992366 -413.015188)
					(end 6.725666 -412.751016)
				)
				(arc
					(start 6.725666 -412.748476)
					(mid 6.992366 -412.481776)
					(end 7.259066 -412.748476)
				)
				(xy 7.502906 -412.748476) (xy 7.502906 -411.938216)
				(arc
					(start 7.259066 -411.938216)
					(mid 6.992366 -412.202388)
					(end 6.725666 -411.938216)
				)
				(arc
					(start 6.725666 -411.935676)
					(mid 6.992366 -411.668976)
					(end 7.259066 -411.935676)
				)
			)
		)
	)
	(zone
		(layers "B.Cu" "In2.Cu")
		(hatch none 0.5)
		(connect_pads
			(clearance 0)
		)
		(min_thickness 0.25)
		(keepout
			(tracks not_allowed)
			(vias allowed)
			(pads allowed)
			(copperpour not_allowed)
			(footprints allowed)
		)
		(placement
			(enabled no)
			(sheetname "")
		)
		(fill yes
			(thermal_gap 0.5)
			(thermal_bridge_width 0.5)
			(island_removal_mode 0)
		)
		(polygon
			(pts
				(arc
					(start 7.502906 -405.535638)
					(mid 6.992366 -405.025098)
					(end 6.481826 -405.535638)
				)
				(arc
					(start 6.481826 -406.348184)
					(mid 6.990969 -406.858976)
					(end 7.502906 -406.350978)
				)
				(arc
					(start 7.259066 -406.350978)
					(mid 6.992366 -406.61515)
					(end 6.725666 -406.350978)
				)
				(arc
					(start 6.725666 -406.348438)
					(mid 6.992366 -406.081738)
					(end 7.259066 -406.348438)
				)
				(xy 7.502906 -406.348438) (xy 7.502906 -405.538178)
				(arc
					(start 7.259066 -405.538178)
					(mid 6.992366 -405.80235)
					(end 6.725666 -405.538178)
				)
				(arc
					(start 6.725666 -405.535638)
					(mid 6.992366 -405.268938)
					(end 7.259066 -405.535638)
				)
			)
		)
	)
	(zone
		(layers "B.Cu" "In2.Cu")
		(hatch none 0.5)
		(connect_pads
			(clearance 0)
		)
		(min_thickness 0.25)
		(keepout
			(tracks not_allowed)
			(vias allowed)
			(pads allowed)
			(copperpour not_allowed)
			(footprints allowed)
		)
		(placement
			(enabled no)
			(sheetname "")
		)
		(fill yes
			(thermal_gap 0.5)
			(thermal_bridge_width 0.5)
			(island_removal_mode 0)
		)
		(polygon
			(pts
				(arc
					(start 7.502906 -291.535866)
					(mid 6.992366 -291.025326)
					(end 6.481826 -291.535866)
				)
				(arc
					(start 6.481826 -292.348412)
					(mid 6.990969 -292.859204)
					(end 7.502906 -292.351206)
				)
				(arc
					(start 7.259066 -292.351206)
					(mid 6.992366 -292.615378)
					(end 6.725666 -292.351206)
				)
				(arc
					(start 6.725666 -292.348666)
					(mid 6.992366 -292.081966)
					(end 7.259066 -292.348666)
				)
				(xy 7.502906 -292.348666) (xy 7.502906 -291.538406)
				(arc
					(start 7.259066 -291.538406)
					(mid 6.992366 -291.802578)
					(end 6.725666 -291.538406)
				)
				(arc
					(start 6.725666 -291.535866)
					(mid 6.992366 -291.269166)
					(end 7.259066 -291.535866)
				)
			)
		)
	)
	(zone
		(layers "B.Cu" "In2.Cu")
		(hatch none 0.5)
		(connect_pads
			(clearance 0)
		)
		(min_thickness 0.25)
		(keepout
			(tracks not_allowed)
			(vias allowed)
			(pads allowed)
			(copperpour not_allowed)
			(footprints allowed)
		)
		(placement
			(enabled no)
			(sheetname "")
		)
		(fill yes
			(thermal_gap 0.5)
			(thermal_bridge_width 0.5)
			(island_removal_mode 0)
		)
		(polygon
			(pts
				(arc
					(start 7.502906 -181.535832)
					(mid 6.992366 -181.025292)
					(end 6.481826 -181.535832)
				)
				(arc
					(start 6.481826 -182.348632)
					(mid 6.991096 -182.85917)
					(end 7.502906 -182.351172)
				)
				(arc
					(start 7.259066 -182.351172)
					(mid 6.992366 -182.615344)
					(end 6.725666 -182.351172)
				)
				(arc
					(start 6.725666 -182.348632)
					(mid 6.992366 -182.081932)
					(end 7.259066 -182.348632)
				)
				(xy 7.502906 -182.348632) (xy 7.502906 -181.538372)
				(arc
					(start 7.259066 -181.538372)
					(mid 6.992366 -181.802544)
					(end 6.725666 -181.538372)
				)
				(arc
					(start 6.725666 -181.535832)
					(mid 6.992366 -181.269132)
					(end 7.259066 -181.535832)
				)
			)
		)
	)
	(zone
		(layers "B.Cu" "In2.Cu")
		(hatch none 0.5)
		(connect_pads
			(clearance 0)
		)
		(min_thickness 0.25)
		(keepout
			(tracks not_allowed)
			(vias allowed)
			(pads allowed)
			(copperpour not_allowed)
			(footprints allowed)
		)
		(placement
			(enabled no)
			(sheetname "")
		)
		(fill yes
			(thermal_gap 0.5)
			(thermal_bridge_width 0.5)
			(island_removal_mode 0)
		)
		(polygon
			(pts
				(arc
					(start 7.502906 -439.984134)
					(mid 6.992366 -439.473594)
					(end 6.481826 -439.984134)
				)
				(arc
					(start 6.481826 -440.79668)
					(mid 6.990969 -441.307472)
					(end 7.502906 -440.799474)
				)
				(arc
					(start 7.259066 -440.799474)
					(mid 6.992366 -441.063646)
					(end 6.725666 -440.799474)
				)
				(arc
					(start 6.725666 -440.796934)
					(mid 6.992366 -440.530234)
					(end 7.259066 -440.796934)
				)
				(xy 7.502906 -440.796934) (xy 7.502906 -439.986674)
				(arc
					(start 7.259066 -439.986674)
					(mid 6.992366 -440.250846)
					(end 6.725666 -439.986674)
				)
				(arc
					(start 6.725666 -439.984134)
					(mid 6.992366 -439.717434)
					(end 7.259066 -439.984134)
				)
			)
		)
	)
	(zone
		(layers "B.Cu" "In2.Cu")
		(hatch none 0.5)
		(connect_pads
			(clearance 0)
		)
		(min_thickness 0.25)
		(keepout
			(tracks not_allowed)
			(vias allowed)
			(pads allowed)
			(copperpour not_allowed)
			(footprints allowed)
		)
		(placement
			(enabled no)
			(sheetname "")
		)
		(fill yes
			(thermal_gap 0.5)
			(thermal_bridge_width 0.5)
			(island_removal_mode 0)
		)
		(polygon
			(pts
				(arc
					(start 7.502906 -152.786588)
					(mid 6.992366 -152.276048)
					(end 6.481826 -152.786588)
				)
				(arc
					(start 6.481826 -153.599388)
					(mid 6.991096 -154.109926)
					(end 7.502906 -153.601928)
				)
				(arc
					(start 7.259066 -153.601928)
					(mid 6.992366 -153.8661)
					(end 6.725666 -153.601928)
				)
				(arc
					(start 6.725666 -153.599388)
					(mid 6.992366 -153.332688)
					(end 7.259066 -153.599388)
				)
				(xy 7.502906 -153.599388) (xy 7.502906 -152.789128)
				(arc
					(start 7.259066 -152.789128)
					(mid 6.992366 -153.0533)
					(end 6.725666 -152.789128)
				)
				(arc
					(start 6.725666 -152.786588)
					(mid 6.992366 -152.519888)
					(end 7.259066 -152.786588)
				)
			)
		)
	)
	(zone
		(layers "B.Cu" "In2.Cu")
		(hatch none 0.5)
		(connect_pads
			(clearance 0)
		)
		(min_thickness 0.25)
		(keepout
			(tracks not_allowed)
			(vias allowed)
			(pads allowed)
			(copperpour not_allowed)
			(footprints allowed)
		)
		(placement
			(enabled no)
			(sheetname "")
		)
		(fill yes
			(thermal_gap 0.5)
			(thermal_bridge_width 0.5)
			(island_removal_mode 0)
		)
		(polygon
			(pts
				(arc
					(start 27.18054 -347.603572)
					(mid 26.67 -347.093032)
					(end 26.15946 -347.603572)
				)
				(arc
					(start 26.15946 -348.416118)
					(mid 26.668603 -348.92691)
					(end 27.18054 -348.418912)
				)
				(arc
					(start 26.9367 -348.418912)
					(mid 26.67 -348.683084)
					(end 26.4033 -348.418912)
				)
				(arc
					(start 26.4033 -348.416372)
					(mid 26.67 -348.149672)
					(end 26.9367 -348.416372)
				)
				(xy 27.18054 -348.416372) (xy 27.18054 -347.606112)
				(arc
					(start 26.9367 -347.606112)
					(mid 26.67 -347.870284)
					(end 26.4033 -347.606112)
				)
				(arc
					(start 26.4033 -347.603572)
					(mid 26.67 -347.336872)
					(end 26.9367 -347.603572)
				)
			)
		)
	)
	(zone
		(layers "B.Cu" "In2.Cu")
		(hatch none 0.5)
		(connect_pads
			(clearance 0)
		)
		(min_thickness 0.25)
		(keepout
			(tracks not_allowed)
			(vias allowed)
			(pads allowed)
			(copperpour not_allowed)
			(footprints allowed)
		)
		(placement
			(enabled no)
			(sheetname "")
		)
		(fill yes
			(thermal_gap 0.5)
			(thermal_bridge_width 0.5)
			(island_removal_mode 0)
		)
		(polygon
			(pts
				(arc
					(start 7.502906 -184.735978)
					(mid 6.992366 -184.225438)
					(end 6.481826 -184.735978)
				)
				(arc
					(start 6.481826 -185.548778)
					(mid 6.991096 -186.059316)
					(end 7.502906 -185.551318)
				)
				(arc
					(start 7.259066 -185.551318)
					(mid 6.992366 -185.81549)
					(end 6.725666 -185.551318)
				)
				(arc
					(start 6.725666 -185.548778)
					(mid 6.992366 -185.282078)
					(end 7.259066 -185.548778)
				)
				(xy 7.502906 -185.548778) (xy 7.502906 -184.738518)
				(arc
					(start 7.259066 -184.738518)
					(mid 6.992366 -185.00269)
					(end 6.725666 -184.738518)
				)
				(arc
					(start 6.725666 -184.735978)
					(mid 6.992366 -184.469278)
					(end 7.259066 -184.735978)
				)
			)
		)
	)
	(zone
		(layers "B.Cu" "In2.Cu")
		(hatch none 0.5)
		(connect_pads
			(clearance 0)
		)
		(min_thickness 0.25)
		(keepout
			(tracks not_allowed)
			(vias allowed)
			(pads allowed)
			(copperpour not_allowed)
			(footprints allowed)
		)
		(placement
			(enabled no)
			(sheetname "")
		)
		(fill yes
			(thermal_gap 0.5)
			(thermal_bridge_width 0.5)
			(island_removal_mode 0)
		)
		(polygon
			(pts
				(arc
					(start 220.840554 -157.583632)
					(mid 220.330014 -157.073092)
					(end 219.819474 -157.583632)
				)
				(arc
					(start 219.819474 -158.396432)
					(mid 220.328744 -158.90697)
					(end 220.840554 -158.398972)
				)
				(arc
					(start 220.596714 -158.398972)
					(mid 220.330014 -158.663144)
					(end 220.063314 -158.398972)
				)
				(arc
					(start 220.063314 -158.396432)
					(mid 220.330014 -158.129732)
					(end 220.596714 -158.396432)
				)
				(xy 220.840554 -158.396432) (xy 220.840554 -157.586172)
				(arc
					(start 220.596714 -157.586172)
					(mid 220.330014 -157.850344)
					(end 220.063314 -157.586172)
				)
				(arc
					(start 220.063314 -157.583632)
					(mid 220.330014 -157.316932)
					(end 220.596714 -157.583632)
				)
			)
		)
	)
	(zone
		(layers "B.Cu" "In2.Cu")
		(hatch none 0.5)
		(connect_pads
			(clearance 0)
		)
		(min_thickness 0.25)
		(keepout
			(tracks not_allowed)
			(vias allowed)
			(pads allowed)
			(copperpour not_allowed)
			(footprints allowed)
		)
		(placement
			(enabled no)
			(sheetname "")
		)
		(fill yes
			(thermal_gap 0.5)
			(thermal_bridge_width 0.5)
			(island_removal_mode 0)
		)
		(polygon
			(pts
				(arc
					(start 7.502906 -328.335894)
					(mid 6.992366 -327.825354)
					(end 6.481826 -328.335894)
				)
				(arc
					(start 6.481826 -329.14844)
					(mid 6.990969 -329.659232)
					(end 7.502906 -329.151234)
				)
				(arc
					(start 7.259066 -329.151234)
					(mid 6.992366 -329.415406)
					(end 6.725666 -329.151234)
				)
				(arc
					(start 6.725666 -329.148694)
					(mid 6.992366 -328.881994)
					(end 7.259066 -329.148694)
				)
				(xy 7.502906 -329.148694) (xy 7.502906 -328.338434)
				(arc
					(start 7.259066 -328.338434)
					(mid 6.992366 -328.602606)
					(end 6.725666 -328.338434)
				)
				(arc
					(start 6.725666 -328.335894)
					(mid 6.992366 -328.069194)
					(end 7.259066 -328.335894)
				)
			)
		)
	)
	(zone
		(layers "B.Cu" "In2.Cu")
		(hatch none 0.5)
		(connect_pads
			(clearance 0)
		)
		(min_thickness 0.25)
		(keepout
			(tracks not_allowed)
			(vias allowed)
			(pads allowed)
			(copperpour not_allowed)
			(footprints allowed)
		)
		(placement
			(enabled no)
			(sheetname "")
		)
		(fill yes
			(thermal_gap 0.5)
			(thermal_bridge_width 0.5)
			(island_removal_mode 0)
		)
		(polygon
			(pts
				(arc
					(start 220.840554 -260.58368)
					(mid 220.330014 -260.07314)
					(end 219.819474 -260.58368)
				)
				(arc
					(start 219.819474 -261.39648)
					(mid 220.328744 -261.907018)
					(end 220.840554 -261.39902)
				)
				(arc
					(start 220.596714 -261.39902)
					(mid 220.330014 -261.663192)
					(end 220.063314 -261.39902)
				)
				(arc
					(start 220.063314 -261.39648)
					(mid 220.330014 -261.12978)
					(end 220.596714 -261.39648)
				)
				(xy 220.840554 -261.39648) (xy 220.840554 -260.58622)
				(arc
					(start 220.596714 -260.58622)
					(mid 220.330014 -260.850392)
					(end 220.063314 -260.58622)
				)
				(arc
					(start 220.063314 -260.58368)
					(mid 220.330014 -260.31698)
					(end 220.596714 -260.58368)
				)
			)
		)
	)
	(zone
		(layers "B.Cu" "In2.Cu")
		(hatch none 0.5)
		(connect_pads
			(clearance 0)
		)
		(min_thickness 0.25)
		(keepout
			(tracks not_allowed)
			(vias allowed)
			(pads allowed)
			(copperpour not_allowed)
			(footprints allowed)
		)
		(placement
			(enabled no)
			(sheetname "")
		)
		(fill yes
			(thermal_gap 0.5)
			(thermal_bridge_width 0.5)
			(island_removal_mode 0)
		)
		(polygon
			(pts
				(arc
					(start 7.502906 -207.93583)
					(mid 6.992366 -207.42529)
					(end 6.481826 -207.93583)
				)
				(arc
					(start 6.481826 -208.74863)
					(mid 6.991096 -209.259168)
					(end 7.502906 -208.75117)
				)
				(arc
					(start 7.259066 -208.75117)
					(mid 6.992366 -209.015342)
					(end 6.725666 -208.75117)
				)
				(arc
					(start 6.725666 -208.74863)
					(mid 6.992366 -208.48193)
					(end 7.259066 -208.74863)
				)
				(xy 7.502906 -208.74863) (xy 7.502906 -207.93837)
				(arc
					(start 7.259066 -207.93837)
					(mid 6.992366 -208.202542)
					(end 6.725666 -207.93837)
				)
				(arc
					(start 6.725666 -207.93583)
					(mid 6.992366 -207.66913)
					(end 7.259066 -207.93583)
				)
			)
		)
	)
	(zone
		(layers "B.Cu" "In2.Cu")
		(hatch none 0.5)
		(connect_pads
			(clearance 0)
		)
		(min_thickness 0.25)
		(keepout
			(tracks not_allowed)
			(vias allowed)
			(pads allowed)
			(copperpour not_allowed)
			(footprints allowed)
		)
		(placement
			(enabled no)
			(sheetname "")
		)
		(fill yes
			(thermal_gap 0.5)
			(thermal_bridge_width 0.5)
			(island_removal_mode 0)
		)
		(polygon
			(pts
				(arc
					(start 7.502906 -427.984158)
					(mid 6.992366 -427.473618)
					(end 6.481826 -427.984158)
				)
				(arc
					(start 6.481826 -428.796958)
					(mid 6.991096 -429.307496)
					(end 7.502906 -428.799498)
				)
				(arc
					(start 7.259066 -428.799498)
					(mid 6.992366 -429.06367)
					(end 6.725666 -428.799498)
				)
				(arc
					(start 6.725666 -428.796958)
					(mid 6.992366 -428.530258)
					(end 7.259066 -428.796958)
				)
				(xy 7.502906 -428.796958) (xy 7.502906 -427.986698)
				(arc
					(start 7.259066 -427.986698)
					(mid 6.992366 -428.25087)
					(end 6.725666 -427.986698)
				)
				(arc
					(start 6.725666 -427.984158)
					(mid 6.992366 -427.717458)
					(end 7.259066 -427.984158)
				)
			)
		)
	)
	(zone
		(layers "B.Cu" "In2.Cu")
		(hatch none 0.5)
		(connect_pads
			(clearance 0)
		)
		(min_thickness 0.25)
		(keepout
			(tracks not_allowed)
			(vias allowed)
			(pads allowed)
			(copperpour not_allowed)
			(footprints allowed)
		)
		(placement
			(enabled no)
			(sheetname "")
		)
		(fill yes
			(thermal_gap 0.5)
			(thermal_bridge_width 0.5)
			(island_removal_mode 0)
		)
		(polygon
			(pts
				(arc
					(start 35.84067 -484.18369)
					(mid 35.33013 -483.67315)
					(end 34.81959 -484.18369)
				)
				(arc
					(start 34.81959 -484.996236)
					(mid 35.328733 -485.507028)
					(end 35.84067 -484.99903)
				)
				(arc
					(start 35.59683 -484.99903)
					(mid 35.33013 -485.263202)
					(end 35.06343 -484.99903)
				)
				(arc
					(start 35.06343 -484.99649)
					(mid 35.33013 -484.72979)
					(end 35.59683 -484.99649)
				)
				(xy 35.84067 -484.99649) (xy 35.84067 -484.18623)
				(arc
					(start 35.59683 -484.18623)
					(mid 35.33013 -484.450402)
					(end 35.06343 -484.18623)
				)
				(arc
					(start 35.06343 -484.18369)
					(mid 35.33013 -483.91699)
					(end 35.59683 -484.18369)
				)
			)
		)
	)
	(zone
		(layers "B.Cu" "In2.Cu")
		(hatch none 0.5)
		(connect_pads
			(clearance 0)
		)
		(min_thickness 0.25)
		(keepout
			(tracks not_allowed)
			(vias allowed)
			(pads allowed)
			(copperpour not_allowed)
			(footprints allowed)
		)
		(placement
			(enabled no)
			(sheetname "")
		)
		(fill yes
			(thermal_gap 0.5)
			(thermal_bridge_width 0.5)
			(island_removal_mode 0)
		)
		(polygon
			(pts
				(arc
					(start 27.18054 -16.203422)
					(mid 26.67 -15.692882)
					(end 26.15946 -16.203422)
				)
				(arc
					(start 26.15946 -17.015968)
					(mid 26.668603 -17.52676)
					(end 27.18054 -17.018762)
				)
				(arc
					(start 26.9367 -17.018762)
					(mid 26.67 -17.282934)
					(end 26.4033 -17.018762)
				)
				(arc
					(start 26.4033 -17.016222)
					(mid 26.67 -16.749522)
					(end 26.9367 -17.016222)
				)
				(xy 27.18054 -17.016222) (xy 27.18054 -16.205962)
				(arc
					(start 26.9367 -16.205962)
					(mid 26.67 -16.470134)
					(end 26.4033 -16.205962)
				)
				(arc
					(start 26.4033 -16.203422)
					(mid 26.67 -15.936722)
					(end 26.9367 -16.203422)
				)
			)
		)
	)
	(zone
		(layers "B.Cu" "In2.Cu")
		(hatch none 0.5)
		(connect_pads
			(clearance 0)
		)
		(min_thickness 0.25)
		(keepout
			(tracks not_allowed)
			(vias allowed)
			(pads allowed)
			(copperpour not_allowed)
			(footprints allowed)
		)
		(placement
			(enabled no)
			(sheetname "")
		)
		(fill yes
			(thermal_gap 0.5)
			(thermal_bridge_width 0.5)
			(island_removal_mode 0)
		)
		(polygon
			(pts
				(arc
					(start 35.84067 -381.183642)
					(mid 35.33013 -380.673102)
					(end 34.81959 -381.183642)
				)
				(arc
					(start 34.81959 -381.996442)
					(mid 35.32886 -382.50698)
					(end 35.84067 -381.998982)
				)
				(arc
					(start 35.59683 -381.998982)
					(mid 35.33013 -382.263154)
					(end 35.06343 -381.998982)
				)
				(arc
					(start 35.06343 -381.996442)
					(mid 35.33013 -381.729742)
					(end 35.59683 -381.996442)
				)
				(xy 35.84067 -381.996442) (xy 35.84067 -381.186182)
				(arc
					(start 35.59683 -381.186182)
					(mid 35.33013 -381.450354)
					(end 35.06343 -381.186182)
				)
				(arc
					(start 35.06343 -381.183642)
					(mid 35.33013 -380.916942)
					(end 35.59683 -381.183642)
				)
			)
		)
	)
	(zone
		(layers "B.Cu" "In2.Cu")
		(hatch none 0.5)
		(connect_pads
			(clearance 0)
		)
		(min_thickness 0.25)
		(keepout
			(tracks not_allowed)
			(vias allowed)
			(pads allowed)
			(copperpour not_allowed)
			(footprints allowed)
		)
		(placement
			(enabled no)
			(sheetname "")
		)
		(fill yes
			(thermal_gap 0.5)
			(thermal_bridge_width 0.5)
			(island_removal_mode 0)
		)
		(polygon
			(pts
				(arc
					(start 7.502906 -310.73598)
					(mid 6.992366 -310.22544)
					(end 6.481826 -310.73598)
				)
				(arc
					(start 6.481826 -311.548526)
					(mid 6.990969 -312.059318)
					(end 7.502906 -311.55132)
				)
				(arc
					(start 7.259066 -311.55132)
					(mid 6.992366 -311.815492)
					(end 6.725666 -311.55132)
				)
				(arc
					(start 6.725666 -311.54878)
					(mid 6.992366 -311.28208)
					(end 7.259066 -311.54878)
				)
				(xy 7.502906 -311.54878) (xy 7.502906 -310.73852)
				(arc
					(start 7.259066 -310.73852)
					(mid 6.992366 -311.002692)
					(end 6.725666 -310.73852)
				)
				(arc
					(start 6.725666 -310.73598)
					(mid 6.992366 -310.46928)
					(end 7.259066 -310.73598)
				)
			)
		)
	)
	(zone
		(layers "B.Cu" "In2.Cu")
		(hatch none 0.5)
		(connect_pads
			(clearance 0)
		)
		(min_thickness 0.25)
		(keepout
			(tracks not_allowed)
			(vias allowed)
			(pads allowed)
			(copperpour not_allowed)
			(footprints allowed)
		)
		(placement
			(enabled no)
			(sheetname "")
		)
		(fill yes
			(thermal_gap 0.5)
			(thermal_bridge_width 0.5)
			(island_removal_mode 0)
		)
		(polygon
			(pts
				(arc
					(start 7.502906 -223.897698)
					(mid 6.992366 -223.387158)
					(end 6.481826 -223.897698)
				)
				(arc
					(start 6.481826 -224.710498)
					(mid 6.991096 -225.221036)
					(end 7.502906 -224.713038)
				)
				(arc
					(start 7.259066 -224.713038)
					(mid 6.992366 -224.97721)
					(end 6.725666 -224.713038)
				)
				(arc
					(start 6.725666 -224.710498)
					(mid 6.992366 -224.443798)
					(end 7.259066 -224.710498)
				)
				(xy 7.502906 -224.710498) (xy 7.502906 -223.900238)
				(arc
					(start 7.259066 -223.900238)
					(mid 6.992366 -224.16441)
					(end 6.725666 -223.900238)
				)
				(arc
					(start 6.725666 -223.897698)
					(mid 6.992366 -223.630998)
					(end 7.259066 -223.897698)
				)
			)
		)
	)
	(zone
		(layers "B.Cu" "In2.Cu")
		(hatch none 0.5)
		(connect_pads
			(clearance 0)
		)
		(min_thickness 0.25)
		(keepout
			(tracks not_allowed)
			(vias allowed)
			(pads allowed)
			(copperpour not_allowed)
			(footprints allowed)
		)
		(placement
			(enabled no)
			(sheetname "")
		)
		(fill yes
			(thermal_gap 0.5)
			(thermal_bridge_width 0.5)
			(island_removal_mode 0)
		)
		(polygon
			(pts
				(arc
					(start 35.84067 -488.983782)
					(mid 35.33013 -488.473242)
					(end 34.81959 -488.983782)
				)
				(arc
					(start 34.81959 -489.796328)
					(mid 35.328733 -490.30712)
					(end 35.84067 -489.799122)
				)
				(arc
					(start 35.59683 -489.799122)
					(mid 35.33013 -490.063294)
					(end 35.06343 -489.799122)
				)
				(arc
					(start 35.06343 -489.796582)
					(mid 35.33013 -489.529882)
					(end 35.59683 -489.796582)
				)
				(xy 35.84067 -489.796582) (xy 35.84067 -488.986322)
				(arc
					(start 35.59683 -488.986322)
					(mid 35.33013 -489.250494)
					(end 35.06343 -488.986322)
				)
				(arc
					(start 35.06343 -488.983782)
					(mid 35.33013 -488.717082)
					(end 35.59683 -488.983782)
				)
			)
		)
	)
	(zone
		(layers "B.Cu" "In2.Cu")
		(hatch none 0.5)
		(connect_pads
			(clearance 0)
		)
		(min_thickness 0.25)
		(keepout
			(tracks not_allowed)
			(vias allowed)
			(pads allowed)
			(copperpour not_allowed)
			(footprints allowed)
		)
		(placement
			(enabled no)
			(sheetname "")
		)
		(fill yes
			(thermal_gap 0.5)
			(thermal_bridge_width 0.5)
			(island_removal_mode 0)
		)
		(polygon
			(pts
				(arc
					(start 35.84067 -175.183546)
					(mid 35.33013 -174.673006)
					(end 34.81959 -175.183546)
				)
				(arc
					(start 34.81959 -175.996346)
					(mid 35.32886 -176.506884)
					(end 35.84067 -175.998886)
				)
				(arc
					(start 35.59683 -175.998886)
					(mid 35.33013 -176.263058)
					(end 35.06343 -175.998886)
				)
				(arc
					(start 35.06343 -175.996346)
					(mid 35.33013 -175.729646)
					(end 35.59683 -175.996346)
				)
				(xy 35.84067 -175.996346) (xy 35.84067 -175.186086)
				(arc
					(start 35.59683 -175.186086)
					(mid 35.33013 -175.450258)
					(end 35.06343 -175.186086)
				)
				(arc
					(start 35.06343 -175.183546)
					(mid 35.33013 -174.916846)
					(end 35.59683 -175.183546)
				)
			)
		)
	)
	(zone
		(layers "B.Cu" "In2.Cu")
		(hatch none 0.5)
		(connect_pads
			(clearance 0)
		)
		(min_thickness 0.25)
		(keepout
			(tracks not_allowed)
			(vias allowed)
			(pads allowed)
			(copperpour not_allowed)
			(footprints allowed)
		)
		(placement
			(enabled no)
			(sheetname "")
		)
		(fill yes
			(thermal_gap 0.5)
			(thermal_bridge_width 0.5)
			(island_removal_mode 0)
		)
		(polygon
			(pts
				(arc
					(start 35.84067 -376.383804)
					(mid 35.33013 -375.873264)
					(end 34.81959 -376.383804)
				)
				(arc
					(start 34.81959 -377.196604)
					(mid 35.32886 -377.707142)
					(end 35.84067 -377.199144)
				)
				(arc
					(start 35.59683 -377.199144)
					(mid 35.33013 -377.463316)
					(end 35.06343 -377.199144)
				)
				(arc
					(start 35.06343 -377.196604)
					(mid 35.33013 -376.929904)
					(end 35.59683 -377.196604)
				)
				(xy 35.84067 -377.196604) (xy 35.84067 -376.386344)
				(arc
					(start 35.59683 -376.386344)
					(mid 35.33013 -376.650516)
					(end 35.06343 -376.386344)
				)
				(arc
					(start 35.06343 -376.383804)
					(mid 35.33013 -376.117104)
					(end 35.59683 -376.383804)
				)
			)
		)
	)
	(zone
		(layers "B.Cu" "In2.Cu")
		(hatch none 0.5)
		(connect_pads
			(clearance 0)
		)
		(min_thickness 0.25)
		(keepout
			(tracks not_allowed)
			(vias allowed)
			(pads allowed)
			(copperpour not_allowed)
			(footprints allowed)
		)
		(placement
			(enabled no)
			(sheetname "")
		)
		(fill yes
			(thermal_gap 0.5)
			(thermal_bridge_width 0.5)
			(island_removal_mode 0)
		)
		(polygon
			(pts
				(arc
					(start 35.84067 -76.98359)
					(mid 35.33013 -76.47305)
					(end 34.81959 -76.98359)
				)
				(arc
					(start 34.81959 -77.79639)
					(mid 35.32886 -78.306928)
					(end 35.84067 -77.79893)
				)
				(arc
					(start 35.59683 -77.79893)
					(mid 35.33013 -78.063102)
					(end 35.06343 -77.79893)
				)
				(arc
					(start 35.06343 -77.79639)
					(mid 35.33013 -77.52969)
					(end 35.59683 -77.79639)
				)
				(xy 35.84067 -77.79639) (xy 35.84067 -76.98613)
				(arc
					(start 35.59683 -76.98613)
					(mid 35.33013 -77.250302)
					(end 35.06343 -76.98613)
				)
				(arc
					(start 35.06343 -76.98359)
					(mid 35.33013 -76.71689)
					(end 35.59683 -76.98359)
				)
			)
		)
	)
	(zone
		(layers "B.Cu" "In2.Cu")
		(hatch none 0.5)
		(connect_pads
			(clearance 0)
		)
		(min_thickness 0.25)
		(keepout
			(tracks not_allowed)
			(vias allowed)
			(pads allowed)
			(copperpour not_allowed)
			(footprints allowed)
		)
		(placement
			(enabled no)
			(sheetname "")
		)
		(fill yes
			(thermal_gap 0.5)
			(thermal_bridge_width 0.5)
			(island_removal_mode 0)
		)
		(polygon
			(pts
				(arc
					(start 7.502906 -353.135946)
					(mid 6.992366 -352.625406)
					(end 6.481826 -353.135946)
				)
				(arc
					(start 6.481826 -353.948746)
					(mid 6.991096 -354.459284)
					(end 7.502906 -353.951286)
				)
				(arc
					(start 7.259066 -353.951286)
					(mid 6.992366 -354.215458)
					(end 6.725666 -353.951286)
				)
				(arc
					(start 6.725666 -353.948746)
					(mid 6.992366 -353.682046)
					(end 7.259066 -353.948746)
				)
				(xy 7.502906 -353.948746) (xy 7.502906 -353.138486)
				(arc
					(start 7.259066 -353.138486)
					(mid 6.992366 -353.402658)
					(end 6.725666 -353.138486)
				)
				(arc
					(start 6.725666 -353.135946)
					(mid 6.992366 -352.869246)
					(end 7.259066 -353.135946)
				)
			)
		)
	)
	(zone
		(layers "B.Cu" "In2.Cu")
		(hatch none 0.5)
		(connect_pads
			(clearance 0)
		)
		(min_thickness 0.25)
		(keepout
			(tracks not_allowed)
			(vias allowed)
			(pads allowed)
			(copperpour not_allowed)
			(footprints allowed)
		)
		(placement
			(enabled no)
			(sheetname "")
		)
		(fill yes
			(thermal_gap 0.5)
			(thermal_bridge_width 0.5)
			(island_removal_mode 0)
		)
		(polygon
			(pts
				(arc
					(start 7.502906 -349.9358)
					(mid 6.992366 -349.42526)
					(end 6.481826 -349.9358)
				)
				(arc
					(start 6.481826 -350.748346)
					(mid 6.990969 -351.259138)
					(end 7.502906 -350.75114)
				)
				(arc
					(start 7.259066 -350.75114)
					(mid 6.992366 -351.015312)
					(end 6.725666 -350.75114)
				)
				(arc
					(start 6.725666 -350.7486)
					(mid 6.992366 -350.4819)
					(end 7.259066 -350.7486)
				)
				(xy 7.502906 -350.7486) (xy 7.502906 -349.93834)
				(arc
					(start 7.259066 -349.93834)
					(mid 6.992366 -350.202512)
					(end 6.725666 -349.93834)
				)
				(arc
					(start 6.725666 -349.9358)
					(mid 6.992366 -349.6691)
					(end 7.259066 -349.9358)
				)
			)
		)
	)
	(zone
		(layers "B.Cu" "In2.Cu")
		(hatch none 0.5)
		(connect_pads
			(clearance 0)
		)
		(min_thickness 0.25)
		(keepout
			(tracks not_allowed)
			(vias allowed)
			(pads allowed)
			(copperpour not_allowed)
			(footprints allowed)
		)
		(placement
			(enabled no)
			(sheetname "")
		)
		(fill yes
			(thermal_gap 0.5)
			(thermal_bridge_width 0.5)
			(island_removal_mode 0)
		)
		(polygon
			(pts
				(arc
					(start 7.502906 -436.784242)
					(mid 6.992366 -436.273702)
					(end 6.481826 -436.784242)
				)
				(arc
					(start 6.481826 -437.596788)
					(mid 6.990969 -438.10758)
					(end 7.502906 -437.599582)
				)
				(arc
					(start 7.259066 -437.599582)
					(mid 6.992366 -437.863754)
					(end 6.725666 -437.599582)
				)
				(arc
					(start 6.725666 -437.597042)
					(mid 6.992366 -437.330342)
					(end 7.259066 -437.597042)
				)
				(xy 7.502906 -437.597042) (xy 7.502906 -436.786782)
				(arc
					(start 7.259066 -436.786782)
					(mid 6.992366 -437.050954)
					(end 6.725666 -436.786782)
				)
				(arc
					(start 6.725666 -436.784242)
					(mid 6.992366 -436.517542)
					(end 7.259066 -436.784242)
				)
			)
		)
	)
	(zone
		(layers "B.Cu" "In2.Cu")
		(hatch none 0.5)
		(connect_pads
			(clearance 0)
		)
		(min_thickness 0.25)
		(keepout
			(tracks not_allowed)
			(vias allowed)
			(pads allowed)
			(copperpour not_allowed)
			(footprints allowed)
		)
		(placement
			(enabled no)
			(sheetname "")
		)
		(fill yes
			(thermal_gap 0.5)
			(thermal_bridge_width 0.5)
			(island_removal_mode 0)
		)
		(polygon
			(pts
				(arc
					(start 220.840554 -72.183498)
					(mid 220.330014 -71.672958)
					(end 219.819474 -72.183498)
				)
				(arc
					(start 219.819474 -72.996298)
					(mid 220.328744 -73.506836)
					(end 220.840554 -72.998838)
				)
				(arc
					(start 220.596714 -72.998838)
					(mid 220.330014 -73.26301)
					(end 220.063314 -72.998838)
				)
				(arc
					(start 220.063314 -72.996298)
					(mid 220.330014 -72.729598)
					(end 220.596714 -72.996298)
				)
				(xy 220.840554 -72.996298) (xy 220.840554 -72.186038)
				(arc
					(start 220.596714 -72.186038)
					(mid 220.330014 -72.45021)
					(end 220.063314 -72.186038)
				)
				(arc
					(start 220.063314 -72.183498)
					(mid 220.330014 -71.916798)
					(end 220.596714 -72.183498)
				)
			)
		)
	)
	(zone
		(layers "B.Cu" "In2.Cu")
		(hatch none 0.5)
		(connect_pads
			(clearance 0)
		)
		(min_thickness 0.25)
		(keepout
			(tracks not_allowed)
			(vias allowed)
			(pads allowed)
			(copperpour not_allowed)
			(footprints allowed)
		)
		(placement
			(enabled no)
			(sheetname "")
		)
		(fill yes
			(thermal_gap 0.5)
			(thermal_bridge_width 0.5)
			(island_removal_mode 0)
		)
		(polygon
			(pts
				(arc
					(start 27.18054 -141.603476)
					(mid 26.67 -141.092936)
					(end 26.15946 -141.603476)
				)
				(arc
					(start 26.15946 -142.416022)
					(mid 26.668603 -142.926814)
					(end 27.18054 -142.418816)
				)
				(arc
					(start 26.9367 -142.418816)
					(mid 26.67 -142.682988)
					(end 26.4033 -142.418816)
				)
				(arc
					(start 26.4033 -142.416276)
					(mid 26.67 -142.149576)
					(end 26.9367 -142.416276)
				)
				(xy 27.18054 -142.416276) (xy 27.18054 -141.606016)
				(arc
					(start 26.9367 -141.606016)
					(mid 26.67 -141.870188)
					(end 26.4033 -141.606016)
				)
				(arc
					(start 26.4033 -141.603476)
					(mid 26.67 -141.336776)
					(end 26.9367 -141.603476)
				)
			)
		)
	)
	(zone
		(layers "B.Cu" "In2.Cu")
		(hatch none 0.5)
		(connect_pads
			(clearance 0)
		)
		(min_thickness 0.25)
		(keepout
			(tracks not_allowed)
			(vias allowed)
			(pads allowed)
			(copperpour not_allowed)
			(footprints allowed)
		)
		(placement
			(enabled no)
			(sheetname "")
		)
		(fill yes
			(thermal_gap 0.5)
			(thermal_bridge_width 0.5)
			(island_removal_mode 0)
		)
		(polygon
			(pts
				(arc
					(start 35.84067 -67.38366)
					(mid 35.33013 -66.87312)
					(end 34.81959 -67.38366)
				)
				(arc
					(start 34.81959 -68.19646)
					(mid 35.32886 -68.706998)
					(end 35.84067 -68.199)
				)
				(arc
					(start 35.59683 -68.199)
					(mid 35.33013 -68.463172)
					(end 35.06343 -68.199)
				)
				(arc
					(start 35.06343 -68.19646)
					(mid 35.33013 -67.92976)
					(end 35.59683 -68.19646)
				)
				(xy 35.84067 -68.19646) (xy 35.84067 -67.3862)
				(arc
					(start 35.59683 -67.3862)
					(mid 35.33013 -67.650372)
					(end 35.06343 -67.3862)
				)
				(arc
					(start 35.06343 -67.38366)
					(mid 35.33013 -67.11696)
					(end 35.59683 -67.38366)
				)
			)
		)
	)
	(zone
		(layers "B.Cu" "In2.Cu")
		(hatch none 0.5)
		(connect_pads
			(clearance 0)
		)
		(min_thickness 0.25)
		(keepout
			(tracks not_allowed)
			(vias allowed)
			(pads allowed)
			(copperpour not_allowed)
			(footprints allowed)
		)
		(placement
			(enabled no)
			(sheetname "")
		)
		(fill yes
			(thermal_gap 0.5)
			(thermal_bridge_width 0.5)
			(island_removal_mode 0)
		)
		(polygon
			(pts
				(arc
					(start 7.502906 -340.38667)
					(mid 6.992366 -339.87613)
					(end 6.481826 -340.38667)
				)
				(arc
					(start 6.481826 -341.19947)
					(mid 6.991096 -341.710008)
					(end 7.502906 -341.20201)
				)
				(arc
					(start 7.259066 -341.20201)
					(mid 6.992366 -341.466182)
					(end 6.725666 -341.20201)
				)
				(arc
					(start 6.725666 -341.19947)
					(mid 6.992366 -340.93277)
					(end 7.259066 -341.19947)
				)
				(xy 7.502906 -341.19947) (xy 7.502906 -340.38921)
				(arc
					(start 7.259066 -340.38921)
					(mid 6.992366 -340.653382)
					(end 6.725666 -340.38921)
				)
				(arc
					(start 6.725666 -340.38667)
					(mid 6.992366 -340.11997)
					(end 7.259066 -340.38667)
				)
			)
		)
	)
	(zone
		(layers "B.Cu" "In2.Cu")
		(hatch none 0.5)
		(connect_pads
			(clearance 0)
		)
		(min_thickness 0.25)
		(keepout
			(tracks not_allowed)
			(vias allowed)
			(pads allowed)
			(copperpour not_allowed)
			(footprints allowed)
		)
		(placement
			(enabled no)
			(sheetname "")
		)
		(fill yes
			(thermal_gap 0.5)
			(thermal_bridge_width 0.5)
			(island_removal_mode 0)
		)
		(polygon
			(pts
				(arc
					(start 220.840554 -67.38366)
					(mid 220.330014 -66.87312)
					(end 219.819474 -67.38366)
				)
				(arc
					(start 219.819474 -68.19646)
					(mid 220.328744 -68.706998)
					(end 220.840554 -68.199)
				)
				(arc
					(start 220.596714 -68.199)
					(mid 220.330014 -68.463172)
					(end 220.063314 -68.199)
				)
				(arc
					(start 220.063314 -68.19646)
					(mid 220.330014 -67.92976)
					(end 220.596714 -68.19646)
				)
				(xy 220.840554 -68.19646) (xy 220.840554 -67.3862)
				(arc
					(start 220.596714 -67.3862)
					(mid 220.330014 -67.650372)
					(end 220.063314 -67.3862)
				)
				(arc
					(start 220.063314 -67.38366)
					(mid 220.330014 -67.11696)
					(end 220.596714 -67.38366)
				)
			)
		)
	)
	(zone
		(layers "B.Cu" "In2.Cu")
		(hatch none 0.5)
		(connect_pads
			(clearance 0)
		)
		(min_thickness 0.25)
		(keepout
			(tracks not_allowed)
			(vias allowed)
			(pads allowed)
			(copperpour not_allowed)
			(footprints allowed)
		)
		(placement
			(enabled no)
			(sheetname "")
		)
		(fill yes
			(thermal_gap 0.5)
			(thermal_bridge_width 0.5)
			(island_removal_mode 0)
		)
		(polygon
			(pts
				(arc
					(start 220.840554 -363.583728)
					(mid 220.330014 -363.073188)
					(end 219.819474 -363.583728)
				)
				(arc
					(start 219.819474 -364.396528)
					(mid 220.328744 -364.907066)
					(end 220.840554 -364.399068)
				)
				(arc
					(start 220.596714 -364.399068)
					(mid 220.330014 -364.66324)
					(end 220.063314 -364.399068)
				)
				(arc
					(start 220.063314 -364.396528)
					(mid 220.330014 -364.129828)
					(end 220.596714 -364.396528)
				)
				(xy 220.840554 -364.396528) (xy 220.840554 -363.586268)
				(arc
					(start 220.596714 -363.586268)
					(mid 220.330014 -363.85044)
					(end 220.063314 -363.586268)
				)
				(arc
					(start 220.063314 -363.583728)
					(mid 220.330014 -363.317028)
					(end 220.596714 -363.583728)
				)
			)
		)
	)
	(zone
		(layers "B.Cu" "In2.Cu")
		(hatch none 0.5)
		(connect_pads
			(clearance 0)
		)
		(min_thickness 0.25)
		(keepout
			(tracks not_allowed)
			(vias allowed)
			(pads allowed)
			(copperpour not_allowed)
			(footprints allowed)
		)
		(placement
			(enabled no)
			(sheetname "")
		)
		(fill yes
			(thermal_gap 0.5)
			(thermal_bridge_width 0.5)
			(island_removal_mode 0)
		)
		(polygon
			(pts
				(arc
					(start 35.84067 -157.583632)
					(mid 35.33013 -157.073092)
					(end 34.81959 -157.583632)
				)
				(arc
					(start 34.81959 -158.396432)
					(mid 35.32886 -158.90697)
					(end 35.84067 -158.398972)
				)
				(arc
					(start 35.59683 -158.398972)
					(mid 35.33013 -158.663144)
					(end 35.06343 -158.398972)
				)
				(arc
					(start 35.06343 -158.396432)
					(mid 35.33013 -158.129732)
					(end 35.59683 -158.396432)
				)
				(xy 35.84067 -158.396432) (xy 35.84067 -157.586172)
				(arc
					(start 35.59683 -157.586172)
					(mid 35.33013 -157.850344)
					(end 35.06343 -157.586172)
				)
				(arc
					(start 35.06343 -157.583632)
					(mid 35.33013 -157.316932)
					(end 35.59683 -157.583632)
				)
			)
		)
	)
	(zone
		(layers "B.Cu" "In2.Cu")
		(hatch none 0.5)
		(connect_pads
			(clearance 0)
		)
		(min_thickness 0.25)
		(keepout
			(tracks not_allowed)
			(vias allowed)
			(pads allowed)
			(copperpour not_allowed)
			(footprints allowed)
		)
		(placement
			(enabled no)
			(sheetname "")
		)
		(fill yes
			(thermal_gap 0.5)
			(thermal_bridge_width 0.5)
			(island_removal_mode 0)
		)
		(polygon
			(pts
				(arc
					(start 7.502906 -278.78659)
					(mid 6.992366 -278.27605)
					(end 6.481826 -278.78659)
				)
				(arc
					(start 6.481826 -279.59939)
					(mid 6.991096 -280.109928)
					(end 7.502906 -279.60193)
				)
				(arc
					(start 7.259066 -279.60193)
					(mid 6.992366 -279.866102)
					(end 6.725666 -279.60193)
				)
				(arc
					(start 6.725666 -279.59939)
					(mid 6.992366 -279.33269)
					(end 7.259066 -279.59939)
				)
				(xy 7.502906 -279.59939) (xy 7.502906 -278.78913)
				(arc
					(start 7.259066 -278.78913)
					(mid 6.992366 -279.053302)
					(end 6.725666 -278.78913)
				)
				(arc
					(start 6.725666 -278.78659)
					(mid 6.992366 -278.51989)
					(end 7.259066 -278.78659)
				)
			)
		)
	)
	(zone
		(layers "B.Cu" "In2.Cu")
		(hatch none 0.5)
		(connect_pads
			(clearance 0)
		)
		(min_thickness 0.25)
		(keepout
			(tracks not_allowed)
			(vias allowed)
			(pads allowed)
			(copperpour not_allowed)
			(footprints allowed)
		)
		(placement
			(enabled no)
			(sheetname "")
		)
		(fill yes
			(thermal_gap 0.5)
			(thermal_bridge_width 0.5)
			(island_removal_mode 0)
		)
		(polygon
			(pts
				(arc
					(start 27.18054 -231.803448)
					(mid 26.67 -231.292908)
					(end 26.15946 -231.803448)
				)
				(arc
					(start 26.15946 -232.615994)
					(mid 26.668603 -233.126786)
					(end 27.18054 -232.618788)
				)
				(arc
					(start 26.9367 -232.618788)
					(mid 26.67 -232.88296)
					(end 26.4033 -232.618788)
				)
				(arc
					(start 26.4033 -232.616248)
					(mid 26.67 -232.349548)
					(end 26.9367 -232.616248)
				)
				(xy 27.18054 -232.616248) (xy 27.18054 -231.805988)
				(arc
					(start 26.9367 -231.805988)
					(mid 26.67 -232.07016)
					(end 26.4033 -231.805988)
				)
				(arc
					(start 26.4033 -231.803448)
					(mid 26.67 -231.536748)
					(end 26.9367 -231.803448)
				)
			)
		)
	)
	(zone
		(layers "B.Cu" "In2.Cu")
		(hatch none 0.5)
		(connect_pads
			(clearance 0)
		)
		(min_thickness 0.25)
		(keepout
			(tracks not_allowed)
			(vias allowed)
			(pads allowed)
			(copperpour not_allowed)
			(footprints allowed)
		)
		(placement
			(enabled no)
			(sheetname "")
		)
		(fill yes
			(thermal_gap 0.5)
			(thermal_bridge_width 0.5)
			(island_removal_mode 0)
		)
		(polygon
			(pts
				(arc
					(start 7.502906 -159.186626)
					(mid 6.992366 -158.676086)
					(end 6.481826 -159.186626)
				)
				(arc
					(start 6.481826 -159.999426)
					(mid 6.991096 -160.509964)
					(end 7.502906 -160.001966)
				)
				(arc
					(start 7.259066 -160.001966)
					(mid 6.992366 -160.266138)
					(end 6.725666 -160.001966)
				)
				(arc
					(start 6.725666 -159.999426)
					(mid 6.992366 -159.732726)
					(end 7.259066 -159.999426)
				)
				(xy 7.502906 -159.999426) (xy 7.502906 -159.189166)
				(arc
					(start 7.259066 -159.189166)
					(mid 6.992366 -159.453338)
					(end 6.725666 -159.189166)
				)
				(arc
					(start 6.725666 -159.186626)
					(mid 6.992366 -158.919926)
					(end 7.259066 -159.186626)
				)
			)
		)
	)
	(zone
		(layers "B.Cu" "In2.Cu")
		(hatch none 0.5)
		(connect_pads
			(clearance 0)
		)
		(min_thickness 0.25)
		(keepout
			(tracks not_allowed)
			(vias allowed)
			(pads allowed)
			(copperpour not_allowed)
			(footprints allowed)
		)
		(placement
			(enabled no)
			(sheetname "")
		)
		(fill yes
			(thermal_gap 0.5)
			(thermal_bridge_width 0.5)
			(island_removal_mode 0)
		)
		(polygon
			(pts
				(arc
					(start 7.502906 -415.135822)
					(mid 6.992366 -414.625282)
					(end 6.481826 -415.135822)
				)
				(arc
					(start 6.481826 -415.948622)
					(mid 6.991096 -416.45916)
					(end 7.502906 -415.951162)
				)
				(arc
					(start 7.259066 -415.951162)
					(mid 6.992366 -416.215334)
					(end 6.725666 -415.951162)
				)
				(arc
					(start 6.725666 -415.948622)
					(mid 6.992366 -415.681922)
					(end 7.259066 -415.948622)
				)
				(xy 7.502906 -415.948622) (xy 7.502906 -415.138362)
				(arc
					(start 7.259066 -415.138362)
					(mid 6.992366 -415.402534)
					(end 6.725666 -415.138362)
				)
				(arc
					(start 6.725666 -415.135822)
					(mid 6.992366 -414.869122)
					(end 7.259066 -415.135822)
				)
			)
		)
	)
	(zone
		(layers "B.Cu" "In2.Cu")
		(hatch none 0.5)
		(connect_pads
			(clearance 0)
		)
		(min_thickness 0.25)
		(keepout
			(tracks not_allowed)
			(vias allowed)
			(pads allowed)
			(copperpour not_allowed)
			(footprints allowed)
		)
		(placement
			(enabled no)
			(sheetname "")
		)
		(fill yes
			(thermal_gap 0.5)
			(thermal_bridge_width 0.5)
			(island_removal_mode 0)
		)
		(polygon
			(pts
				(arc
					(start 7.502906 -301.135796)
					(mid 6.992366 -300.625256)
					(end 6.481826 -301.135796)
				)
				(arc
					(start 6.481826 -301.948342)
					(mid 6.990969 -302.459134)
					(end 7.502906 -301.951136)
				)
				(arc
					(start 7.259066 -301.951136)
					(mid 6.992366 -302.215308)
					(end 6.725666 -301.951136)
				)
				(arc
					(start 6.725666 -301.948596)
					(mid 6.992366 -301.681896)
					(end 7.259066 -301.948596)
				)
				(xy 7.502906 -301.948596) (xy 7.502906 -301.138336)
				(arc
					(start 7.259066 -301.138336)
					(mid 6.992366 -301.402508)
					(end 6.725666 -301.138336)
				)
				(arc
					(start 6.725666 -301.135796)
					(mid 6.992366 -300.869096)
					(end 7.259066 -301.135796)
				)
			)
		)
	)
	(zone
		(layers "B.Cu" "In2.Cu")
		(hatch none 0.5)
		(connect_pads
			(clearance 0)
		)
		(min_thickness 0.25)
		(keepout
			(tracks not_allowed)
			(vias allowed)
			(pads allowed)
			(copperpour not_allowed)
			(footprints allowed)
		)
		(placement
			(enabled no)
			(sheetname "")
		)
		(fill yes
			(thermal_gap 0.5)
			(thermal_bridge_width 0.5)
			(island_removal_mode 0)
		)
		(polygon
			(pts
				(arc
					(start 7.502906 -346.735908)
					(mid 6.992366 -346.225368)
					(end 6.481826 -346.735908)
				)
				(arc
					(start 6.481826 -347.548454)
					(mid 6.990969 -348.059246)
					(end 7.502906 -347.551248)
				)
				(arc
					(start 7.259066 -347.551248)
					(mid 6.992366 -347.81542)
					(end 6.725666 -347.551248)
				)
				(arc
					(start 6.725666 -347.548708)
					(mid 6.992366 -347.282008)
					(end 7.259066 -347.548708)
				)
				(xy 7.502906 -347.548708) (xy 7.502906 -346.738448)
				(arc
					(start 7.259066 -346.738448)
					(mid 6.992366 -347.00262)
					(end 6.725666 -346.738448)
				)
				(arc
					(start 6.725666 -346.735908)
					(mid 6.992366 -346.469208)
					(end 7.259066 -346.735908)
				)
			)
		)
	)
	(zone
		(layers "B.Cu" "In2.Cu")
		(hatch none 0.5)
		(connect_pads
			(clearance 0)
		)
		(min_thickness 0.25)
		(keepout
			(tracks not_allowed)
			(vias allowed)
			(pads allowed)
			(copperpour not_allowed)
			(footprints allowed)
		)
		(placement
			(enabled no)
			(sheetname "")
		)
		(fill yes
			(thermal_gap 0.5)
			(thermal_bridge_width 0.5)
			(island_removal_mode 0)
		)
		(polygon
			(pts
				(arc
					(start 27.18054 -450.60362)
					(mid 26.67 -450.09308)
					(end 26.15946 -450.60362)
				)
				(arc
					(start 26.15946 -451.41642)
					(mid 26.66873 -451.926958)
					(end 27.18054 -451.41896)
				)
				(arc
					(start 26.9367 -451.41896)
					(mid 26.67 -451.683132)
					(end 26.4033 -451.41896)
				)
				(arc
					(start 26.4033 -451.41642)
					(mid 26.67 -451.14972)
					(end 26.9367 -451.41642)
				)
				(xy 27.18054 -451.41642) (xy 27.18054 -450.60616)
				(arc
					(start 26.9367 -450.60616)
					(mid 26.67 -450.870332)
					(end 26.4033 -450.60616)
				)
				(arc
					(start 26.4033 -450.60362)
					(mid 26.67 -450.33692)
					(end 26.9367 -450.60362)
				)
			)
		)
	)
	(zone
		(layers "B.Cu" "In2.Cu")
		(hatch none 0.5)
		(connect_pads
			(clearance 0)
		)
		(min_thickness 0.25)
		(keepout
			(tracks not_allowed)
			(vias allowed)
			(pads allowed)
			(copperpour not_allowed)
			(footprints allowed)
		)
		(placement
			(enabled no)
			(sheetname "")
		)
		(fill yes
			(thermal_gap 0.5)
			(thermal_bridge_width 0.5)
			(island_removal_mode 0)
		)
		(polygon
			(pts
				(arc
					(start 220.840554 -484.18369)
					(mid 220.330014 -483.67315)
					(end 219.819474 -484.18369)
				)
				(arc
					(start 219.819474 -484.99649)
					(mid 220.328744 -485.507028)
					(end 220.840554 -484.99903)
				)
				(arc
					(start 220.596714 -484.99903)
					(mid 220.330014 -485.263202)
					(end 220.063314 -484.99903)
				)
				(arc
					(start 220.063314 -484.99649)
					(mid 220.330014 -484.72979)
					(end 220.596714 -484.99649)
				)
				(xy 220.840554 -484.99649) (xy 220.840554 -484.18623)
				(arc
					(start 220.596714 -484.18623)
					(mid 220.330014 -484.450402)
					(end 220.063314 -484.18623)
				)
				(arc
					(start 220.063314 -484.18369)
					(mid 220.330014 -483.91699)
					(end 220.596714 -484.18369)
				)
			)
		)
	)
	(zone
		(layers "B.Cu" "In2.Cu")
		(hatch none 0.5)
		(connect_pads
			(clearance 0)
		)
		(min_thickness 0.25)
		(keepout
			(tracks not_allowed)
			(vias allowed)
			(pads allowed)
			(copperpour not_allowed)
			(footprints allowed)
		)
		(placement
			(enabled no)
			(sheetname "")
		)
		(fill yes
			(thermal_gap 0.5)
			(thermal_bridge_width 0.5)
			(island_removal_mode 0)
		)
		(polygon
			(pts
				(arc
					(start 7.502906 -390.33577)
					(mid 6.992366 -389.82523)
					(end 6.481826 -390.33577)
				)
				(arc
					(start 6.481826 -391.14857)
					(mid 6.991096 -391.659108)
					(end 7.502906 -391.15111)
				)
				(arc
					(start 7.259066 -391.15111)
					(mid 6.992366 -391.415282)
					(end 6.725666 -391.15111)
				)
				(arc
					(start 6.725666 -391.14857)
					(mid 6.992366 -390.88187)
					(end 7.259066 -391.14857)
				)
				(xy 7.502906 -391.14857) (xy 7.502906 -390.33831)
				(arc
					(start 7.259066 -390.33831)
					(mid 6.992366 -390.602482)
					(end 6.725666 -390.33831)
				)
				(arc
					(start 6.725666 -390.33577)
					(mid 6.992366 -390.06907)
					(end 7.259066 -390.33577)
				)
			)
		)
	)
	(zone
		(layers "B.Cu" "In2.Cu")
		(hatch none 0.5)
		(connect_pads
			(clearance 0)
		)
		(min_thickness 0.25)
		(keepout
			(tracks not_allowed)
			(vias allowed)
			(pads allowed)
			(copperpour not_allowed)
			(footprints allowed)
		)
		(placement
			(enabled no)
			(sheetname "")
		)
		(fill yes
			(thermal_gap 0.5)
			(thermal_bridge_width 0.5)
			(island_removal_mode 0)
		)
		(polygon
			(pts
				(arc
					(start 35.84067 -282.983686)
					(mid 35.33013 -282.473146)
					(end 34.81959 -282.983686)
				)
				(arc
					(start 34.81959 -283.796486)
					(mid 35.32886 -284.307024)
					(end 35.84067 -283.799026)
				)
				(arc
					(start 35.59683 -283.799026)
					(mid 35.33013 -284.063198)
					(end 35.06343 -283.799026)
				)
				(arc
					(start 35.06343 -283.796486)
					(mid 35.33013 -283.529786)
					(end 35.59683 -283.796486)
				)
				(xy 35.84067 -283.796486) (xy 35.84067 -282.986226)
				(arc
					(start 35.59683 -282.986226)
					(mid 35.33013 -283.250398)
					(end 35.06343 -282.986226)
				)
				(arc
					(start 35.06343 -282.983686)
					(mid 35.33013 -282.716986)
					(end 35.59683 -282.983686)
				)
			)
		)
	)
	(zone
		(layers "B.Cu" "In2.Cu")
		(hatch none 0.5)
		(connect_pads
			(clearance 0)
		)
		(min_thickness 0.25)
		(keepout
			(tracks not_allowed)
			(vias allowed)
			(pads allowed)
			(copperpour not_allowed)
			(footprints allowed)
		)
		(placement
			(enabled no)
			(sheetname "")
		)
		(fill yes
			(thermal_gap 0.5)
			(thermal_bridge_width 0.5)
			(island_removal_mode 0)
		)
		(polygon
			(pts
				(arc
					(start 220.840554 -385.983734)
					(mid 220.330014 -385.473194)
					(end 219.819474 -385.983734)
				)
				(arc
					(start 219.819474 -386.796534)
					(mid 220.328744 -387.307072)
					(end 220.840554 -386.799074)
				)
				(arc
					(start 220.596714 -386.799074)
					(mid 220.330014 -387.063246)
					(end 220.063314 -386.799074)
				)
				(arc
					(start 220.063314 -386.796534)
					(mid 220.330014 -386.529834)
					(end 220.596714 -386.796534)
				)
				(xy 220.840554 -386.796534) (xy 220.840554 -385.986274)
				(arc
					(start 220.596714 -385.986274)
					(mid 220.330014 -386.250446)
					(end 220.063314 -385.986274)
				)
				(arc
					(start 220.063314 -385.983734)
					(mid 220.330014 -385.717034)
					(end 220.596714 -385.983734)
				)
			)
		)
	)
	(zone
		(layers "B.Cu" "In2.Cu")
		(hatch none 0.5)
		(connect_pads
			(clearance 0)
		)
		(min_thickness 0.25)
		(keepout
			(tracks not_allowed)
			(vias allowed)
			(pads allowed)
			(copperpour not_allowed)
			(footprints allowed)
		)
		(placement
			(enabled no)
			(sheetname "")
		)
		(fill yes
			(thermal_gap 0.5)
			(thermal_bridge_width 0.5)
			(island_removal_mode 0)
		)
		(polygon
			(pts
				(arc
					(start 7.502906 -217.485214)
					(mid 6.992366 -216.974674)
					(end 6.481826 -217.485214)
				)
				(arc
					(start 6.481826 -218.298014)
					(mid 6.991096 -218.808552)
					(end 7.502906 -218.300554)
				)
				(arc
					(start 7.259066 -218.300554)
					(mid 6.992366 -218.564726)
					(end 6.725666 -218.300554)
				)
				(arc
					(start 6.725666 -218.298014)
					(mid 6.992366 -218.031314)
					(end 7.259066 -218.298014)
				)
				(xy 7.502906 -218.298014) (xy 7.502906 -217.487754)
				(arc
					(start 7.259066 -217.487754)
					(mid 6.992366 -217.751926)
					(end 6.725666 -217.487754)
				)
				(arc
					(start 6.725666 -217.485214)
					(mid 6.992366 -217.218514)
					(end 7.259066 -217.485214)
				)
			)
		)
	)
	(zone
		(layers "B.Cu" "In2.Cu")
		(hatch none 0.5)
		(connect_pads
			(clearance 0)
		)
		(min_thickness 0.25)
		(keepout
			(tracks not_allowed)
			(vias allowed)
			(pads allowed)
			(copperpour not_allowed)
			(footprints allowed)
		)
		(placement
			(enabled no)
			(sheetname "")
		)
		(fill yes
			(thermal_gap 0.5)
			(thermal_bridge_width 0.5)
			(island_removal_mode 0)
		)
		(polygon
			(pts
				(arc
					(start 35.84067 -479.383852)
					(mid 35.33013 -478.873312)
					(end 34.81959 -479.383852)
				)
				(arc
					(start 34.81959 -480.196398)
					(mid 35.328733 -480.70719)
					(end 35.84067 -480.199192)
				)
				(arc
					(start 35.59683 -480.199192)
					(mid 35.33013 -480.463364)
					(end 35.06343 -480.199192)
				)
				(arc
					(start 35.06343 -480.196652)
					(mid 35.33013 -479.929952)
					(end 35.59683 -480.196652)
				)
				(xy 35.84067 -480.196652) (xy 35.84067 -479.386392)
				(arc
					(start 35.59683 -479.386392)
					(mid 35.33013 -479.650564)
					(end 35.06343 -479.386392)
				)
				(arc
					(start 35.06343 -479.383852)
					(mid 35.33013 -479.117152)
					(end 35.59683 -479.383852)
				)
			)
		)
	)
	(zone
		(layers "B.Cu" "In2.Cu")
		(hatch none 0.5)
		(connect_pads
			(clearance 0)
		)
		(min_thickness 0.25)
		(keepout
			(tracks not_allowed)
			(vias allowed)
			(pads allowed)
			(copperpour not_allowed)
			(footprints allowed)
		)
		(placement
			(enabled no)
			(sheetname "")
		)
		(fill yes
			(thermal_gap 0.5)
			(thermal_bridge_width 0.5)
			(island_removal_mode 0)
		)
		(polygon
			(pts
				(arc
					(start 220.840554 -170.383708)
					(mid 220.330014 -169.873168)
					(end 219.819474 -170.383708)
				)
				(arc
					(start 219.819474 -171.196508)
					(mid 220.328744 -171.707046)
					(end 220.840554 -171.199048)
				)
				(arc
					(start 220.596714 -171.199048)
					(mid 220.330014 -171.46322)
					(end 220.063314 -171.199048)
				)
				(arc
					(start 220.063314 -171.196508)
					(mid 220.330014 -170.929808)
					(end 220.596714 -171.196508)
				)
				(xy 220.840554 -171.196508) (xy 220.840554 -170.386248)
				(arc
					(start 220.596714 -170.386248)
					(mid 220.330014 -170.65042)
					(end 220.063314 -170.386248)
				)
				(arc
					(start 220.063314 -170.383708)
					(mid 220.330014 -170.117008)
					(end 220.596714 -170.383708)
				)
			)
		)
	)
	(zone
		(layers "B.Cu" "In2.Cu")
		(hatch none 0.5)
		(connect_pads
			(clearance 0)
		)
		(min_thickness 0.25)
		(keepout
			(tracks not_allowed)
			(vias allowed)
			(pads allowed)
			(copperpour not_allowed)
			(footprints allowed)
		)
		(placement
			(enabled no)
			(sheetname "")
		)
		(fill yes
			(thermal_gap 0.5)
			(thermal_bridge_width 0.5)
			(island_removal_mode 0)
		)
		(polygon
			(pts
				(arc
					(start 27.18054 -334.803496)
					(mid 26.67 -334.292956)
					(end 26.15946 -334.803496)
				)
				(arc
					(start 26.15946 -335.616042)
					(mid 26.668603 -336.126834)
					(end 27.18054 -335.618836)
				)
				(arc
					(start 26.9367 -335.618836)
					(mid 26.67 -335.883008)
					(end 26.4033 -335.618836)
				)
				(arc
					(start 26.4033 -335.616296)
					(mid 26.67 -335.349596)
					(end 26.9367 -335.616296)
				)
				(xy 27.18054 -335.616296) (xy 27.18054 -334.806036)
				(arc
					(start 26.9367 -334.806036)
					(mid 26.67 -335.070208)
					(end 26.4033 -334.806036)
				)
				(arc
					(start 26.4033 -334.803496)
					(mid 26.67 -334.536796)
					(end 26.9367 -334.803496)
				)
			)
		)
	)
	(zone
		(layers "B.Cu" "In2.Cu")
		(hatch none 0.5)
		(connect_pads
			(clearance 0)
		)
		(min_thickness 0.25)
		(keepout
			(tracks not_allowed)
			(vias allowed)
			(pads allowed)
			(copperpour not_allowed)
			(footprints allowed)
		)
		(placement
			(enabled no)
			(sheetname "")
		)
		(fill yes
			(thermal_gap 0.5)
			(thermal_bridge_width 0.5)
			(island_removal_mode 0)
		)
		(polygon
			(pts
				(arc
					(start 7.502906 -337.186778)
					(mid 6.992366 -336.676238)
					(end 6.481826 -337.186778)
				)
				(arc
					(start 6.481826 -337.999578)
					(mid 6.991096 -338.510116)
					(end 7.502906 -338.002118)
				)
				(arc
					(start 7.259066 -338.002118)
					(mid 6.992366 -338.26629)
					(end 6.725666 -338.002118)
				)
				(arc
					(start 6.725666 -337.999578)
					(mid 6.992366 -337.732878)
					(end 7.259066 -337.999578)
				)
				(xy 7.502906 -337.999578) (xy 7.502906 -337.189318)
				(arc
					(start 7.259066 -337.189318)
					(mid 6.992366 -337.45349)
					(end 6.725666 -337.189318)
				)
				(arc
					(start 6.725666 -337.186778)
					(mid 6.992366 -336.920078)
					(end 7.259066 -337.186778)
				)
			)
		)
	)
	(zone
		(layers "B.Cu" "In2.Cu")
		(hatch none 0.5)
		(connect_pads
			(clearance 0)
		)
		(min_thickness 0.25)
		(keepout
			(tracks not_allowed)
			(vias allowed)
			(pads allowed)
			(copperpour not_allowed)
			(footprints allowed)
		)
		(placement
			(enabled no)
			(sheetname "")
		)
		(fill yes
			(thermal_gap 0.5)
			(thermal_bridge_width 0.5)
			(island_removal_mode 0)
		)
		(polygon
			(pts
				(arc
					(start 35.84067 -466.583776)
					(mid 35.33013 -466.073236)
					(end 34.81959 -466.583776)
				)
				(arc
					(start 34.81959 -467.396322)
					(mid 35.328733 -467.907114)
					(end 35.84067 -467.399116)
				)
				(arc
					(start 35.59683 -467.399116)
					(mid 35.33013 -467.663288)
					(end 35.06343 -467.399116)
				)
				(arc
					(start 35.06343 -467.396576)
					(mid 35.33013 -467.129876)
					(end 35.59683 -467.396576)
				)
				(xy 35.84067 -467.396576) (xy 35.84067 -466.586316)
				(arc
					(start 35.59683 -466.586316)
					(mid 35.33013 -466.850488)
					(end 35.06343 -466.586316)
				)
				(arc
					(start 35.06343 -466.583776)
					(mid 35.33013 -466.317076)
					(end 35.59683 -466.583776)
				)
			)
		)
	)
	(zone
		(layers "B.Cu" "In2.Cu")
		(hatch none 0.5)
		(connect_pads
			(clearance 0)
		)
		(min_thickness 0.25)
		(keepout
			(tracks not_allowed)
			(vias allowed)
			(pads allowed)
			(copperpour not_allowed)
			(footprints allowed)
		)
		(placement
			(enabled no)
			(sheetname "")
		)
		(fill yes
			(thermal_gap 0.5)
			(thermal_bridge_width 0.5)
			(island_removal_mode 0)
		)
		(polygon
			(pts
				(arc
					(start 7.502906 -171.986702)
					(mid 6.992366 -171.476162)
					(end 6.481826 -171.986702)
				)
				(arc
					(start 6.481826 -172.799502)
					(mid 6.991096 -173.31004)
					(end 7.502906 -172.802042)
				)
				(arc
					(start 7.259066 -172.802042)
					(mid 6.992366 -173.066214)
					(end 6.725666 -172.802042)
				)
				(arc
					(start 6.725666 -172.799502)
					(mid 6.992366 -172.532802)
					(end 7.259066 -172.799502)
				)
				(xy 7.502906 -172.799502) (xy 7.502906 -171.989242)
				(arc
					(start 7.259066 -171.989242)
					(mid 6.992366 -172.253414)
					(end 6.725666 -171.989242)
				)
				(arc
					(start 6.725666 -171.986702)
					(mid 6.992366 -171.720002)
					(end 7.259066 -171.986702)
				)
			)
		)
	)
	(zone
		(layers "B.Cu" "In2.Cu")
		(hatch none 0.5)
		(connect_pads
			(clearance 0)
		)
		(min_thickness 0.25)
		(keepout
			(tracks not_allowed)
			(vias allowed)
			(pads allowed)
			(copperpour not_allowed)
			(footprints allowed)
		)
		(placement
			(enabled no)
			(sheetname "")
		)
		(fill yes
			(thermal_gap 0.5)
			(thermal_bridge_width 0.5)
			(island_removal_mode 0)
		)
		(polygon
			(pts
				(arc
					(start 7.502906 -214.285068)
					(mid 6.992366 -213.774528)
					(end 6.481826 -214.285068)
				)
				(arc
					(start 6.481826 -215.097868)
					(mid 6.991096 -215.608406)
					(end 7.502906 -215.100408)
				)
				(arc
					(start 7.259066 -215.100408)
					(mid 6.992366 -215.36458)
					(end 6.725666 -215.100408)
				)
				(arc
					(start 6.725666 -215.097868)
					(mid 6.992366 -214.831168)
					(end 7.259066 -215.097868)
				)
				(xy 7.502906 -215.097868) (xy 7.502906 -214.287608)
				(arc
					(start 7.259066 -214.287608)
					(mid 6.992366 -214.55178)
					(end 6.725666 -214.287608)
				)
				(arc
					(start 6.725666 -214.285068)
					(mid 6.992366 -214.018368)
					(end 7.259066 -214.285068)
				)
			)
		)
	)
	(zone
		(layers "B.Cu" "In2.Cu")
		(hatch none 0.5)
		(connect_pads
			(clearance 0)
		)
		(min_thickness 0.25)
		(keepout
			(tracks not_allowed)
			(vias allowed)
			(pads allowed)
			(copperpour not_allowed)
			(footprints allowed)
		)
		(placement
			(enabled no)
			(sheetname "")
		)
		(fill yes
			(thermal_gap 0.5)
			(thermal_bridge_width 0.5)
			(island_removal_mode 0)
		)
		(polygon
			(pts
				(arc
					(start 27.18054 -330.003658)
					(mid 26.67 -329.493118)
					(end 26.15946 -330.003658)
				)
				(arc
					(start 26.15946 -330.816204)
					(mid 26.668603 -331.326996)
					(end 27.18054 -330.818998)
				)
				(arc
					(start 26.9367 -330.818998)
					(mid 26.67 -331.08317)
					(end 26.4033 -330.818998)
				)
				(arc
					(start 26.4033 -330.816458)
					(mid 26.67 -330.549758)
					(end 26.9367 -330.816458)
				)
				(xy 27.18054 -330.816458) (xy 27.18054 -330.006198)
				(arc
					(start 26.9367 -330.006198)
					(mid 26.67 -330.27037)
					(end 26.4033 -330.006198)
				)
				(arc
					(start 26.4033 -330.003658)
					(mid 26.67 -329.736958)
					(end 26.9367 -330.003658)
				)
			)
		)
	)
	(zone
		(layers "B.Cu" "In2.Cu")
		(hatch none 0.5)
		(connect_pads
			(clearance 0)
		)
		(min_thickness 0.25)
		(keepout
			(tracks not_allowed)
			(vias allowed)
			(pads allowed)
			(copperpour not_allowed)
			(footprints allowed)
		)
		(placement
			(enabled no)
			(sheetname "")
		)
		(fill yes
			(thermal_gap 0.5)
			(thermal_bridge_width 0.5)
			(island_removal_mode 0)
		)
		(polygon
			(pts
				(arc
					(start 7.502906 -162.386772)
					(mid 6.992366 -161.876232)
					(end 6.481826 -162.386772)
				)
				(arc
					(start 6.481826 -163.199572)
					(mid 6.991096 -163.71011)
					(end 7.502906 -163.202112)
				)
				(arc
					(start 7.259066 -163.202112)
					(mid 6.992366 -163.466284)
					(end 6.725666 -163.202112)
				)
				(arc
					(start 6.725666 -163.199572)
					(mid 6.992366 -162.932872)
					(end 7.259066 -163.199572)
				)
				(xy 7.502906 -163.199572) (xy 7.502906 -162.389312)
				(arc
					(start 7.259066 -162.389312)
					(mid 6.992366 -162.653484)
					(end 6.725666 -162.389312)
				)
				(arc
					(start 6.725666 -162.386772)
					(mid 6.992366 -162.120072)
					(end 7.259066 -162.386772)
				)
			)
		)
	)
	(zone
		(layers "B.Cu" "In2.Cu")
		(hatch none 0.5)
		(connect_pads
			(clearance 0)
		)
		(min_thickness 0.25)
		(keepout
			(tracks not_allowed)
			(vias allowed)
			(pads allowed)
			(copperpour not_allowed)
			(footprints allowed)
		)
		(placement
			(enabled no)
			(sheetname "")
		)
		(fill yes
			(thermal_gap 0.5)
			(thermal_bridge_width 0.5)
			(island_removal_mode 0)
		)
		(polygon
			(pts
				(arc
					(start 220.840554 -273.383756)
					(mid 220.330014 -272.873216)
					(end 219.819474 -273.383756)
				)
				(arc
					(start 219.819474 -274.196556)
					(mid 220.328744 -274.707094)
					(end 220.840554 -274.199096)
				)
				(arc
					(start 220.596714 -274.199096)
					(mid 220.330014 -274.463268)
					(end 220.063314 -274.199096)
				)
				(arc
					(start 220.063314 -274.196556)
					(mid 220.330014 -273.929856)
					(end 220.596714 -274.196556)
				)
				(xy 220.840554 -274.196556) (xy 220.840554 -273.386296)
				(arc
					(start 220.596714 -273.386296)
					(mid 220.330014 -273.650468)
					(end 220.063314 -273.386296)
				)
				(arc
					(start 220.063314 -273.383756)
					(mid 220.330014 -273.117056)
					(end 220.596714 -273.383756)
				)
			)
		)
	)
	(zone
		(layers "B.Cu" "In2.Cu")
		(hatch none 0.5)
		(connect_pads
			(clearance 0)
		)
		(min_thickness 0.25)
		(keepout
			(tracks not_allowed)
			(vias allowed)
			(pads allowed)
			(copperpour not_allowed)
			(footprints allowed)
		)
		(placement
			(enabled no)
			(sheetname "")
		)
		(fill yes
			(thermal_gap 0.5)
			(thermal_bridge_width 0.5)
			(island_removal_mode 0)
		)
		(polygon
			(pts
				(arc
					(start 7.502906 -192.735962)
					(mid 6.992366 -192.225422)
					(end 6.481826 -192.735962)
				)
				(arc
					(start 6.481826 -193.548762)
					(mid 6.991096 -194.0593)
					(end 7.502906 -193.551302)
				)
				(arc
					(start 7.259066 -193.551302)
					(mid 6.992366 -193.815474)
					(end 6.725666 -193.551302)
				)
				(arc
					(start 6.725666 -193.548762)
					(mid 6.992366 -193.282062)
					(end 7.259066 -193.548762)
				)
				(xy 7.502906 -193.548762) (xy 7.502906 -192.738502)
				(arc
					(start 7.259066 -192.738502)
					(mid 6.992366 -193.002674)
					(end 6.725666 -192.738502)
				)
				(arc
					(start 6.725666 -192.735962)
					(mid 6.992366 -192.469262)
					(end 7.259066 -192.735962)
				)
			)
		)
	)
	(zone
		(layers "B.Cu" "In2.Cu")
		(hatch none 0.5)
		(connect_pads
			(clearance 0)
		)
		(min_thickness 0.25)
		(keepout
			(tracks not_allowed)
			(vias allowed)
			(pads allowed)
			(copperpour not_allowed)
			(footprints allowed)
		)
		(placement
			(enabled no)
			(sheetname "")
		)
		(fill yes
			(thermal_gap 0.5)
			(thermal_bridge_width 0.5)
			(island_removal_mode 0)
		)
		(polygon
			(pts
				(arc
					(start 7.502906 -408.735784)
					(mid 6.992366 -408.225244)
					(end 6.481826 -408.735784)
				)
				(arc
					(start 6.481826 -409.54833)
					(mid 6.990969 -410.059122)
					(end 7.502906 -409.551124)
				)
				(arc
					(start 7.259066 -409.551124)
					(mid 6.992366 -409.815296)
					(end 6.725666 -409.551124)
				)
				(arc
					(start 6.725666 -409.548584)
					(mid 6.992366 -409.281884)
					(end 7.259066 -409.548584)
				)
				(xy 7.502906 -409.548584) (xy 7.502906 -408.738324)
				(arc
					(start 7.259066 -408.738324)
					(mid 6.992366 -409.002496)
					(end 6.725666 -408.738324)
				)
				(arc
					(start 6.725666 -408.735784)
					(mid 6.992366 -408.469084)
					(end 7.259066 -408.735784)
				)
			)
		)
	)
	(zone
		(layers "B.Cu" "In2.Cu")
		(hatch none 0.5)
		(connect_pads
			(clearance 0)
		)
		(min_thickness 0.25)
		(keepout
			(tracks not_allowed)
			(vias allowed)
			(pads allowed)
			(copperpour not_allowed)
			(footprints allowed)
		)
		(placement
			(enabled no)
			(sheetname "")
		)
		(fill yes
			(thermal_gap 0.5)
			(thermal_bridge_width 0.5)
			(island_removal_mode 0)
		)
		(polygon
			(pts
				(arc
					(start 220.840554 -54.583584)
					(mid 220.330014 -54.073044)
					(end 219.819474 -54.583584)
				)
				(arc
					(start 219.819474 -55.396384)
					(mid 220.328744 -55.906922)
					(end 220.840554 -55.398924)
				)
				(arc
					(start 220.596714 -55.398924)
					(mid 220.330014 -55.663096)
					(end 220.063314 -55.398924)
				)
				(arc
					(start 220.063314 -55.396384)
					(mid 220.330014 -55.129684)
					(end 220.596714 -55.396384)
				)
				(xy 220.840554 -55.396384) (xy 220.840554 -54.586124)
				(arc
					(start 220.596714 -54.586124)
					(mid 220.330014 -54.850296)
					(end 220.063314 -54.586124)
				)
				(arc
					(start 220.063314 -54.583584)
					(mid 220.330014 -54.316884)
					(end 220.596714 -54.583584)
				)
			)
		)
	)
	(zone
		(layers "B.Cu" "In2.Cu")
		(hatch none 0.5)
		(connect_pads
			(clearance 0)
		)
		(min_thickness 0.25)
		(keepout
			(tracks not_allowed)
			(vias allowed)
			(pads allowed)
			(copperpour not_allowed)
			(footprints allowed)
		)
		(placement
			(enabled no)
			(sheetname "")
		)
		(fill yes
			(thermal_gap 0.5)
			(thermal_bridge_width 0.5)
			(island_removal_mode 0)
		)
		(polygon
			(pts
				(arc
					(start 7.502906 -446.384172)
					(mid 6.992366 -445.873632)
					(end 6.481826 -446.384172)
				)
				(arc
					(start 6.481826 -447.196718)
					(mid 6.990969 -447.70751)
					(end 7.502906 -447.199512)
				)
				(arc
					(start 7.259066 -447.199512)
					(mid 6.992366 -447.463684)
					(end 6.725666 -447.199512)
				)
				(arc
					(start 6.725666 -447.196972)
					(mid 6.992366 -446.930272)
					(end 7.259066 -447.196972)
				)
				(xy 7.502906 -447.196972) (xy 7.502906 -446.386712)
				(arc
					(start 7.259066 -446.386712)
					(mid 6.992366 -446.650884)
					(end 6.725666 -446.386712)
				)
				(arc
					(start 6.725666 -446.384172)
					(mid 6.992366 -446.117472)
					(end 7.259066 -446.384172)
				)
			)
		)
	)
	(zone
		(layers "B.Cu" "In2.Cu")
		(hatch none 0.5)
		(connect_pads
			(clearance 0)
		)
		(min_thickness 0.25)
		(keepout
			(tracks not_allowed)
			(vias allowed)
			(pads allowed)
			(copperpour not_allowed)
			(footprints allowed)
		)
		(placement
			(enabled no)
			(sheetname "")
		)
		(fill yes
			(thermal_gap 0.5)
			(thermal_bridge_width 0.5)
			(island_removal_mode 0)
		)
		(polygon
			(pts
				(arc
					(start 220.840554 -282.983686)
					(mid 220.330014 -282.473146)
					(end 219.819474 -282.983686)
				)
				(arc
					(start 219.819474 -283.796486)
					(mid 220.328744 -284.307024)
					(end 220.840554 -283.799026)
				)
				(arc
					(start 220.596714 -283.799026)
					(mid 220.330014 -284.063198)
					(end 220.063314 -283.799026)
				)
				(arc
					(start 220.063314 -283.796486)
					(mid 220.330014 -283.529786)
					(end 220.596714 -283.796486)
				)
				(xy 220.840554 -283.796486) (xy 220.840554 -282.986226)
				(arc
					(start 220.596714 -282.986226)
					(mid 220.330014 -283.250398)
					(end 220.063314 -282.986226)
				)
				(arc
					(start 220.063314 -282.983686)
					(mid 220.330014 -282.716986)
					(end 220.596714 -282.983686)
				)
			)
		)
	)
	(zone
		(layers "B.Cu" "In2.Cu")
		(hatch none 0.5)
		(connect_pads
			(clearance 0)
		)
		(min_thickness 0.25)
		(keepout
			(tracks not_allowed)
			(vias allowed)
			(pads allowed)
			(copperpour not_allowed)
			(footprints allowed)
		)
		(placement
			(enabled no)
			(sheetname "")
		)
		(fill yes
			(thermal_gap 0.5)
			(thermal_bridge_width 0.5)
			(island_removal_mode 0)
		)
		(polygon
			(pts
				(arc
					(start 7.502906 -325.136002)
					(mid 6.992366 -324.625462)
					(end 6.481826 -325.136002)
				)
				(arc
					(start 6.481826 -325.948548)
					(mid 6.990969 -326.45934)
					(end 7.502906 -325.951342)
				)
				(arc
					(start 7.259066 -325.951342)
					(mid 6.992366 -326.215514)
					(end 6.725666 -325.951342)
				)
				(arc
					(start 6.725666 -325.948802)
					(mid 6.992366 -325.682102)
					(end 7.259066 -325.948802)
				)
				(xy 7.502906 -325.948802) (xy 7.502906 -325.138542)
				(arc
					(start 7.259066 -325.138542)
					(mid 6.992366 -325.402714)
					(end 6.725666 -325.138542)
				)
				(arc
					(start 6.725666 -325.136002)
					(mid 6.992366 -324.869302)
					(end 7.259066 -325.136002)
				)
			)
		)
	)
	(zone
		(layers "B.Cu" "In2.Cu")
		(hatch none 0.5)
		(connect_pads
			(clearance 0)
		)
		(min_thickness 0.25)
		(keepout
			(tracks not_allowed)
			(vias allowed)
			(pads allowed)
			(copperpour not_allowed)
			(footprints allowed)
		)
		(placement
			(enabled no)
			(sheetname "")
		)
		(fill yes
			(thermal_gap 0.5)
			(thermal_bridge_width 0.5)
			(island_removal_mode 0)
		)
		(polygon
			(pts
				(arc
					(start 27.18054 -21.003514)
					(mid 26.67 -20.492974)
					(end 26.15946 -21.003514)
				)
				(arc
					(start 26.15946 -21.81606)
					(mid 26.668603 -22.326852)
					(end 27.18054 -21.818854)
				)
				(arc
					(start 26.9367 -21.818854)
					(mid 26.67 -22.083026)
					(end 26.4033 -21.818854)
				)
				(arc
					(start 26.4033 -21.816314)
					(mid 26.67 -21.549614)
					(end 26.9367 -21.816314)
				)
				(xy 27.18054 -21.816314) (xy 27.18054 -21.006054)
				(arc
					(start 26.9367 -21.006054)
					(mid 26.67 -21.270226)
					(end 26.4033 -21.006054)
				)
				(arc
					(start 26.4033 -21.003514)
					(mid 26.67 -20.736814)
					(end 26.9367 -21.003514)
				)
			)
		)
	)
	(zone
		(layers "B.Cu" "In2.Cu")
		(hatch none 0.5)
		(connect_pads
			(clearance 0)
		)
		(min_thickness 0.25)
		(keepout
			(tracks not_allowed)
			(vias allowed)
			(pads allowed)
			(copperpour not_allowed)
			(footprints allowed)
		)
		(placement
			(enabled no)
			(sheetname "")
		)
		(fill yes
			(thermal_gap 0.5)
			(thermal_bridge_width 0.5)
			(island_removal_mode 0)
		)
		(polygon
			(pts
				(arc
					(start 7.502906 -321.935856)
					(mid 6.992366 -321.425316)
					(end 6.481826 -321.935856)
				)
				(arc
					(start 6.481826 -322.748402)
					(mid 6.990969 -323.259194)
					(end 7.502906 -322.751196)
				)
				(arc
					(start 7.259066 -322.751196)
					(mid 6.992366 -323.015368)
					(end 6.725666 -322.751196)
				)
				(arc
					(start 6.725666 -322.748656)
					(mid 6.992366 -322.481956)
					(end 7.259066 -322.748656)
				)
				(xy 7.502906 -322.748656) (xy 7.502906 -321.938396)
				(arc
					(start 7.259066 -321.938396)
					(mid 6.992366 -322.202568)
					(end 6.725666 -321.938396)
				)
				(arc
					(start 6.725666 -321.935856)
					(mid 6.992366 -321.669156)
					(end 7.259066 -321.935856)
				)
			)
		)
	)
	(zone
		(layers "B.Cu" "In2.Cu")
		(hatch none 0.5)
		(connect_pads
			(clearance 0)
		)
		(min_thickness 0.25)
		(keepout
			(tracks not_allowed)
			(vias allowed)
			(pads allowed)
			(copperpour not_allowed)
			(footprints allowed)
		)
		(placement
			(enabled no)
			(sheetname "")
		)
		(fill yes
			(thermal_gap 0.5)
			(thermal_bridge_width 0.5)
			(island_removal_mode 0)
		)
		(polygon
			(pts
				(arc
					(start 27.18054 -227.00361)
					(mid 26.67 -226.49307)
					(end 26.15946 -227.00361)
				)
				(arc
					(start 26.15946 -227.816156)
					(mid 26.668603 -228.326948)
					(end 27.18054 -227.81895)
				)
				(arc
					(start 26.9367 -227.81895)
					(mid 26.67 -228.083122)
					(end 26.4033 -227.81895)
				)
				(arc
					(start 26.4033 -227.81641)
					(mid 26.67 -227.54971)
					(end 26.9367 -227.81641)
				)
				(xy 27.18054 -227.81641) (xy 27.18054 -227.00615)
				(arc
					(start 26.9367 -227.00615)
					(mid 26.67 -227.270322)
					(end 26.4033 -227.00615)
				)
				(arc
					(start 26.4033 -227.00361)
					(mid 26.67 -226.73691)
					(end 26.9367 -227.00361)
				)
			)
		)
	)
	(zone
		(layers "B.Cu" "In2.Cu")
		(hatch none 0.5)
		(connect_pads
			(clearance 0)
		)
		(min_thickness 0.25)
		(keepout
			(tracks not_allowed)
			(vias allowed)
			(pads allowed)
			(copperpour not_allowed)
			(footprints allowed)
		)
		(placement
			(enabled no)
			(sheetname "")
		)
		(fill yes
			(thermal_gap 0.5)
			(thermal_bridge_width 0.5)
			(island_removal_mode 0)
		)
		(polygon
			(pts
				(arc
					(start 7.502906 -201.535792)
					(mid 6.992366 -201.025252)
					(end 6.481826 -201.535792)
				)
				(arc
					(start 6.481826 -202.348592)
					(mid 6.991096 -202.85913)
					(end 7.502906 -202.351132)
				)
				(arc
					(start 7.259066 -202.351132)
					(mid 6.992366 -202.615304)
					(end 6.725666 -202.351132)
				)
				(arc
					(start 6.725666 -202.348592)
					(mid 6.992366 -202.081892)
					(end 7.259066 -202.348592)
				)
				(xy 7.502906 -202.348592) (xy 7.502906 -201.538332)
				(arc
					(start 7.259066 -201.538332)
					(mid 6.992366 -201.802504)
					(end 6.725666 -201.538332)
				)
				(arc
					(start 6.725666 -201.535792)
					(mid 6.992366 -201.269092)
					(end 7.259066 -201.535792)
				)
			)
		)
	)
	(zone
		(layers "B.Cu" "In2.Cu")
		(hatch none 0.5)
		(connect_pads
			(clearance 0)
		)
		(min_thickness 0.25)
		(keepout
			(tracks not_allowed)
			(vias allowed)
			(pads allowed)
			(copperpour not_allowed)
			(footprints allowed)
		)
		(placement
			(enabled no)
			(sheetname "")
		)
		(fill yes
			(thermal_gap 0.5)
			(thermal_bridge_width 0.5)
			(island_removal_mode 0)
		)
		(polygon
			(pts
				(arc
					(start 27.18054 -25.803352)
					(mid 26.67 -25.292812)
					(end 26.15946 -25.803352)
				)
				(arc
					(start 26.15946 -26.615898)
					(mid 26.668603 -27.12669)
					(end 27.18054 -26.618692)
				)
				(arc
					(start 26.9367 -26.618692)
					(mid 26.67 -26.882864)
					(end 26.4033 -26.618692)
				)
				(arc
					(start 26.4033 -26.616152)
					(mid 26.67 -26.349452)
					(end 26.9367 -26.616152)
				)
				(xy 27.18054 -26.616152) (xy 27.18054 -25.805892)
				(arc
					(start 26.9367 -25.805892)
					(mid 26.67 -26.070064)
					(end 26.4033 -25.805892)
				)
				(arc
					(start 26.4033 -25.803352)
					(mid 26.67 -25.536652)
					(end 26.9367 -25.803352)
				)
			)
		)
	)
	(zone
		(layers "B.Cu" "In2.Cu")
		(hatch none 0.5)
		(connect_pads
			(clearance 0)
		)
		(min_thickness 0.25)
		(keepout
			(tracks not_allowed)
			(vias allowed)
			(pads allowed)
			(copperpour not_allowed)
			(footprints allowed)
		)
		(placement
			(enabled no)
			(sheetname "")
		)
		(fill yes
			(thermal_gap 0.5)
			(thermal_bridge_width 0.5)
			(island_removal_mode 0)
		)
		(polygon
			(pts
				(arc
					(start 35.84067 -385.983734)
					(mid 35.33013 -385.473194)
					(end 34.81959 -385.983734)
				)
				(arc
					(start 34.81959 -386.796534)
					(mid 35.32886 -387.307072)
					(end 35.84067 -386.799074)
				)
				(arc
					(start 35.59683 -386.799074)
					(mid 35.33013 -387.063246)
					(end 35.06343 -386.799074)
				)
				(arc
					(start 35.06343 -386.796534)
					(mid 35.33013 -386.529834)
					(end 35.59683 -386.796534)
				)
				(xy 35.84067 -386.796534) (xy 35.84067 -385.986274)
				(arc
					(start 35.59683 -385.986274)
					(mid 35.33013 -386.250446)
					(end 35.06343 -385.986274)
				)
				(arc
					(start 35.06343 -385.983734)
					(mid 35.33013 -385.717034)
					(end 35.59683 -385.983734)
				)
			)
		)
	)
	(zone
		(layers "B.Cu" "In2.Cu")
		(hatch none 0.5)
		(connect_pads
			(clearance 0)
		)
		(min_thickness 0.25)
		(keepout
			(tracks not_allowed)
			(vias allowed)
			(pads allowed)
			(copperpour not_allowed)
			(footprints allowed)
		)
		(placement
			(enabled no)
			(sheetname "")
		)
		(fill yes
			(thermal_gap 0.5)
			(thermal_bridge_width 0.5)
			(island_removal_mode 0)
		)
		(polygon
			(pts
				(arc
					(start 27.18054 -325.203566)
					(mid 26.67 -324.693026)
					(end 26.15946 -325.203566)
				)
				(arc
					(start 26.15946 -326.016112)
					(mid 26.668603 -326.526904)
					(end 27.18054 -326.018906)
				)
				(arc
					(start 26.9367 -326.018906)
					(mid 26.67 -326.283078)
					(end 26.4033 -326.018906)
				)
				(arc
					(start 26.4033 -326.016366)
					(mid 26.67 -325.749666)
					(end 26.9367 -326.016366)
				)
				(xy 27.18054 -326.016366) (xy 27.18054 -325.206106)
				(arc
					(start 26.9367 -325.206106)
					(mid 26.67 -325.470278)
					(end 26.4033 -325.206106)
				)
				(arc
					(start 26.4033 -325.203566)
					(mid 26.67 -324.936866)
					(end 26.9367 -325.203566)
				)
			)
		)
	)
	(zone
		(layers "B.Cu" "In2.Cu")
		(hatch none 0.5)
		(connect_pads
			(clearance 0)
		)
		(min_thickness 0.25)
		(keepout
			(tracks not_allowed)
			(vias allowed)
			(pads allowed)
			(copperpour not_allowed)
			(footprints allowed)
		)
		(placement
			(enabled no)
			(sheetname "")
		)
		(fill yes
			(thermal_gap 0.5)
			(thermal_bridge_width 0.5)
			(island_removal_mode 0)
		)
		(polygon
			(pts
				(arc
					(start 220.840554 -376.383804)
					(mid 220.330014 -375.873264)
					(end 219.819474 -376.383804)
				)
				(arc
					(start 219.819474 -377.196604)
					(mid 220.328744 -377.707142)
					(end 220.840554 -377.199144)
				)
				(arc
					(start 220.596714 -377.199144)
					(mid 220.330014 -377.463316)
					(end 220.063314 -377.199144)
				)
				(arc
					(start 220.063314 -377.196604)
					(mid 220.330014 -376.929904)
					(end 220.596714 -377.196604)
				)
				(xy 220.840554 -377.196604) (xy 220.840554 -376.386344)
				(arc
					(start 220.596714 -376.386344)
					(mid 220.330014 -376.650516)
					(end 220.063314 -376.386344)
				)
				(arc
					(start 220.063314 -376.383804)
					(mid 220.330014 -376.117104)
					(end 220.596714 -376.383804)
				)
			)
		)
	)
	(zone
		(layers "B.Cu" "In2.Cu")
		(hatch none 0.5)
		(connect_pads
			(clearance 0)
		)
		(min_thickness 0.25)
		(keepout
			(tracks not_allowed)
			(vias allowed)
			(pads allowed)
			(copperpour not_allowed)
			(footprints allowed)
		)
		(placement
			(enabled no)
			(sheetname "")
		)
		(fill yes
			(thermal_gap 0.5)
			(thermal_bridge_width 0.5)
			(island_removal_mode 0)
		)
		(polygon
			(pts
				(arc
					(start 7.502906 -387.135624)
					(mid 6.992366 -386.625084)
					(end 6.481826 -387.135624)
				)
				(arc
					(start 6.481826 -387.948424)
					(mid 6.991096 -388.458962)
					(end 7.502906 -387.950964)
				)
				(arc
					(start 7.259066 -387.950964)
					(mid 6.992366 -388.215136)
					(end 6.725666 -387.950964)
				)
				(arc
					(start 6.725666 -387.948424)
					(mid 6.992366 -387.681724)
					(end 7.259066 -387.948424)
				)
				(xy 7.502906 -387.948424) (xy 7.502906 -387.138164)
				(arc
					(start 7.259066 -387.138164)
					(mid 6.992366 -387.402336)
					(end 6.725666 -387.138164)
				)
				(arc
					(start 6.725666 -387.135624)
					(mid 6.992366 -386.868924)
					(end 7.259066 -387.135624)
				)
			)
		)
	)
	(zone
		(layers "B.Cu" "In2.Cu")
		(hatch none 0.5)
		(connect_pads
			(clearance 0)
		)
		(min_thickness 0.25)
		(keepout
			(tracks not_allowed)
			(vias allowed)
			(pads allowed)
			(copperpour not_allowed)
			(footprints allowed)
		)
		(placement
			(enabled no)
			(sheetname "")
		)
		(fill yes
			(thermal_gap 0.5)
			(thermal_bridge_width 0.5)
			(island_removal_mode 0)
		)
		(polygon
			(pts
				(arc
					(start 7.502906 -402.335746)
					(mid 6.992366 -401.825206)
					(end 6.481826 -402.335746)
				)
				(arc
					(start 6.481826 -403.148292)
					(mid 6.990969 -403.659084)
					(end 7.502906 -403.151086)
				)
				(arc
					(start 7.259066 -403.151086)
					(mid 6.992366 -403.415258)
					(end 6.725666 -403.151086)
				)
				(arc
					(start 6.725666 -403.148546)
					(mid 6.992366 -402.881846)
					(end 7.259066 -403.148546)
				)
				(xy 7.502906 -403.148546) (xy 7.502906 -402.338286)
				(arc
					(start 7.259066 -402.338286)
					(mid 6.992366 -402.602458)
					(end 6.725666 -402.338286)
				)
				(arc
					(start 6.725666 -402.335746)
					(mid 6.992366 -402.069046)
					(end 7.259066 -402.335746)
				)
			)
		)
	)
	(zone
		(layers "B.Cu" "In2.Cu")
		(hatch none 0.5)
		(connect_pads
			(clearance 0)
		)
		(min_thickness 0.25)
		(keepout
			(tracks not_allowed)
			(vias allowed)
			(pads allowed)
			(copperpour not_allowed)
			(footprints allowed)
		)
		(placement
			(enabled no)
			(sheetname "")
		)
		(fill yes
			(thermal_gap 0.5)
			(thermal_bridge_width 0.5)
			(island_removal_mode 0)
		)
		(polygon
			(pts
				(arc
					(start 27.18054 -428.203614)
					(mid 26.67 -427.693074)
					(end 26.15946 -428.203614)
				)
				(arc
					(start 26.15946 -429.016414)
					(mid 26.66873 -429.526952)
					(end 27.18054 -429.018954)
				)
				(arc
					(start 26.9367 -429.018954)
					(mid 26.67 -429.283126)
					(end 26.4033 -429.018954)
				)
				(arc
					(start 26.4033 -429.016414)
					(mid 26.67 -428.749714)
					(end 26.9367 -429.016414)
				)
				(xy 27.18054 -429.016414) (xy 27.18054 -428.206154)
				(arc
					(start 26.9367 -428.206154)
					(mid 26.67 -428.470326)
					(end 26.4033 -428.206154)
				)
				(arc
					(start 26.4033 -428.203614)
					(mid 26.67 -427.936914)
					(end 26.9367 -428.203614)
				)
			)
		)
	)
	(zone
		(layers "B.Cu" "In2.Cu")
		(hatch none 0.5)
		(connect_pads
			(clearance 0)
		)
		(min_thickness 0.25)
		(keepout
			(tracks not_allowed)
			(vias allowed)
			(pads allowed)
			(copperpour not_allowed)
			(footprints allowed)
		)
		(placement
			(enabled no)
			(sheetname "")
		)
		(fill yes
			(thermal_gap 0.5)
			(thermal_bridge_width 0.5)
			(island_removal_mode 0)
		)
		(polygon
			(pts
				(arc
					(start 220.840554 -175.183546)
					(mid 220.330014 -174.673006)
					(end 219.819474 -175.183546)
				)
				(arc
					(start 219.819474 -175.996346)
					(mid 220.328744 -176.506884)
					(end 220.840554 -175.998886)
				)
				(arc
					(start 220.596714 -175.998886)
					(mid 220.330014 -176.263058)
					(end 220.063314 -175.998886)
				)
				(arc
					(start 220.063314 -175.996346)
					(mid 220.330014 -175.729646)
					(end 220.596714 -175.996346)
				)
				(xy 220.840554 -175.996346) (xy 220.840554 -175.186086)
				(arc
					(start 220.596714 -175.186086)
					(mid 220.330014 -175.450258)
					(end 220.063314 -175.186086)
				)
				(arc
					(start 220.063314 -175.183546)
					(mid 220.330014 -174.916846)
					(end 220.596714 -175.183546)
				)
			)
		)
	)
	(zone
		(layers "B.Cu" "In2.Cu")
		(hatch none 0.5)
		(connect_pads
			(clearance 0)
		)
		(min_thickness 0.25)
		(keepout
			(tracks not_allowed)
			(vias allowed)
			(pads allowed)
			(copperpour not_allowed)
			(footprints allowed)
		)
		(placement
			(enabled no)
			(sheetname "")
		)
		(fill yes
			(thermal_gap 0.5)
			(thermal_bridge_width 0.5)
			(island_removal_mode 0)
		)
		(polygon
			(pts
				(arc
					(start 7.502906 -227.135944)
					(mid 6.992366 -226.625404)
					(end 6.481826 -227.135944)
				)
				(arc
					(start 6.481826 -227.948744)
					(mid 6.991096 -228.459282)
					(end 7.502906 -227.951284)
				)
				(arc
					(start 7.259066 -227.951284)
					(mid 6.992366 -228.215456)
					(end 6.725666 -227.951284)
				)
				(arc
					(start 6.725666 -227.948744)
					(mid 6.992366 -227.682044)
					(end 7.259066 -227.948744)
				)
				(xy 7.502906 -227.948744) (xy 7.502906 -227.138484)
				(arc
					(start 7.259066 -227.138484)
					(mid 6.992366 -227.402656)
					(end 6.725666 -227.138484)
				)
				(arc
					(start 6.725666 -227.135944)
					(mid 6.992366 -226.869244)
					(end 7.259066 -227.135944)
				)
			)
		)
	)
	(zone
		(layers "B.Cu" "In2.Cu")
		(hatch none 0.5)
		(connect_pads
			(clearance 0)
		)
		(min_thickness 0.25)
		(keepout
			(tracks not_allowed)
			(vias allowed)
			(pads allowed)
			(copperpour not_allowed)
			(footprints allowed)
		)
		(placement
			(enabled no)
			(sheetname "")
		)
		(fill yes
			(thermal_gap 0.5)
			(thermal_bridge_width 0.5)
			(island_removal_mode 0)
		)
		(polygon
			(pts
				(arc
					(start 35.84067 -72.183498)
					(mid 35.33013 -71.672958)
					(end 34.81959 -72.183498)
				)
				(arc
					(start 34.81959 -72.996298)
					(mid 35.32886 -73.506836)
					(end 35.84067 -72.998838)
				)
				(arc
					(start 35.59683 -72.998838)
					(mid 35.33013 -73.26301)
					(end 35.06343 -72.998838)
				)
				(arc
					(start 35.06343 -72.996298)
					(mid 35.33013 -72.729598)
					(end 35.59683 -72.996298)
				)
				(xy 35.84067 -72.996298) (xy 35.84067 -72.186038)
				(arc
					(start 35.59683 -72.186038)
					(mid 35.33013 -72.45021)
					(end 35.06343 -72.186038)
				)
				(arc
					(start 35.06343 -72.183498)
					(mid 35.33013 -71.916798)
					(end 35.59683 -72.183498)
				)
			)
		)
	)
	(zone
		(layers "B.Cu" "In2.Cu")
		(hatch none 0.5)
		(connect_pads
			(clearance 0)
		)
		(min_thickness 0.25)
		(keepout
			(tracks not_allowed)
			(vias allowed)
			(pads allowed)
			(copperpour not_allowed)
			(footprints allowed)
		)
		(placement
			(enabled no)
			(sheetname "")
		)
		(fill yes
			(thermal_gap 0.5)
			(thermal_bridge_width 0.5)
			(island_removal_mode 0)
		)
		(polygon
			(pts
				(arc
					(start 7.502906 -307.535834)
					(mid 6.992366 -307.025294)
					(end 6.481826 -307.535834)
				)
				(arc
					(start 6.481826 -308.34838)
					(mid 6.990969 -308.859172)
					(end 7.502906 -308.351174)
				)
				(arc
					(start 7.259066 -308.351174)
					(mid 6.992366 -308.615346)
					(end 6.725666 -308.351174)
				)
				(arc
					(start 6.725666 -308.348634)
					(mid 6.992366 -308.081934)
					(end 7.259066 -308.348634)
				)
				(xy 7.502906 -308.348634) (xy 7.502906 -307.538374)
				(arc
					(start 7.259066 -307.538374)
					(mid 6.992366 -307.802546)
					(end 6.725666 -307.538374)
				)
				(arc
					(start 6.725666 -307.535834)
					(mid 6.992366 -307.269134)
					(end 7.259066 -307.535834)
				)
			)
		)
	)
	(zone
		(layers "B.Cu" "In2.Cu")
		(hatch none 0.5)
		(connect_pads
			(clearance 0)
		)
		(min_thickness 0.25)
		(keepout
			(tracks not_allowed)
			(vias allowed)
			(pads allowed)
			(copperpour not_allowed)
			(footprints allowed)
		)
		(placement
			(enabled no)
			(sheetname "")
		)
		(fill yes
			(thermal_gap 0.5)
			(thermal_bridge_width 0.5)
			(island_removal_mode 0)
		)
		(polygon
			(pts
				(arc
					(start 7.502906 -168.78681)
					(mid 6.992366 -168.27627)
					(end 6.481826 -168.78681)
				)
				(arc
					(start 6.481826 -169.59961)
					(mid 6.991096 -170.110148)
					(end 7.502906 -169.60215)
				)
				(arc
					(start 7.259066 -169.60215)
					(mid 6.992366 -169.866322)
					(end 6.725666 -169.60215)
				)
				(arc
					(start 6.725666 -169.59961)
					(mid 6.992366 -169.33291)
					(end 7.259066 -169.59961)
				)
				(xy 7.502906 -169.59961) (xy 7.502906 -168.78935)
				(arc
					(start 7.259066 -168.78935)
					(mid 6.992366 -169.053522)
					(end 6.725666 -168.78935)
				)
				(arc
					(start 6.725666 -168.78681)
					(mid 6.992366 -168.52011)
					(end 7.259066 -168.78681)
				)
			)
		)
	)
	(zone
		(layers "B.Cu" "In2.Cu")
		(hatch none 0.5)
		(connect_pads
			(clearance 0)
		)
		(min_thickness 0.25)
		(keepout
			(tracks not_allowed)
			(vias allowed)
			(pads allowed)
			(copperpour not_allowed)
			(footprints allowed)
		)
		(placement
			(enabled no)
			(sheetname "")
		)
		(fill yes
			(thermal_gap 0.5)
			(thermal_bridge_width 0.5)
			(island_removal_mode 0)
		)
		(polygon
			(pts
				(arc
					(start 220.840554 -466.583776)
					(mid 220.330014 -466.073236)
					(end 219.819474 -466.583776)
				)
				(arc
					(start 219.819474 -467.396576)
					(mid 220.328744 -467.907114)
					(end 220.840554 -467.399116)
				)
				(arc
					(start 220.596714 -467.399116)
					(mid 220.330014 -467.663288)
					(end 220.063314 -467.399116)
				)
				(arc
					(start 220.063314 -467.396576)
					(mid 220.330014 -467.129876)
					(end 220.596714 -467.396576)
				)
				(xy 220.840554 -467.396576) (xy 220.840554 -466.586316)
				(arc
					(start 220.596714 -466.586316)
					(mid 220.330014 -466.850488)
					(end 220.063314 -466.586316)
				)
				(arc
					(start 220.063314 -466.583776)
					(mid 220.330014 -466.317076)
					(end 220.596714 -466.583776)
				)
			)
		)
	)
	(zone
		(layers "B.Cu" "In2.Cu")
		(hatch none 0.5)
		(connect_pads
			(clearance 0)
		)
		(min_thickness 0.25)
		(keepout
			(tracks not_allowed)
			(vias allowed)
			(pads allowed)
			(copperpour not_allowed)
			(footprints allowed)
		)
		(placement
			(enabled no)
			(sheetname "")
		)
		(fill yes
			(thermal_gap 0.5)
			(thermal_bridge_width 0.5)
			(island_removal_mode 0)
		)
		(polygon
			(pts
				(arc
					(start 27.18054 -222.203518)
					(mid 26.67 -221.692978)
					(end 26.15946 -222.203518)
				)
				(arc
					(start 26.15946 -223.016064)
					(mid 26.668603 -223.526856)
					(end 27.18054 -223.018858)
				)
				(arc
					(start 26.9367 -223.018858)
					(mid 26.67 -223.28303)
					(end 26.4033 -223.018858)
				)
				(arc
					(start 26.4033 -223.016318)
					(mid 26.67 -222.749618)
					(end 26.9367 -223.016318)
				)
				(xy 27.18054 -223.016318) (xy 27.18054 -222.206058)
				(arc
					(start 26.9367 -222.206058)
					(mid 26.67 -222.47023)
					(end 26.4033 -222.206058)
				)
				(arc
					(start 26.4033 -222.203518)
					(mid 26.67 -221.936818)
					(end 26.9367 -222.203518)
				)
			)
		)
	)
	(zone
		(layers "B.Cu" "In2.Cu")
		(hatch none 0.5)
		(connect_pads
			(clearance 0)
		)
		(min_thickness 0.25)
		(keepout
			(tracks not_allowed)
			(vias allowed)
			(pads allowed)
			(copperpour not_allowed)
			(footprints allowed)
		)
		(placement
			(enabled no)
			(sheetname "")
		)
		(fill yes
			(thermal_gap 0.5)
			(thermal_bridge_width 0.5)
			(island_removal_mode 0)
		)
		(polygon
			(pts
				(arc
					(start 7.502906 -294.736012)
					(mid 6.992366 -294.225472)
					(end 6.481826 -294.736012)
				)
				(arc
					(start 6.481826 -295.548558)
					(mid 6.990969 -296.05935)
					(end 7.502906 -295.551352)
				)
				(arc
					(start 7.259066 -295.551352)
					(mid 6.992366 -295.815524)
					(end 6.725666 -295.551352)
				)
				(arc
					(start 6.725666 -295.548812)
					(mid 6.992366 -295.282112)
					(end 7.259066 -295.548812)
				)
				(xy 7.502906 -295.548812) (xy 7.502906 -294.738552)
				(arc
					(start 7.259066 -294.738552)
					(mid 6.992366 -295.002724)
					(end 6.725666 -294.738552)
				)
				(arc
					(start 6.725666 -294.736012)
					(mid 6.992366 -294.469312)
					(end 7.259066 -294.736012)
				)
			)
		)
	)
	(zone
		(layers "B.Cu" "In2.Cu")
		(hatch none 0.5)
		(connect_pads
			(clearance 0)
		)
		(min_thickness 0.25)
		(keepout
			(tracks not_allowed)
			(vias allowed)
			(pads allowed)
			(copperpour not_allowed)
			(footprints allowed)
		)
		(placement
			(enabled no)
			(sheetname "")
		)
		(fill yes
			(thermal_gap 0.5)
			(thermal_bridge_width 0.5)
			(island_removal_mode 0)
		)
		(polygon
			(pts
				(arc
					(start 7.502906 -195.935854)
					(mid 6.992366 -195.425314)
					(end 6.481826 -195.935854)
				)
				(arc
					(start 6.481826 -196.748654)
					(mid 6.991096 -197.259192)
					(end 7.502906 -196.751194)
				)
				(arc
					(start 7.259066 -196.751194)
					(mid 6.992366 -197.015366)
					(end 6.725666 -196.751194)
				)
				(arc
					(start 6.725666 -196.748654)
					(mid 6.992366 -196.481954)
					(end 7.259066 -196.748654)
				)
				(xy 7.502906 -196.748654) (xy 7.502906 -195.938394)
				(arc
					(start 7.259066 -195.938394)
					(mid 6.992366 -196.202566)
					(end 6.725666 -195.938394)
				)
				(arc
					(start 6.725666 -195.935854)
					(mid 6.992366 -195.669154)
					(end 7.259066 -195.935854)
				)
			)
		)
	)
	(zone
		(layers "B.Cu" "In2.Cu")
		(hatch none 0.5)
		(connect_pads
			(clearance 0)
		)
		(min_thickness 0.25)
		(keepout
			(tracks not_allowed)
			(vias allowed)
			(pads allowed)
			(copperpour not_allowed)
			(footprints allowed)
		)
		(placement
			(enabled no)
			(sheetname "")
		)
		(fill yes
			(thermal_gap 0.5)
			(thermal_bridge_width 0.5)
			(island_removal_mode 0)
		)
		(polygon
			(pts
				(arc
					(start 35.84067 -260.58368)
					(mid 35.33013 -260.07314)
					(end 34.81959 -260.58368)
				)
				(arc
					(start 34.81959 -261.39648)
					(mid 35.32886 -261.907018)
					(end 35.84067 -261.39902)
				)
				(arc
					(start 35.59683 -261.39902)
					(mid 35.33013 -261.663192)
					(end 35.06343 -261.39902)
				)
				(arc
					(start 35.06343 -261.39648)
					(mid 35.33013 -261.12978)
					(end 35.59683 -261.39648)
				)
				(xy 35.84067 -261.39648) (xy 35.84067 -260.58622)
				(arc
					(start 35.59683 -260.58622)
					(mid 35.33013 -260.850392)
					(end 35.06343 -260.58622)
				)
				(arc
					(start 35.06343 -260.58368)
					(mid 35.33013 -260.31698)
					(end 35.59683 -260.58368)
				)
			)
		)
	)
	(zone
		(layers "B.Cu" "In2.Cu")
		(hatch none 0.5)
		(connect_pads
			(clearance 0)
		)
		(min_thickness 0.25)
		(keepout
			(tracks not_allowed)
			(vias allowed)
			(pads allowed)
			(copperpour not_allowed)
			(footprints allowed)
		)
		(placement
			(enabled no)
			(sheetname "")
		)
		(fill yes
			(thermal_gap 0.5)
			(thermal_bridge_width 0.5)
			(island_removal_mode 0)
		)
		(polygon
			(pts
				(arc
					(start 27.18054 -128.8034)
					(mid 26.67 -128.29286)
					(end 26.15946 -128.8034)
				)
				(arc
					(start 26.15946 -129.615946)
					(mid 26.668603 -130.126738)
					(end 27.18054 -129.61874)
				)
				(arc
					(start 26.9367 -129.61874)
					(mid 26.67 -129.882912)
					(end 26.4033 -129.61874)
				)
				(arc
					(start 26.4033 -129.6162)
					(mid 26.67 -129.3495)
					(end 26.9367 -129.6162)
				)
				(xy 27.18054 -129.6162) (xy 27.18054 -128.80594)
				(arc
					(start 26.9367 -128.80594)
					(mid 26.67 -129.070112)
					(end 26.4033 -128.80594)
				)
				(arc
					(start 26.4033 -128.8034)
					(mid 26.67 -128.5367)
					(end 26.9367 -128.8034)
				)
			)
		)
	)
	(zone
		(layers "B.Cu" "In2.Cu")
		(hatch none 0.5)
		(connect_pads
			(clearance 0)
		)
		(min_thickness 0.25)
		(keepout
			(tracks not_allowed)
			(vias allowed)
			(pads allowed)
			(copperpour not_allowed)
			(footprints allowed)
		)
		(placement
			(enabled no)
			(sheetname "")
		)
		(fill yes
			(thermal_gap 0.5)
			(thermal_bridge_width 0.5)
			(island_removal_mode 0)
		)
		(polygon
			(pts
				(arc
					(start 27.18054 -437.803544)
					(mid 26.67 -437.293004)
					(end 26.15946 -437.803544)
				)
				(arc
					(start 26.15946 -438.616344)
					(mid 26.66873 -439.126882)
					(end 27.18054 -438.618884)
				)
				(arc
					(start 26.9367 -438.618884)
					(mid 26.67 -438.883056)
					(end 26.4033 -438.618884)
				)
				(arc
					(start 26.4033 -438.616344)
					(mid 26.67 -438.349644)
					(end 26.9367 -438.616344)
				)
				(xy 27.18054 -438.616344) (xy 27.18054 -437.806084)
				(arc
					(start 26.9367 -437.806084)
					(mid 26.67 -438.070256)
					(end 26.4033 -437.806084)
				)
				(arc
					(start 26.4033 -437.803544)
					(mid 26.67 -437.536844)
					(end 26.9367 -437.803544)
				)
			)
		)
	)
	(zone
		(layers "B.Cu" "In2.Cu")
		(hatch none 0.5)
		(connect_pads
			(clearance 0)
		)
		(min_thickness 0.25)
		(keepout
			(tracks not_allowed)
			(vias allowed)
			(pads allowed)
			(copperpour not_allowed)
			(footprints allowed)
		)
		(placement
			(enabled no)
			(sheetname "")
		)
		(fill yes
			(thermal_gap 0.5)
			(thermal_bridge_width 0.5)
			(island_removal_mode 0)
		)
		(polygon
			(pts
				(arc
					(start 7.502906 -356.335838)
					(mid 6.992366 -355.825298)
					(end 6.481826 -356.335838)
				)
				(arc
					(start 6.481826 -357.148384)
					(mid 6.990969 -357.659176)
					(end 7.502906 -357.151178)
				)
				(arc
					(start 7.259066 -357.151178)
					(mid 6.992366 -357.41535)
					(end 6.725666 -357.151178)
				)
				(arc
					(start 6.725666 -357.148638)
					(mid 6.992366 -356.881938)
					(end 7.259066 -357.148638)
				)
				(xy 7.502906 -357.148638) (xy 7.502906 -356.338378)
				(arc
					(start 7.259066 -356.338378)
					(mid 6.992366 -356.60255)
					(end 6.725666 -356.338378)
				)
				(arc
					(start 6.725666 -356.335838)
					(mid 6.992366 -356.069138)
					(end 7.259066 -356.335838)
				)
			)
		)
	)
	(zone
		(layers "B.Cu" "In2.Cu")
		(hatch none 0.5)
		(connect_pads
			(clearance 0)
		)
		(min_thickness 0.25)
		(keepout
			(tracks not_allowed)
			(vias allowed)
			(pads allowed)
			(copperpour not_allowed)
			(footprints allowed)
		)
		(placement
			(enabled no)
			(sheetname "")
		)
		(fill yes
			(thermal_gap 0.5)
			(thermal_bridge_width 0.5)
			(island_removal_mode 0)
		)
		(polygon
			(pts
				(arc
					(start 35.84067 -179.983638)
					(mid 35.33013 -179.473098)
					(end 34.81959 -179.983638)
				)
				(arc
					(start 34.81959 -180.796438)
					(mid 35.32886 -181.306976)
					(end 35.84067 -180.798978)
				)
				(arc
					(start 35.59683 -180.798978)
					(mid 35.33013 -181.06315)
					(end 35.06343 -180.798978)
				)
				(arc
					(start 35.06343 -180.796438)
					(mid 35.33013 -180.529738)
					(end 35.59683 -180.796438)
				)
				(xy 35.84067 -180.796438) (xy 35.84067 -179.986178)
				(arc
					(start 35.59683 -179.986178)
					(mid 35.33013 -180.25035)
					(end 35.06343 -179.986178)
				)
				(arc
					(start 35.06343 -179.983638)
					(mid 35.33013 -179.716938)
					(end 35.59683 -179.983638)
				)
			)
		)
	)
	(zone
		(layers "B.Cu" "In2.Cu")
		(hatch none 0.5)
		(connect_pads
			(clearance 0)
		)
		(min_thickness 0.25)
		(keepout
			(tracks not_allowed)
			(vias allowed)
			(pads allowed)
			(copperpour not_allowed)
			(footprints allowed)
		)
		(placement
			(enabled no)
			(sheetname "")
		)
		(fill yes
			(thermal_gap 0.5)
			(thermal_bridge_width 0.5)
			(island_removal_mode 0)
		)
		(polygon
			(pts
				(arc
					(start 35.84067 -273.383756)
					(mid 35.33013 -272.873216)
					(end 34.81959 -273.383756)
				)
				(arc
					(start 34.81959 -274.196556)
					(mid 35.32886 -274.707094)
					(end 35.84067 -274.199096)
				)
				(arc
					(start 35.59683 -274.199096)
					(mid 35.33013 -274.463268)
					(end 35.06343 -274.199096)
				)
				(arc
					(start 35.06343 -274.196556)
					(mid 35.33013 -273.929856)
					(end 35.59683 -274.196556)
				)
				(xy 35.84067 -274.196556) (xy 35.84067 -273.386296)
				(arc
					(start 35.59683 -273.386296)
					(mid 35.33013 -273.650468)
					(end 35.06343 -273.386296)
				)
				(arc
					(start 35.06343 -273.383756)
					(mid 35.33013 -273.117056)
					(end 35.59683 -273.383756)
				)
			)
		)
	)
	(zone
		(layers "B.Cu" "In2.Cu")
		(hatch none 0.5)
		(connect_pads
			(clearance 0)
		)
		(min_thickness 0.25)
		(keepout
			(tracks not_allowed)
			(vias allowed)
			(pads allowed)
			(copperpour not_allowed)
			(footprints allowed)
		)
		(placement
			(enabled no)
			(sheetname "")
		)
		(fill yes
			(thermal_gap 0.5)
			(thermal_bridge_width 0.5)
			(island_removal_mode 0)
		)
		(polygon
			(pts
				(arc
					(start 7.502906 -281.986736)
					(mid 6.992366 -281.476196)
					(end 6.481826 -281.986736)
				)
				(arc
					(start 6.481826 -282.799536)
					(mid 6.991096 -283.310074)
					(end 7.502906 -282.802076)
				)
				(arc
					(start 7.259066 -282.802076)
					(mid 6.992366 -283.066248)
					(end 6.725666 -282.802076)
				)
				(arc
					(start 6.725666 -282.799536)
					(mid 6.992366 -282.532836)
					(end 7.259066 -282.799536)
				)
				(xy 7.502906 -282.799536) (xy 7.502906 -281.989276)
				(arc
					(start 7.259066 -281.989276)
					(mid 6.992366 -282.253448)
					(end 6.725666 -281.989276)
				)
				(arc
					(start 6.725666 -281.986736)
					(mid 6.992366 -281.720036)
					(end 7.259066 -281.986736)
				)
			)
		)
	)
	(zone
		(layers "B.Cu" "In2.Cu")
		(hatch none 0.5)
		(connect_pads
			(clearance 0)
		)
		(min_thickness 0.25)
		(keepout
			(tracks not_allowed)
			(vias allowed)
			(pads allowed)
			(copperpour not_allowed)
			(footprints allowed)
		)
		(placement
			(enabled no)
			(sheetname "")
		)
		(fill yes
			(thermal_gap 0.5)
			(thermal_bridge_width 0.5)
			(island_removal_mode 0)
		)
		(polygon
			(pts
				(arc
					(start 7.502906 -155.974034)
					(mid 6.992366 -155.463494)
					(end 6.481826 -155.974034)
				)
				(arc
					(start 6.481826 -156.786834)
					(mid 6.991096 -157.297372)
					(end 7.502906 -156.789374)
				)
				(arc
					(start 7.259066 -156.789374)
					(mid 6.992366 -157.053546)
					(end 6.725666 -156.789374)
				)
				(arc
					(start 6.725666 -156.786834)
					(mid 6.992366 -156.520134)
					(end 7.259066 -156.786834)
				)
				(xy 7.502906 -156.786834) (xy 7.502906 -155.976574)
				(arc
					(start 7.259066 -155.976574)
					(mid 6.992366 -156.240746)
					(end 6.725666 -155.976574)
				)
				(arc
					(start 6.725666 -155.974034)
					(mid 6.992366 -155.707334)
					(end 7.259066 -155.974034)
				)
			)
		)
	)
	(zone
		(layers "B.Cu" "In2.Cu")
		(hatch none 0.5)
		(connect_pads
			(clearance 0)
		)
		(min_thickness 0.25)
		(keepout
			(tracks not_allowed)
			(vias allowed)
			(pads allowed)
			(copperpour not_allowed)
			(footprints allowed)
		)
		(placement
			(enabled no)
			(sheetname "")
		)
		(fill yes
			(thermal_gap 0.5)
			(thermal_bridge_width 0.5)
			(island_removal_mode 0)
		)
		(polygon
			(pts
				(arc
					(start 7.502906 -304.335942)
					(mid 6.992366 -303.825402)
					(end 6.481826 -304.335942)
				)
				(arc
					(start 6.481826 -305.148488)
					(mid 6.990969 -305.65928)
					(end 7.502906 -305.151282)
				)
				(arc
					(start 7.259066 -305.151282)
					(mid 6.992366 -305.415454)
					(end 6.725666 -305.151282)
				)
				(arc
					(start 6.725666 -305.148742)
					(mid 6.992366 -304.882042)
					(end 7.259066 -305.148742)
				)
				(xy 7.502906 -305.148742) (xy 7.502906 -304.338482)
				(arc
					(start 7.259066 -304.338482)
					(mid 6.992366 -304.602654)
					(end 6.725666 -304.338482)
				)
				(arc
					(start 6.725666 -304.335942)
					(mid 6.992366 -304.069242)
					(end 7.259066 -304.335942)
				)
			)
		)
	)
	(zone
		(layers "B.Cu" "In2.Cu")
		(hatch none 0.5)
		(connect_pads
			(clearance 0)
		)
		(min_thickness 0.25)
		(keepout
			(tracks not_allowed)
			(vias allowed)
			(pads allowed)
			(copperpour not_allowed)
			(footprints allowed)
		)
		(placement
			(enabled no)
			(sheetname "")
		)
		(fill yes
			(thermal_gap 0.5)
			(thermal_bridge_width 0.5)
			(island_removal_mode 0)
		)
		(polygon
			(pts
				(arc
					(start 220.840554 -179.983638)
					(mid 220.330014 -179.473098)
					(end 219.819474 -179.983638)
				)
				(arc
					(start 219.819474 -180.796438)
					(mid 220.328744 -181.306976)
					(end 220.840554 -180.798978)
				)
				(arc
					(start 220.596714 -180.798978)
					(mid 220.330014 -181.06315)
					(end 220.063314 -180.798978)
				)
				(arc
					(start 220.063314 -180.796438)
					(mid 220.330014 -180.529738)
					(end 220.596714 -180.796438)
				)
				(xy 220.840554 -180.796438) (xy 220.840554 -179.986178)
				(arc
					(start 220.596714 -179.986178)
					(mid 220.330014 -180.25035)
					(end 220.063314 -179.986178)
				)
				(arc
					(start 220.063314 -179.983638)
					(mid 220.330014 -179.716938)
					(end 220.596714 -179.983638)
				)
			)
		)
	)
	(zone
		(layers "B.Cu" "In2.Cu")
		(hatch none 0.5)
		(connect_pads
			(clearance 0)
		)
		(min_thickness 0.25)
		(keepout
			(tracks not_allowed)
			(vias allowed)
			(pads allowed)
			(copperpour not_allowed)
			(footprints allowed)
		)
		(placement
			(enabled no)
			(sheetname "")
		)
		(fill yes
			(thermal_gap 0.5)
			(thermal_bridge_width 0.5)
			(island_removal_mode 0)
		)
		(polygon
			(pts
				(arc
					(start 220.840554 -479.383852)
					(mid 220.330014 -478.873312)
					(end 219.819474 -479.383852)
				)
				(arc
					(start 219.819474 -480.196652)
					(mid 220.328744 -480.70719)
					(end 220.840554 -480.199192)
				)
				(arc
					(start 220.596714 -480.199192)
					(mid 220.330014 -480.463364)
					(end 220.063314 -480.199192)
				)
				(arc
					(start 220.063314 -480.196652)
					(mid 220.330014 -479.929952)
					(end 220.596714 -480.196652)
				)
				(xy 220.840554 -480.196652) (xy 220.840554 -479.386392)
				(arc
					(start 220.596714 -479.386392)
					(mid 220.330014 -479.650564)
					(end 220.063314 -479.386392)
				)
				(arc
					(start 220.063314 -479.383852)
					(mid 220.330014 -479.117152)
					(end 220.596714 -479.383852)
				)
			)
		)
	)
	(zone
		(layers "B.Cu" "In2.Cu")
		(hatch none 0.5)
		(connect_pads
			(clearance 0)
		)
		(min_thickness 0.25)
		(keepout
			(tracks not_allowed)
			(vias allowed)
			(pads allowed)
			(copperpour not_allowed)
			(footprints allowed)
		)
		(placement
			(enabled no)
			(sheetname "")
		)
		(fill yes
			(thermal_gap 0.5)
			(thermal_bridge_width 0.5)
			(island_removal_mode 0)
		)
		(polygon
			(pts
				(arc
					(start 35.84067 -363.583728)
					(mid 35.33013 -363.073188)
					(end 34.81959 -363.583728)
				)
				(arc
					(start 34.81959 -364.396528)
					(mid 35.32886 -364.907066)
					(end 35.84067 -364.399068)
				)
				(arc
					(start 35.59683 -364.399068)
					(mid 35.33013 -364.66324)
					(end 35.06343 -364.399068)
				)
				(arc
					(start 35.06343 -364.396528)
					(mid 35.33013 -364.129828)
					(end 35.59683 -364.396528)
				)
				(xy 35.84067 -364.396528) (xy 35.84067 -363.586268)
				(arc
					(start 35.59683 -363.586268)
					(mid 35.33013 -363.85044)
					(end 35.06343 -363.586268)
				)
				(arc
					(start 35.06343 -363.583728)
					(mid 35.33013 -363.317028)
					(end 35.59683 -363.583728)
				)
			)
		)
	)
	(zone
		(layers "B.Cu" "In2.Cu")
		(hatch none 0.5)
		(connect_pads
			(clearance 0)
		)
		(min_thickness 0.25)
		(keepout
			(tracks not_allowed)
			(vias allowed)
			(pads allowed)
			(copperpour not_allowed)
			(footprints allowed)
		)
		(placement
			(enabled no)
			(sheetname "")
		)
		(fill yes
			(thermal_gap 0.5)
			(thermal_bridge_width 0.5)
			(island_removal_mode 0)
		)
		(polygon
			(pts
				(arc
					(start 7.502906 -220.685106)
					(mid 6.992366 -220.174566)
					(end 6.481826 -220.685106)
				)
				(arc
					(start 6.481826 -221.497652)
					(mid 6.990969 -222.008444)
					(end 7.502906 -221.500446)
				)
				(arc
					(start 7.259066 -221.500446)
					(mid 6.992366 -221.764618)
					(end 6.725666 -221.500446)
				)
				(arc
					(start 6.725666 -221.497906)
					(mid 6.992366 -221.231206)
					(end 7.259066 -221.497906)
				)
				(xy 7.502906 -221.497906) (xy 7.502906 -220.687646)
				(arc
					(start 7.259066 -220.687646)
					(mid 6.992366 -220.951818)
					(end 6.725666 -220.687646)
				)
				(arc
					(start 6.725666 -220.685106)
					(mid 6.992366 -220.418406)
					(end 7.259066 -220.685106)
				)
			)
		)
	)
	(zone
		(layers "B.Cu" "In2.Cu")
		(hatch none 0.5)
		(connect_pads
			(clearance 0)
		)
		(min_thickness 0.25)
		(keepout
			(tracks not_allowed)
			(vias allowed)
			(pads allowed)
			(copperpour not_allowed)
			(footprints allowed)
		)
		(placement
			(enabled no)
			(sheetname "")
		)
		(fill yes
			(thermal_gap 0.5)
			(thermal_bridge_width 0.5)
			(island_removal_mode 0)
		)
		(polygon
			(pts
				(arc
					(start 220.840554 -488.983782)
					(mid 220.330014 -488.473242)
					(end 219.819474 -488.983782)
				)
				(arc
					(start 219.819474 -489.796582)
					(mid 220.328744 -490.30712)
					(end 220.840554 -489.799122)
				)
				(arc
					(start 220.596714 -489.799122)
					(mid 220.330014 -490.063294)
					(end 220.063314 -489.799122)
				)
				(arc
					(start 220.063314 -489.796582)
					(mid 220.330014 -489.529882)
					(end 220.596714 -489.796582)
				)
				(xy 220.840554 -489.796582) (xy 220.840554 -488.986322)
				(arc
					(start 220.596714 -488.986322)
					(mid 220.330014 -489.250494)
					(end 220.063314 -488.986322)
				)
				(arc
					(start 220.063314 -488.983782)
					(mid 220.330014 -488.717082)
					(end 220.596714 -488.983782)
				)
			)
		)
	)
	(zone
		(layers "B.Cu" "In2.Cu")
		(hatch none 0.5)
		(connect_pads
			(clearance 0)
		)
		(min_thickness 0.25)
		(keepout
			(tracks not_allowed)
			(vias allowed)
			(pads allowed)
			(copperpour not_allowed)
			(footprints allowed)
		)
		(placement
			(enabled no)
			(sheetname "")
		)
		(fill yes
			(thermal_gap 0.5)
			(thermal_bridge_width 0.5)
			(island_removal_mode 0)
		)
		(polygon
			(pts
				(arc
					(start 7.502906 -297.935904)
					(mid 6.992366 -297.425364)
					(end 6.481826 -297.935904)
				)
				(arc
					(start 6.481826 -298.74845)
					(mid 6.990969 -299.259242)
					(end 7.502906 -298.751244)
				)
				(arc
					(start 7.259066 -298.751244)
					(mid 6.992366 -299.015416)
					(end 6.725666 -298.751244)
				)
				(arc
					(start 6.725666 -298.748704)
					(mid 6.992366 -298.482004)
					(end 7.259066 -298.748704)
				)
				(xy 7.502906 -298.748704) (xy 7.502906 -297.938444)
				(arc
					(start 7.259066 -297.938444)
					(mid 6.992366 -298.202616)
					(end 6.725666 -297.938444)
				)
				(arc
					(start 6.725666 -297.935904)
					(mid 6.992366 -297.669204)
					(end 7.259066 -297.935904)
				)
			)
		)
	)
	(zone
		(layers "B.Cu" "In2.Cu")
		(hatch none 0.5)
		(connect_pads
			(clearance 0)
		)
		(min_thickness 0.25)
		(keepout
			(tracks not_allowed)
			(vias allowed)
			(pads allowed)
			(copperpour not_allowed)
			(footprints allowed)
		)
		(placement
			(enabled no)
			(sheetname "")
		)
		(fill yes
			(thermal_gap 0.5)
			(thermal_bridge_width 0.5)
			(island_removal_mode 0)
		)
		(polygon
			(pts
				(arc
					(start 220.840554 -278.183594)
					(mid 220.330014 -277.673054)
					(end 219.819474 -278.183594)
				)
				(arc
					(start 219.819474 -278.996394)
					(mid 220.328744 -279.506932)
					(end 220.840554 -278.998934)
				)
				(arc
					(start 220.596714 -278.998934)
					(mid 220.330014 -279.263106)
					(end 220.063314 -278.998934)
				)
				(arc
					(start 220.063314 -278.996394)
					(mid 220.330014 -278.729694)
					(end 220.596714 -278.996394)
				)
				(xy 220.840554 -278.996394) (xy 220.840554 -278.186134)
				(arc
					(start 220.596714 -278.186134)
					(mid 220.330014 -278.450306)
					(end 220.063314 -278.186134)
				)
				(arc
					(start 220.063314 -278.183594)
					(mid 220.330014 -277.916894)
					(end 220.596714 -278.183594)
				)
			)
		)
	)
	(zone
		(layers "B.Cu" "In2.Cu")
		(hatch none 0.5)
		(connect_pads
			(clearance 0)
		)
		(min_thickness 0.25)
		(keepout
			(tracks not_allowed)
			(vias allowed)
			(pads allowed)
			(copperpour not_allowed)
			(footprints allowed)
		)
		(placement
			(enabled no)
			(sheetname "")
		)
		(fill yes
			(thermal_gap 0.5)
			(thermal_bridge_width 0.5)
			(island_removal_mode 0)
		)
		(polygon
			(pts
				(arc
					(start 35.84067 -170.383708)
					(mid 35.33013 -169.873168)
					(end 34.81959 -170.383708)
				)
				(arc
					(start 34.81959 -171.196508)
					(mid 35.32886 -171.707046)
					(end 35.84067 -171.199048)
				)
				(arc
					(start 35.59683 -171.199048)
					(mid 35.33013 -171.46322)
					(end 35.06343 -171.199048)
				)
				(arc
					(start 35.06343 -171.196508)
					(mid 35.33013 -170.929808)
					(end 35.59683 -171.196508)
				)
				(xy 35.84067 -171.196508) (xy 35.84067 -170.386248)
				(arc
					(start 35.59683 -170.386248)
					(mid 35.33013 -170.65042)
					(end 35.06343 -170.386248)
				)
				(arc
					(start 35.06343 -170.383708)
					(mid 35.33013 -170.117008)
					(end 35.59683 -170.383708)
				)
			)
		)
	)
	(zone
		(layers "B.Cu" "In2.Cu")
		(hatch none 0.5)
		(connect_pads
			(clearance 0)
		)
		(min_thickness 0.25)
		(keepout
			(tracks not_allowed)
			(vias allowed)
			(pads allowed)
			(copperpour not_allowed)
			(footprints allowed)
		)
		(placement
			(enabled no)
			(sheetname "")
		)
		(fill yes
			(thermal_gap 0.5)
			(thermal_bridge_width 0.5)
			(island_removal_mode 0)
		)
		(polygon
			(pts
				(arc
					(start 27.18054 -433.003706)
					(mid 26.67 -432.493166)
					(end 26.15946 -433.003706)
				)
				(arc
					(start 26.15946 -433.816506)
					(mid 26.66873 -434.327044)
					(end 27.18054 -433.819046)
				)
				(arc
					(start 26.9367 -433.819046)
					(mid 26.67 -434.083218)
					(end 26.4033 -433.819046)
				)
				(arc
					(start 26.4033 -433.816506)
					(mid 26.67 -433.549806)
					(end 26.9367 -433.816506)
				)
				(xy 27.18054 -433.816506) (xy 27.18054 -433.006246)
				(arc
					(start 26.9367 -433.006246)
					(mid 26.67 -433.270418)
					(end 26.4033 -433.006246)
				)
				(arc
					(start 26.4033 -433.003706)
					(mid 26.67 -432.737006)
					(end 26.9367 -433.003706)
				)
			)
		)
	)
	(zone
		(layers "B.Cu" "In2.Cu")
		(hatch none 0.5)
		(connect_pads
			(clearance 0)
		)
		(min_thickness 0.25)
		(keepout
			(tracks not_allowed)
			(vias allowed)
			(pads allowed)
			(copperpour not_allowed)
			(footprints allowed)
		)
		(placement
			(enabled no)
			(sheetname "")
		)
		(fill yes
			(thermal_gap 0.5)
			(thermal_bridge_width 0.5)
			(island_removal_mode 0)
		)
		(polygon
			(pts
				(arc
					(start 7.502906 -396.735808)
					(mid 6.992366 -396.225268)
					(end 6.481826 -396.735808)
				)
				(arc
					(start 6.481826 -397.548608)
					(mid 6.991096 -398.059146)
					(end 7.502906 -397.551148)
				)
				(arc
					(start 7.259066 -397.551148)
					(mid 6.992366 -397.81532)
					(end 6.725666 -397.551148)
				)
				(arc
					(start 6.725666 -397.548608)
					(mid 6.992366 -397.281908)
					(end 7.259066 -397.548608)
				)
				(xy 7.502906 -397.548608) (xy 7.502906 -396.738348)
				(arc
					(start 7.259066 -396.738348)
					(mid 6.992366 -397.00252)
					(end 6.725666 -396.738348)
				)
				(arc
					(start 6.725666 -396.735808)
					(mid 6.992366 -396.469108)
					(end 7.259066 -396.735808)
				)
			)
		)
	)
	(zone
		(layers "B.Cu" "In2.Cu")
		(hatch none 0.5)
		(connect_pads
			(clearance 0)
		)
		(min_thickness 0.25)
		(keepout
			(tracks not_allowed)
			(vias allowed)
			(pads allowed)
			(copperpour not_allowed)
			(footprints allowed)
		)
		(placement
			(enabled no)
			(sheetname "")
		)
		(fill yes
			(thermal_gap 0.5)
			(thermal_bridge_width 0.5)
			(island_removal_mode 0)
		)
		(polygon
			(pts
				(arc
					(start 7.502906 -175.186594)
					(mid 6.992366 -174.676054)
					(end 6.481826 -175.186594)
				)
				(arc
					(start 6.481826 -175.999394)
					(mid 6.991096 -176.509932)
					(end 7.502906 -176.001934)
				)
				(arc
					(start 7.259066 -176.001934)
					(mid 6.992366 -176.266106)
					(end 6.725666 -176.001934)
				)
				(arc
					(start 6.725666 -175.999394)
					(mid 6.992366 -175.732694)
					(end 7.259066 -175.999394)
				)
				(xy 7.502906 -175.999394) (xy 7.502906 -175.189134)
				(arc
					(start 7.259066 -175.189134)
					(mid 6.992366 -175.453306)
					(end 6.725666 -175.189134)
				)
				(arc
					(start 6.725666 -175.186594)
					(mid 6.992366 -174.919894)
					(end 7.259066 -175.186594)
				)
			)
		)
	)
	(zone
		(layers "B.Cu" "In2.Cu")
		(hatch none 0.5)
		(connect_pads
			(clearance 0)
		)
		(min_thickness 0.25)
		(keepout
			(tracks not_allowed)
			(vias allowed)
			(pads allowed)
			(copperpour not_allowed)
			(footprints allowed)
		)
		(placement
			(enabled no)
			(sheetname "")
		)
		(fill yes
			(thermal_gap 0.5)
			(thermal_bridge_width 0.5)
			(island_removal_mode 0)
		)
		(polygon
			(pts
				(arc
					(start 7.502906 -288.335974)
					(mid 6.992366 -287.825434)
					(end 6.481826 -288.335974)
				)
				(arc
					(start 6.481826 -289.148774)
					(mid 6.991096 -289.659312)
					(end 7.502906 -289.151314)
				)
				(arc
					(start 7.259066 -289.151314)
					(mid 6.992366 -289.415486)
					(end 6.725666 -289.151314)
				)
				(arc
					(start 6.725666 -289.148774)
					(mid 6.992366 -288.882074)
					(end 7.259066 -289.148774)
				)
				(xy 7.502906 -289.148774) (xy 7.502906 -288.338514)
				(arc
					(start 7.259066 -288.338514)
					(mid 6.992366 -288.602686)
					(end 6.725666 -288.338514)
				)
				(arc
					(start 6.725666 -288.335974)
					(mid 6.992366 -288.069274)
					(end 7.259066 -288.335974)
				)
			)
		)
	)
	(zone
		(layers "B.Cu" "In2.Cu")
		(hatch none 0.5)
		(connect_pads
			(clearance 0)
		)
		(min_thickness 0.25)
		(keepout
			(tracks not_allowed)
			(vias allowed)
			(pads allowed)
			(copperpour not_allowed)
			(footprints allowed)
		)
		(placement
			(enabled no)
			(sheetname "")
		)
		(fill yes
			(thermal_gap 0.5)
			(thermal_bridge_width 0.5)
			(island_removal_mode 0)
		)
		(polygon
			(pts
				(arc
					(start 35.84067 -278.183594)
					(mid 35.33013 -277.673054)
					(end 34.81959 -278.183594)
				)
				(arc
					(start 34.81959 -278.996394)
					(mid 35.32886 -279.506932)
					(end 35.84067 -278.998934)
				)
				(arc
					(start 35.59683 -278.998934)
					(mid 35.33013 -279.263106)
					(end 35.06343 -278.998934)
				)
				(arc
					(start 35.06343 -278.996394)
					(mid 35.33013 -278.729694)
					(end 35.59683 -278.996394)
				)
				(xy 35.84067 -278.996394) (xy 35.84067 -278.186134)
				(arc
					(start 35.59683 -278.186134)
					(mid 35.33013 -278.450306)
					(end 35.06343 -278.186134)
				)
				(arc
					(start 35.06343 -278.183594)
					(mid 35.33013 -277.916894)
					(end 35.59683 -278.183594)
				)
			)
		)
	)
	(zone
		(layers "B.Cu" "In2.Cu")
		(hatch none 0.5)
		(connect_pads
			(clearance 0)
		)
		(min_thickness 0.25)
		(keepout
			(tracks not_allowed)
			(vias allowed)
			(pads allowed)
			(copperpour not_allowed)
			(footprints allowed)
		)
		(placement
			(enabled no)
			(sheetname "")
		)
		(fill yes
			(thermal_gap 0.5)
			(thermal_bridge_width 0.5)
			(island_removal_mode 0)
		)
		(polygon
			(pts
				(arc
					(start 7.502906 -204.735938)
					(mid 6.992366 -204.225398)
					(end 6.481826 -204.735938)
				)
				(arc
					(start 6.481826 -205.548738)
					(mid 6.991096 -206.059276)
					(end 7.502906 -205.551278)
				)
				(arc
					(start 7.259066 -205.551278)
					(mid 6.992366 -205.81545)
					(end 6.725666 -205.551278)
				)
				(arc
					(start 6.725666 -205.548738)
					(mid 6.992366 -205.282038)
					(end 7.259066 -205.548738)
				)
				(xy 7.502906 -205.548738) (xy 7.502906 -204.738478)
				(arc
					(start 7.259066 -204.738478)
					(mid 6.992366 -205.00265)
					(end 6.725666 -204.738478)
				)
				(arc
					(start 6.725666 -204.735938)
					(mid 6.992366 -204.469238)
					(end 7.259066 -204.735938)
				)
			)
		)
	)
	(zone
		(layers "B.Cu" "In2.Cu")
		(hatch none 0.5)
		(connect_pads
			(clearance 0)
		)
		(min_thickness 0.25)
		(keepout
			(tracks not_allowed)
			(vias allowed)
			(pads allowed)
			(copperpour not_allowed)
			(footprints allowed)
		)
		(placement
			(enabled no)
			(sheetname "")
		)
		(fill yes
			(thermal_gap 0.5)
			(thermal_bridge_width 0.5)
			(island_removal_mode 0)
		)
		(polygon
			(pts
				(arc
					(start 27.18054 -119.20347)
					(mid 26.67 -118.69293)
					(end 26.15946 -119.20347)
				)
				(arc
					(start 26.15946 -120.016016)
					(mid 26.668603 -120.526808)
					(end 27.18054 -120.01881)
				)
				(arc
					(start 26.9367 -120.01881)
					(mid 26.67 -120.282982)
					(end 26.4033 -120.01881)
				)
				(arc
					(start 26.4033 -120.01627)
					(mid 26.67 -119.74957)
					(end 26.9367 -120.01627)
				)
				(xy 27.18054 -120.01627) (xy 27.18054 -119.20601)
				(arc
					(start 26.9367 -119.20601)
					(mid 26.67 -119.470182)
					(end 26.4033 -119.20601)
				)
				(arc
					(start 26.4033 -119.20347)
					(mid 26.67 -118.93677)
					(end 26.9367 -119.20347)
				)
			)
		)
	)
	(zone
		(layers "B.Cu" "In2.Cu")
		(hatch none 0.5)
		(connect_pads
			(clearance 0)
		)
		(min_thickness 0.25)
		(keepout
			(tracks not_allowed)
			(vias allowed)
			(pads allowed)
			(copperpour not_allowed)
			(footprints allowed)
		)
		(placement
			(enabled no)
			(sheetname "")
		)
		(fill yes
			(thermal_gap 0.5)
			(thermal_bridge_width 0.5)
			(island_removal_mode 0)
		)
		(polygon
			(pts
				(arc
					(start 7.502906 -431.184304)
					(mid 6.992366 -430.673764)
					(end 6.481826 -431.184304)
				)
				(arc
					(start 6.481826 -431.997104)
					(mid 6.991096 -432.507642)
					(end 7.502906 -431.999644)
				)
				(arc
					(start 7.259066 -431.999644)
					(mid 6.992366 -432.263816)
					(end 6.725666 -431.999644)
				)
				(arc
					(start 6.725666 -431.997104)
					(mid 6.992366 -431.730404)
					(end 7.259066 -431.997104)
				)
				(xy 7.502906 -431.997104) (xy 7.502906 -431.186844)
				(arc
					(start 7.259066 -431.186844)
					(mid 6.992366 -431.451016)
					(end 6.725666 -431.186844)
				)
				(arc
					(start 6.725666 -431.184304)
					(mid 6.992366 -430.917604)
					(end 7.259066 -431.184304)
				)
			)
		)
	)
	(zone
		(layers "B.Cu" "In5.Cu")
		(hatch none 0.5)
		(connect_pads
			(clearance 0)
		)
		(min_thickness 0.25)
		(keepout
			(tracks not_allowed)
			(vias allowed)
			(pads allowed)
			(copperpour not_allowed)
			(footprints allowed)
		)
		(placement
			(enabled no)
			(sheetname "")
		)
		(fill yes
			(thermal_gap 0.5)
			(thermal_bridge_width 0.5)
			(island_removal_mode 0)
		)
		(polygon
			(pts
				(arc
					(start 37.33927 -388.23138)
					(mid 36.72713 -387.61924)
					(end 36.11499 -388.23138)
				)
				(arc
					(start 36.11499 -389.34898)
					(mid 36.72586 -389.961119)
					(end 37.33927 -389.35152)
				)
				(arc
					(start 36.99383 -389.35152)
					(mid 36.72713 -389.615692)
					(end 36.46043 -389.35152)
				)
				(arc
					(start 36.46043 -389.34898)
					(mid 36.72713 -389.08228)
					(end 36.99383 -389.34898)
				)
				(xy 37.33927 -389.34898) (xy 37.33927 -388.23392)
				(arc
					(start 36.99383 -388.23392)
					(mid 36.72713 -388.498092)
					(end 36.46043 -388.23392)
				)
				(arc
					(start 36.46043 -388.23138)
					(mid 36.72713 -387.96468)
					(end 36.99383 -388.23138)
				)
			)
		)
	)
	(zone
		(layers "B.Cu" "In5.Cu")
		(hatch none 0.5)
		(connect_pads
			(clearance 0)
		)
		(min_thickness 0.25)
		(keepout
			(tracks not_allowed)
			(vias allowed)
			(pads allowed)
			(copperpour not_allowed)
			(footprints allowed)
		)
		(placement
			(enabled no)
			(sheetname "")
		)
		(fill yes
			(thermal_gap 0.5)
			(thermal_bridge_width 0.5)
			(island_removal_mode 0)
		)
		(polygon
			(pts
				(arc
					(start 222.339154 -74.431144)
					(mid 221.727014 -73.819004)
					(end 221.114874 -74.431144)
				)
				(arc
					(start 221.114874 -75.548744)
					(mid 221.725744 -76.160883)
					(end 222.339154 -75.551284)
				)
				(arc
					(start 221.993714 -75.551284)
					(mid 221.727014 -75.815456)
					(end 221.460314 -75.551284)
				)
				(arc
					(start 221.460314 -75.548744)
					(mid 221.727014 -75.282044)
					(end 221.993714 -75.548744)
				)
				(xy 222.339154 -75.548744) (xy 222.339154 -74.433684)
				(arc
					(start 221.993714 -74.433684)
					(mid 221.727014 -74.697856)
					(end 221.460314 -74.433684)
				)
				(arc
					(start 221.460314 -74.431144)
					(mid 221.727014 -74.164444)
					(end 221.993714 -74.431144)
				)
			)
		)
	)
	(zone
		(layers "B.Cu" "In5.Cu")
		(hatch none 0.5)
		(connect_pads
			(clearance 0)
		)
		(min_thickness 0.25)
		(keepout
			(tracks not_allowed)
			(vias allowed)
			(pads allowed)
			(copperpour not_allowed)
			(footprints allowed)
		)
		(placement
			(enabled no)
			(sheetname "")
		)
		(fill yes
			(thermal_gap 0.5)
			(thermal_bridge_width 0.5)
			(island_removal_mode 0)
		)
		(polygon
			(pts
				(arc
					(start 37.33927 -285.231332)
					(mid 36.72713 -284.619192)
					(end 36.11499 -285.231332)
				)
				(arc
					(start 36.11499 -286.348932)
					(mid 36.72586 -286.961071)
					(end 37.33927 -286.351472)
				)
				(arc
					(start 36.99383 -286.351472)
					(mid 36.72713 -286.615644)
					(end 36.46043 -286.351472)
				)
				(arc
					(start 36.46043 -286.348932)
					(mid 36.72713 -286.082232)
					(end 36.99383 -286.348932)
				)
				(xy 37.33927 -286.348932) (xy 37.33927 -285.233872)
				(arc
					(start 36.99383 -285.233872)
					(mid 36.72713 -285.498044)
					(end 36.46043 -285.233872)
				)
				(arc
					(start 36.46043 -285.231332)
					(mid 36.72713 -284.964632)
					(end 36.99383 -285.231332)
				)
			)
		)
	)
	(zone
		(layers "B.Cu" "In5.Cu")
		(hatch none 0.5)
		(connect_pads
			(clearance 0)
		)
		(min_thickness 0.25)
		(keepout
			(tracks not_allowed)
			(vias allowed)
			(pads allowed)
			(copperpour not_allowed)
			(footprints allowed)
		)
		(placement
			(enabled no)
			(sheetname "")
		)
		(fill yes
			(thermal_gap 0.5)
			(thermal_bridge_width 0.5)
			(island_removal_mode 0)
		)
		(polygon
			(pts
				(arc
					(start 37.33927 -159.831278)
					(mid 36.72713 -159.219138)
					(end 36.11499 -159.831278)
				)
				(arc
					(start 36.11499 -160.948878)
					(mid 36.72586 -161.561017)
					(end 37.33927 -160.951418)
				)
				(arc
					(start 36.99383 -160.951418)
					(mid 36.72713 -161.21559)
					(end 36.46043 -160.951418)
				)
				(arc
					(start 36.46043 -160.948878)
					(mid 36.72713 -160.682178)
					(end 36.99383 -160.948878)
				)
				(xy 37.33927 -160.948878) (xy 37.33927 -159.833818)
				(arc
					(start 36.99383 -159.833818)
					(mid 36.72713 -160.09799)
					(end 36.46043 -159.833818)
				)
				(arc
					(start 36.46043 -159.831278)
					(mid 36.72713 -159.564578)
					(end 36.99383 -159.831278)
				)
			)
		)
	)
	(zone
		(layers "B.Cu" "In5.Cu")
		(hatch none 0.5)
		(connect_pads
			(clearance 0)
		)
		(min_thickness 0.25)
		(keepout
			(tracks not_allowed)
			(vias allowed)
			(pads allowed)
			(copperpour not_allowed)
			(footprints allowed)
		)
		(placement
			(enabled no)
			(sheetname "")
		)
		(fill yes
			(thermal_gap 0.5)
			(thermal_bridge_width 0.5)
			(island_removal_mode 0)
		)
		(polygon
			(pts
				(arc
					(start 25.88514 -435.251352)
					(mid 25.273 -434.639212)
					(end 24.66086 -435.251352)
				)
				(arc
					(start 24.66086 -436.368952)
					(mid 25.27173 -436.981091)
					(end 25.88514 -436.371492)
				)
				(arc
					(start 25.5397 -436.371492)
					(mid 25.273 -436.635664)
					(end 25.0063 -436.371492)
				)
				(arc
					(start 25.0063 -436.368952)
					(mid 25.273 -436.102252)
					(end 25.5397 -436.368952)
				)
				(xy 25.88514 -436.368952) (xy 25.88514 -435.253892)
				(arc
					(start 25.5397 -435.253892)
					(mid 25.273 -435.518064)
					(end 25.0063 -435.253892)
				)
				(arc
					(start 25.0063 -435.251352)
					(mid 25.273 -434.984652)
					(end 25.5397 -435.251352)
				)
			)
		)
	)
	(zone
		(layers "B.Cu" "In5.Cu")
		(hatch none 0.5)
		(connect_pads
			(clearance 0)
		)
		(min_thickness 0.25)
		(keepout
			(tracks not_allowed)
			(vias allowed)
			(pads allowed)
			(copperpour not_allowed)
			(footprints allowed)
		)
		(placement
			(enabled no)
			(sheetname "")
		)
		(fill yes
			(thermal_gap 0.5)
			(thermal_bridge_width 0.5)
			(island_removal_mode 0)
		)
		(polygon
			(pts
				(arc
					(start 37.33927 -365.831374)
					(mid 36.72713 -365.219234)
					(end 36.11499 -365.831374)
				)
				(arc
					(start 36.11499 -366.948974)
					(mid 36.72586 -367.561113)
					(end 37.33927 -366.951514)
				)
				(arc
					(start 36.99383 -366.951514)
					(mid 36.72713 -367.215686)
					(end 36.46043 -366.951514)
				)
				(arc
					(start 36.46043 -366.948974)
					(mid 36.72713 -366.682274)
					(end 36.99383 -366.948974)
				)
				(xy 37.33927 -366.948974) (xy 37.33927 -365.833914)
				(arc
					(start 36.99383 -365.833914)
					(mid 36.72713 -366.098086)
					(end 36.46043 -365.833914)
				)
				(arc
					(start 36.46043 -365.831374)
					(mid 36.72713 -365.564674)
					(end 36.99383 -365.831374)
				)
			)
		)
	)
	(zone
		(layers "B.Cu" "In5.Cu")
		(hatch none 0.5)
		(connect_pads
			(clearance 0)
		)
		(min_thickness 0.25)
		(keepout
			(tracks not_allowed)
			(vias allowed)
			(pads allowed)
			(copperpour not_allowed)
			(footprints allowed)
		)
		(placement
			(enabled no)
			(sheetname "")
		)
		(fill yes
			(thermal_gap 0.5)
			(thermal_bridge_width 0.5)
			(island_removal_mode 0)
		)
		(polygon
			(pts
				(arc
					(start 222.339154 -481.631244)
					(mid 221.727014 -481.019104)
					(end 221.114874 -481.631244)
				)
				(arc
					(start 221.114874 -482.748844)
					(mid 221.725744 -483.360983)
					(end 222.339154 -482.751384)
				)
				(arc
					(start 221.993714 -482.751384)
					(mid 221.727014 -483.015556)
					(end 221.460314 -482.751384)
				)
				(arc
					(start 221.460314 -482.748844)
					(mid 221.727014 -482.482144)
					(end 221.993714 -482.748844)
				)
				(xy 222.339154 -482.748844) (xy 222.339154 -481.633784)
				(arc
					(start 221.993714 -481.633784)
					(mid 221.727014 -481.897956)
					(end 221.460314 -481.633784)
				)
				(arc
					(start 221.460314 -481.631244)
					(mid 221.727014 -481.364544)
					(end 221.993714 -481.631244)
				)
			)
		)
	)
	(zone
		(layers "B.Cu" "In5.Cu")
		(hatch none 0.5)
		(connect_pads
			(clearance 0)
		)
		(min_thickness 0.25)
		(keepout
			(tracks not_allowed)
			(vias allowed)
			(pads allowed)
			(copperpour not_allowed)
			(footprints allowed)
		)
		(placement
			(enabled no)
			(sheetname "")
		)
		(fill yes
			(thermal_gap 0.5)
			(thermal_bridge_width 0.5)
			(island_removal_mode 0)
		)
		(polygon
			(pts
				(arc
					(start 222.339154 -182.231284)
					(mid 221.727014 -181.619144)
					(end 221.114874 -182.231284)
				)
				(arc
					(start 221.114874 -183.348884)
					(mid 221.725744 -183.961023)
					(end 222.339154 -183.351424)
				)
				(arc
					(start 221.993714 -183.351424)
					(mid 221.727014 -183.615596)
					(end 221.460314 -183.351424)
				)
				(arc
					(start 221.460314 -183.348884)
					(mid 221.727014 -183.082184)
					(end 221.993714 -183.348884)
				)
				(xy 222.339154 -183.348884) (xy 222.339154 -182.233824)
				(arc
					(start 221.993714 -182.233824)
					(mid 221.727014 -182.497996)
					(end 221.460314 -182.233824)
				)
				(arc
					(start 221.460314 -182.231284)
					(mid 221.727014 -181.964584)
					(end 221.993714 -182.231284)
				)
			)
		)
	)
	(zone
		(layers "B.Cu" "In5.Cu")
		(hatch none 0.5)
		(connect_pads
			(clearance 0)
		)
		(min_thickness 0.25)
		(keepout
			(tracks not_allowed)
			(vias allowed)
			(pads allowed)
			(copperpour not_allowed)
			(footprints allowed)
		)
		(placement
			(enabled no)
			(sheetname "")
		)
		(fill yes
			(thermal_gap 0.5)
			(thermal_bridge_width 0.5)
			(island_removal_mode 0)
		)
		(polygon
			(pts
				(arc
					(start 25.88514 -327.451212)
					(mid 25.273 -326.839072)
					(end 24.66086 -327.451212)
				)
				(arc
					(start 24.66086 -328.568558)
					(mid 25.271603 -329.18095)
					(end 25.88514 -328.571352)
				)
				(arc
					(start 25.5397 -328.571352)
					(mid 25.273 -328.835524)
					(end 25.0063 -328.571352)
				)
				(arc
					(start 25.0063 -328.568812)
					(mid 25.273 -328.302112)
					(end 25.5397 -328.568812)
				)
				(xy 25.88514 -328.568812) (xy 25.88514 -327.453752)
				(arc
					(start 25.5397 -327.453752)
					(mid 25.273 -327.717924)
					(end 25.0063 -327.453752)
				)
				(arc
					(start 25.0063 -327.451212)
					(mid 25.273 -327.184512)
					(end 25.5397 -327.451212)
				)
			)
		)
	)
	(zone
		(layers "B.Cu" "In5.Cu")
		(hatch none 0.5)
		(connect_pads
			(clearance 0)
		)
		(min_thickness 0.25)
		(keepout
			(tracks not_allowed)
			(vias allowed)
			(pads allowed)
			(copperpour not_allowed)
			(footprints allowed)
		)
		(placement
			(enabled no)
			(sheetname "")
		)
		(fill yes
			(thermal_gap 0.5)
			(thermal_bridge_width 0.5)
			(island_removal_mode 0)
		)
		(polygon
			(pts
				(arc
					(start 25.88514 -430.45126)
					(mid 25.273 -429.83912)
					(end 24.66086 -430.45126)
				)
				(arc
					(start 24.66086 -431.56886)
					(mid 25.27173 -432.180999)
					(end 25.88514 -431.5714)
				)
				(arc
					(start 25.5397 -431.5714)
					(mid 25.273 -431.835572)
					(end 25.0063 -431.5714)
				)
				(arc
					(start 25.0063 -431.56886)
					(mid 25.273 -431.30216)
					(end 25.5397 -431.56886)
				)
				(xy 25.88514 -431.56886) (xy 25.88514 -430.4538)
				(arc
					(start 25.5397 -430.4538)
					(mid 25.273 -430.717972)
					(end 25.0063 -430.4538)
				)
				(arc
					(start 25.0063 -430.45126)
					(mid 25.273 -430.18456)
					(end 25.5397 -430.45126)
				)
			)
		)
	)
	(zone
		(layers "B.Cu" "In5.Cu")
		(hatch none 0.5)
		(connect_pads
			(clearance 0)
		)
		(min_thickness 0.25)
		(keepout
			(tracks not_allowed)
			(vias allowed)
			(pads allowed)
			(copperpour not_allowed)
			(footprints allowed)
		)
		(placement
			(enabled no)
			(sheetname "")
		)
		(fill yes
			(thermal_gap 0.5)
			(thermal_bridge_width 0.5)
			(island_removal_mode 0)
		)
		(polygon
			(pts
				(arc
					(start 25.88514 -36.050982)
					(mid 25.273 -35.438842)
					(end 24.66086 -36.050982)
				)
				(arc
					(start 24.66086 -37.168328)
					(mid 25.271603 -37.78072)
					(end 25.88514 -37.171122)
				)
				(arc
					(start 25.5397 -37.171122)
					(mid 25.273 -37.435294)
					(end 25.0063 -37.171122)
				)
				(arc
					(start 25.0063 -37.168582)
					(mid 25.273 -36.901882)
					(end 25.5397 -37.168582)
				)
				(xy 25.88514 -37.168582) (xy 25.88514 -36.053522)
				(arc
					(start 25.5397 -36.053522)
					(mid 25.273 -36.317694)
					(end 25.0063 -36.053522)
				)
				(arc
					(start 25.0063 -36.050982)
					(mid 25.273 -35.784282)
					(end 25.5397 -36.050982)
				)
			)
		)
	)
	(zone
		(layers "B.Cu" "In5.Cu")
		(hatch none 0.5)
		(connect_pads
			(clearance 0)
		)
		(min_thickness 0.25)
		(keepout
			(tracks not_allowed)
			(vias allowed)
			(pads allowed)
			(copperpour not_allowed)
			(footprints allowed)
		)
		(placement
			(enabled no)
			(sheetname "")
		)
		(fill yes
			(thermal_gap 0.5)
			(thermal_bridge_width 0.5)
			(island_removal_mode 0)
		)
		(polygon
			(pts
				(arc
					(start 37.33927 -378.631196)
					(mid 36.72713 -378.019056)
					(end 36.11499 -378.631196)
				)
				(arc
					(start 36.11499 -379.748796)
					(mid 36.72586 -380.360935)
					(end 37.33927 -379.751336)
				)
				(arc
					(start 36.99383 -379.751336)
					(mid 36.72713 -380.015508)
					(end 36.46043 -379.751336)
				)
				(arc
					(start 36.46043 -379.748796)
					(mid 36.72713 -379.482096)
					(end 36.99383 -379.748796)
				)
				(xy 37.33927 -379.748796) (xy 37.33927 -378.633736)
				(arc
					(start 36.99383 -378.633736)
					(mid 36.72713 -378.897908)
					(end 36.46043 -378.633736)
				)
				(arc
					(start 36.46043 -378.631196)
					(mid 36.72713 -378.364496)
					(end 36.99383 -378.631196)
				)
			)
		)
	)
	(zone
		(layers "B.Cu" "In5.Cu")
		(hatch none 0.5)
		(connect_pads
			(clearance 0)
		)
		(min_thickness 0.25)
		(keepout
			(tracks not_allowed)
			(vias allowed)
			(pads allowed)
			(copperpour not_allowed)
			(footprints allowed)
		)
		(placement
			(enabled no)
			(sheetname "")
		)
		(fill yes
			(thermal_gap 0.5)
			(thermal_bridge_width 0.5)
			(island_removal_mode 0)
		)
		(polygon
			(pts
				(arc
					(start 37.33927 -79.231236)
					(mid 36.72713 -78.619096)
					(end 36.11499 -79.231236)
				)
				(arc
					(start 36.11499 -80.348836)
					(mid 36.72586 -80.960975)
					(end 37.33927 -80.351376)
				)
				(arc
					(start 36.99383 -80.351376)
					(mid 36.72713 -80.615548)
					(end 36.46043 -80.351376)
				)
				(arc
					(start 36.46043 -80.348836)
					(mid 36.72713 -80.082136)
					(end 36.99383 -80.348836)
				)
				(xy 37.33927 -80.348836) (xy 37.33927 -79.233776)
				(arc
					(start 36.99383 -79.233776)
					(mid 36.72713 -79.497948)
					(end 36.46043 -79.233776)
				)
				(arc
					(start 36.46043 -79.231236)
					(mid 36.72713 -78.964536)
					(end 36.99383 -79.231236)
				)
			)
		)
	)
	(zone
		(layers "B.Cu" "In5.Cu")
		(hatch none 0.5)
		(connect_pads
			(clearance 0)
		)
		(min_thickness 0.25)
		(keepout
			(tracks not_allowed)
			(vias allowed)
			(pads allowed)
			(copperpour not_allowed)
			(footprints allowed)
		)
		(placement
			(enabled no)
			(sheetname "")
		)
		(fill yes
			(thermal_gap 0.5)
			(thermal_bridge_width 0.5)
			(island_removal_mode 0)
		)
		(polygon
			(pts
				(arc
					(start 25.88514 -126.251208)
					(mid 25.273 -125.639068)
					(end 24.66086 -126.251208)
				)
				(arc
					(start 24.66086 -127.368554)
					(mid 25.271603 -127.980946)
					(end 25.88514 -127.371348)
				)
				(arc
					(start 25.5397 -127.371348)
					(mid 25.273 -127.63552)
					(end 25.0063 -127.371348)
				)
				(arc
					(start 25.0063 -127.368808)
					(mid 25.273 -127.102108)
					(end 25.5397 -127.368808)
				)
				(xy 25.88514 -127.368808) (xy 25.88514 -126.253748)
				(arc
					(start 25.5397 -126.253748)
					(mid 25.273 -126.51792)
					(end 25.0063 -126.253748)
				)
				(arc
					(start 25.0063 -126.251208)
					(mid 25.273 -125.984508)
					(end 25.5397 -126.251208)
				)
			)
		)
	)
	(zone
		(layers "B.Cu" "In5.Cu")
		(hatch none 0.5)
		(connect_pads
			(clearance 0)
		)
		(min_thickness 0.25)
		(keepout
			(tracks not_allowed)
			(vias allowed)
			(pads allowed)
			(copperpour not_allowed)
			(footprints allowed)
		)
		(placement
			(enabled no)
			(sheetname "")
		)
		(fill yes
			(thermal_gap 0.5)
			(thermal_bridge_width 0.5)
			(island_removal_mode 0)
		)
		(polygon
			(pts
				(arc
					(start 25.88514 -345.051126)
					(mid 25.273 -344.438986)
					(end 24.66086 -345.051126)
				)
				(arc
					(start 24.66086 -346.168726)
					(mid 25.27173 -346.780865)
					(end 25.88514 -346.171266)
				)
				(arc
					(start 25.5397 -346.171266)
					(mid 25.273 -346.435438)
					(end 25.0063 -346.171266)
				)
				(arc
					(start 25.0063 -346.168726)
					(mid 25.273 -345.902026)
					(end 25.5397 -346.168726)
				)
				(xy 25.88514 -346.168726) (xy 25.88514 -345.053666)
				(arc
					(start 25.5397 -345.053666)
					(mid 25.273 -345.317838)
					(end 25.0063 -345.053666)
				)
				(arc
					(start 25.0063 -345.051126)
					(mid 25.273 -344.784426)
					(end 25.5397 -345.051126)
				)
			)
		)
	)
	(zone
		(layers "B.Cu" "In5.Cu")
		(hatch none 0.5)
		(connect_pads
			(clearance 0)
		)
		(min_thickness 0.25)
		(keepout
			(tracks not_allowed)
			(vias allowed)
			(pads allowed)
			(copperpour not_allowed)
			(footprints allowed)
		)
		(placement
			(enabled no)
			(sheetname "")
		)
		(fill yes
			(thermal_gap 0.5)
			(thermal_bridge_width 0.5)
			(island_removal_mode 0)
		)
		(polygon
			(pts
				(arc
					(start 25.88514 -121.451116)
					(mid 25.273 -120.838976)
					(end 24.66086 -121.451116)
				)
				(arc
					(start 24.66086 -122.568462)
					(mid 25.271603 -123.180854)
					(end 25.88514 -122.571256)
				)
				(arc
					(start 25.5397 -122.571256)
					(mid 25.273 -122.835428)
					(end 25.0063 -122.571256)
				)
				(arc
					(start 25.0063 -122.568716)
					(mid 25.273 -122.302016)
					(end 25.5397 -122.568716)
				)
				(xy 25.88514 -122.568716) (xy 25.88514 -121.453656)
				(arc
					(start 25.5397 -121.453656)
					(mid 25.273 -121.717828)
					(end 25.0063 -121.453656)
				)
				(arc
					(start 25.0063 -121.451116)
					(mid 25.273 -121.184416)
					(end 25.5397 -121.451116)
				)
			)
		)
	)
	(zone
		(layers "B.Cu" "In5.Cu")
		(hatch none 0.5)
		(connect_pads
			(clearance 0)
		)
		(min_thickness 0.25)
		(keepout
			(tracks not_allowed)
			(vias allowed)
			(pads allowed)
			(copperpour not_allowed)
			(footprints allowed)
		)
		(placement
			(enabled no)
			(sheetname "")
		)
		(fill yes
			(thermal_gap 0.5)
			(thermal_bridge_width 0.5)
			(island_removal_mode 0)
		)
		(polygon
			(pts
				(arc
					(start 25.88514 -116.651024)
					(mid 25.273 -116.038884)
					(end 24.66086 -116.651024)
				)
				(arc
					(start 24.66086 -117.768624)
					(mid 25.27173 -118.380763)
					(end 25.88514 -117.771164)
				)
				(arc
					(start 25.5397 -117.771164)
					(mid 25.273 -118.035336)
					(end 25.0063 -117.771164)
				)
				(arc
					(start 25.0063 -117.768624)
					(mid 25.273 -117.501924)
					(end 25.5397 -117.768624)
				)
				(xy 25.88514 -117.768624) (xy 25.88514 -116.653564)
				(arc
					(start 25.5397 -116.653564)
					(mid 25.273 -116.917736)
					(end 25.0063 -116.653564)
				)
				(arc
					(start 25.0063 -116.651024)
					(mid 25.273 -116.384324)
					(end 25.5397 -116.651024)
				)
			)
		)
	)
	(zone
		(layers "B.Cu" "In5.Cu")
		(hatch none 0.5)
		(connect_pads
			(clearance 0)
		)
		(min_thickness 0.25)
		(keepout
			(tracks not_allowed)
			(vias allowed)
			(pads allowed)
			(copperpour not_allowed)
			(footprints allowed)
		)
		(placement
			(enabled no)
			(sheetname "")
		)
		(fill yes
			(thermal_gap 0.5)
			(thermal_bridge_width 0.5)
			(island_removal_mode 0)
		)
		(polygon
			(pts
				(arc
					(start 37.33927 -486.431336)
					(mid 36.72713 -485.819196)
					(end 36.11499 -486.431336)
				)
				(arc
					(start 36.11499 -487.548936)
					(mid 36.72586 -488.161075)
					(end 37.33927 -487.551476)
				)
				(arc
					(start 36.99383 -487.551476)
					(mid 36.72713 -487.815648)
					(end 36.46043 -487.551476)
				)
				(arc
					(start 36.46043 -487.548936)
					(mid 36.72713 -487.282236)
					(end 36.99383 -487.548936)
				)
				(xy 37.33927 -487.548936) (xy 37.33927 -486.433876)
				(arc
					(start 36.99383 -486.433876)
					(mid 36.72713 -486.698048)
					(end 36.46043 -486.433876)
				)
				(arc
					(start 36.46043 -486.431336)
					(mid 36.72713 -486.164636)
					(end 36.99383 -486.431336)
				)
			)
		)
	)
	(zone
		(layers "B.Cu" "In5.Cu")
		(hatch none 0.5)
		(connect_pads
			(clearance 0)
		)
		(min_thickness 0.25)
		(keepout
			(tracks not_allowed)
			(vias allowed)
			(pads allowed)
			(copperpour not_allowed)
			(footprints allowed)
		)
		(placement
			(enabled no)
			(sheetname "")
		)
		(fill yes
			(thermal_gap 0.5)
			(thermal_bridge_width 0.5)
			(island_removal_mode 0)
		)
		(polygon
			(pts
				(arc
					(start 25.88514 -229.251256)
					(mid 25.273 -228.639116)
					(end 24.66086 -229.251256)
				)
				(arc
					(start 24.66086 -230.368602)
					(mid 25.271603 -230.980994)
					(end 25.88514 -230.371396)
				)
				(arc
					(start 25.5397 -230.371396)
					(mid 25.273 -230.635568)
					(end 25.0063 -230.371396)
				)
				(arc
					(start 25.0063 -230.368856)
					(mid 25.273 -230.102156)
					(end 25.5397 -230.368856)
				)
				(xy 25.88514 -230.368856) (xy 25.88514 -229.253796)
				(arc
					(start 25.5397 -229.253796)
					(mid 25.273 -229.517968)
					(end 25.0063 -229.253796)
				)
				(arc
					(start 25.0063 -229.251256)
					(mid 25.273 -228.984556)
					(end 25.5397 -229.251256)
				)
			)
		)
	)
	(zone
		(layers "B.Cu" "In5.Cu")
		(hatch none 0.5)
		(connect_pads
			(clearance 0)
		)
		(min_thickness 0.25)
		(keepout
			(tracks not_allowed)
			(vias allowed)
			(pads allowed)
			(copperpour not_allowed)
			(footprints allowed)
		)
		(placement
			(enabled no)
			(sheetname "")
		)
		(fill yes
			(thermal_gap 0.5)
			(thermal_bridge_width 0.5)
			(island_removal_mode 0)
		)
		(polygon
			(pts
				(arc
					(start 222.339154 -285.231332)
					(mid 221.727014 -284.619192)
					(end 221.114874 -285.231332)
				)
				(arc
					(start 221.114874 -286.348932)
					(mid 221.725744 -286.961071)
					(end 222.339154 -286.351472)
				)
				(arc
					(start 221.993714 -286.351472)
					(mid 221.727014 -286.615644)
					(end 221.460314 -286.351472)
				)
				(arc
					(start 221.460314 -286.348932)
					(mid 221.727014 -286.082232)
					(end 221.993714 -286.348932)
				)
				(xy 222.339154 -286.348932) (xy 222.339154 -285.233872)
				(arc
					(start 221.993714 -285.233872)
					(mid 221.727014 -285.498044)
					(end 221.460314 -285.233872)
				)
				(arc
					(start 221.460314 -285.231332)
					(mid 221.727014 -284.964632)
					(end 221.993714 -285.231332)
				)
			)
		)
	)
	(zone
		(layers "B.Cu" "In5.Cu")
		(hatch none 0.5)
		(connect_pads
			(clearance 0)
		)
		(min_thickness 0.25)
		(keepout
			(tracks not_allowed)
			(vias allowed)
			(pads allowed)
			(copperpour not_allowed)
			(footprints allowed)
		)
		(placement
			(enabled no)
			(sheetname "")
		)
		(fill yes
			(thermal_gap 0.5)
			(thermal_bridge_width 0.5)
			(island_removal_mode 0)
		)
		(polygon
			(pts
				(arc
					(start 222.339154 -262.831326)
					(mid 221.727014 -262.219186)
					(end 221.114874 -262.831326)
				)
				(arc
					(start 221.114874 -263.948926)
					(mid 221.725744 -264.561065)
					(end 222.339154 -263.951466)
				)
				(arc
					(start 221.993714 -263.951466)
					(mid 221.727014 -264.215638)
					(end 221.460314 -263.951466)
				)
				(arc
					(start 221.460314 -263.948926)
					(mid 221.727014 -263.682226)
					(end 221.993714 -263.948926)
				)
				(xy 222.339154 -263.948926) (xy 222.339154 -262.833866)
				(arc
					(start 221.993714 -262.833866)
					(mid 221.727014 -263.098038)
					(end 221.460314 -262.833866)
				)
				(arc
					(start 221.460314 -262.831326)
					(mid 221.727014 -262.564626)
					(end 221.993714 -262.831326)
				)
			)
		)
	)
	(zone
		(layers "B.Cu" "In5.Cu")
		(hatch none 0.5)
		(connect_pads
			(clearance 0)
		)
		(min_thickness 0.25)
		(keepout
			(tracks not_allowed)
			(vias allowed)
			(pads allowed)
			(copperpour not_allowed)
			(footprints allowed)
		)
		(placement
			(enabled no)
			(sheetname "")
		)
		(fill yes
			(thermal_gap 0.5)
			(thermal_bridge_width 0.5)
			(island_removal_mode 0)
		)
		(polygon
			(pts
				(arc
					(start 25.88514 -13.676376)
					(mid 25.273 -13.064236)
					(end 24.66086 -13.676376)
				)
				(arc
					(start 24.66086 -14.793976)
					(mid 25.27173 -15.406115)
					(end 25.88514 -14.796516)
				)
				(arc
					(start 25.5397 -14.796516)
					(mid 25.273 -15.060688)
					(end 25.0063 -14.796516)
				)
				(arc
					(start 25.0063 -14.793976)
					(mid 25.273 -14.527276)
					(end 25.5397 -14.793976)
				)
				(xy 25.88514 -14.793976) (xy 25.88514 -13.678916)
				(arc
					(start 25.5397 -13.678916)
					(mid 25.273 -13.943088)
					(end 25.0063 -13.678916)
				)
				(arc
					(start 25.0063 -13.676376)
					(mid 25.273 -13.409676)
					(end 25.5397 -13.676376)
				)
			)
		)
	)
	(zone
		(layers "B.Cu" "In5.Cu")
		(hatch none 0.5)
		(connect_pads
			(clearance 0)
		)
		(min_thickness 0.25)
		(keepout
			(tracks not_allowed)
			(vias allowed)
			(pads allowed)
			(copperpour not_allowed)
			(footprints allowed)
		)
		(placement
			(enabled no)
			(sheetname "")
		)
		(fill yes
			(thermal_gap 0.5)
			(thermal_bridge_width 0.5)
			(island_removal_mode 0)
		)
		(polygon
			(pts
				(arc
					(start 25.88514 -224.451164)
					(mid 25.273 -223.839024)
					(end 24.66086 -224.451164)
				)
				(arc
					(start 24.66086 -225.56851)
					(mid 25.271603 -226.180902)
					(end 25.88514 -225.571304)
				)
				(arc
					(start 25.5397 -225.571304)
					(mid 25.273 -225.835476)
					(end 25.0063 -225.571304)
				)
				(arc
					(start 25.0063 -225.568764)
					(mid 25.273 -225.302064)
					(end 25.5397 -225.568764)
				)
				(xy 25.88514 -225.568764) (xy 25.88514 -224.453704)
				(arc
					(start 25.5397 -224.453704)
					(mid 25.273 -224.717876)
					(end 25.0063 -224.453704)
				)
				(arc
					(start 25.0063 -224.451164)
					(mid 25.273 -224.184464)
					(end 25.5397 -224.451164)
				)
			)
		)
	)
	(zone
		(layers "B.Cu" "In5.Cu")
		(hatch none 0.5)
		(connect_pads
			(clearance 0)
		)
		(min_thickness 0.25)
		(keepout
			(tracks not_allowed)
			(vias allowed)
			(pads allowed)
			(copperpour not_allowed)
			(footprints allowed)
		)
		(placement
			(enabled no)
			(sheetname "")
		)
		(fill yes
			(thermal_gap 0.5)
			(thermal_bridge_width 0.5)
			(island_removal_mode 0)
		)
		(polygon
			(pts
				(arc
					(start 37.33927 -172.6311)
					(mid 36.72713 -172.01896)
					(end 36.11499 -172.6311)
				)
				(arc
					(start 36.11499 -173.7487)
					(mid 36.72586 -174.360839)
					(end 37.33927 -173.75124)
				)
				(arc
					(start 36.99383 -173.75124)
					(mid 36.72713 -174.015412)
					(end 36.46043 -173.75124)
				)
				(arc
					(start 36.46043 -173.7487)
					(mid 36.72713 -173.482)
					(end 36.99383 -173.7487)
				)
				(xy 37.33927 -173.7487) (xy 37.33927 -172.63364)
				(arc
					(start 36.99383 -172.63364)
					(mid 36.72713 -172.897812)
					(end 36.46043 -172.63364)
				)
				(arc
					(start 36.46043 -172.6311)
					(mid 36.72713 -172.3644)
					(end 36.99383 -172.6311)
				)
			)
		)
	)
	(zone
		(layers "B.Cu" "In5.Cu")
		(hatch none 0.5)
		(connect_pads
			(clearance 0)
		)
		(min_thickness 0.25)
		(keepout
			(tracks not_allowed)
			(vias allowed)
			(pads allowed)
			(copperpour not_allowed)
			(footprints allowed)
		)
		(placement
			(enabled no)
			(sheetname "")
		)
		(fill yes
			(thermal_gap 0.5)
			(thermal_bridge_width 0.5)
			(island_removal_mode 0)
		)
		(polygon
			(pts
				(arc
					(start 222.339154 -365.831374)
					(mid 221.727014 -365.219234)
					(end 221.114874 -365.831374)
				)
				(arc
					(start 221.114874 -366.948974)
					(mid 221.725744 -367.561113)
					(end 222.339154 -366.951514)
				)
				(arc
					(start 221.993714 -366.951514)
					(mid 221.727014 -367.215686)
					(end 221.460314 -366.951514)
				)
				(arc
					(start 221.460314 -366.948974)
					(mid 221.727014 -366.682274)
					(end 221.993714 -366.948974)
				)
				(xy 222.339154 -366.948974) (xy 222.339154 -365.833914)
				(arc
					(start 221.993714 -365.833914)
					(mid 221.727014 -366.098086)
					(end 221.460314 -365.833914)
				)
				(arc
					(start 221.460314 -365.831374)
					(mid 221.727014 -365.564674)
					(end 221.993714 -365.831374)
				)
			)
		)
	)
	(zone
		(layers "B.Cu" "In5.Cu")
		(hatch none 0.5)
		(connect_pads
			(clearance 0)
		)
		(min_thickness 0.25)
		(keepout
			(tracks not_allowed)
			(vias allowed)
			(pads allowed)
			(copperpour not_allowed)
			(footprints allowed)
		)
		(placement
			(enabled no)
			(sheetname "")
		)
		(fill yes
			(thermal_gap 0.5)
			(thermal_bridge_width 0.5)
			(island_removal_mode 0)
		)
		(polygon
			(pts
				(arc
					(start 222.339154 -388.23138)
					(mid 221.727014 -387.61924)
					(end 221.114874 -388.23138)
				)
				(arc
					(start 221.114874 -389.34898)
					(mid 221.725744 -389.961119)
					(end 222.339154 -389.35152)
				)
				(arc
					(start 221.993714 -389.35152)
					(mid 221.727014 -389.615692)
					(end 221.460314 -389.35152)
				)
				(arc
					(start 221.460314 -389.34898)
					(mid 221.727014 -389.08228)
					(end 221.993714 -389.34898)
				)
				(xy 222.339154 -389.34898) (xy 222.339154 -388.23392)
				(arc
					(start 221.993714 -388.23392)
					(mid 221.727014 -388.498092)
					(end 221.460314 -388.23392)
				)
				(arc
					(start 221.460314 -388.23138)
					(mid 221.727014 -387.96468)
					(end 221.993714 -388.23138)
				)
			)
		)
	)
	(zone
		(layers "B.Cu" "In5.Cu")
		(hatch none 0.5)
		(connect_pads
			(clearance 0)
		)
		(min_thickness 0.25)
		(keepout
			(tracks not_allowed)
			(vias allowed)
			(pads allowed)
			(copperpour not_allowed)
			(footprints allowed)
		)
		(placement
			(enabled no)
			(sheetname "")
		)
		(fill yes
			(thermal_gap 0.5)
			(thermal_bridge_width 0.5)
			(island_removal_mode 0)
		)
		(polygon
			(pts
				(arc
					(start 37.33927 -74.431144)
					(mid 36.72713 -73.819004)
					(end 36.11499 -74.431144)
				)
				(arc
					(start 36.11499 -75.548744)
					(mid 36.72586 -76.160883)
					(end 37.33927 -75.551284)
				)
				(arc
					(start 36.99383 -75.551284)
					(mid 36.72713 -75.815456)
					(end 36.46043 -75.551284)
				)
				(arc
					(start 36.46043 -75.548744)
					(mid 36.72713 -75.282044)
					(end 36.99383 -75.548744)
				)
				(xy 37.33927 -75.548744) (xy 37.33927 -74.433684)
				(arc
					(start 36.99383 -74.433684)
					(mid 36.72713 -74.697856)
					(end 36.46043 -74.433684)
				)
				(arc
					(start 36.46043 -74.431144)
					(mid 36.72713 -74.164444)
					(end 36.99383 -74.431144)
				)
			)
		)
	)
	(zone
		(layers "B.Cu" "In5.Cu")
		(hatch none 0.5)
		(connect_pads
			(clearance 0)
		)
		(min_thickness 0.25)
		(keepout
			(tracks not_allowed)
			(vias allowed)
			(pads allowed)
			(copperpour not_allowed)
			(footprints allowed)
		)
		(placement
			(enabled no)
			(sheetname "")
		)
		(fill yes
			(thermal_gap 0.5)
			(thermal_bridge_width 0.5)
			(island_removal_mode 0)
		)
		(polygon
			(pts
				(arc
					(start 37.33927 -491.231428)
					(mid 36.72713 -490.619288)
					(end 36.11499 -491.231428)
				)
				(arc
					(start 36.11499 -492.348774)
					(mid 36.725733 -492.961166)
					(end 37.33927 -492.351568)
				)
				(arc
					(start 36.99383 -492.351568)
					(mid 36.72713 -492.61574)
					(end 36.46043 -492.351568)
				)
				(arc
					(start 36.46043 -492.349028)
					(mid 36.72713 -492.082328)
					(end 36.99383 -492.349028)
				)
				(xy 37.33927 -492.349028) (xy 37.33927 -491.233968)
				(arc
					(start 36.99383 -491.233968)
					(mid 36.72713 -491.49814)
					(end 36.46043 -491.233968)
				)
				(arc
					(start 36.46043 -491.231428)
					(mid 36.72713 -490.964728)
					(end 36.99383 -491.231428)
				)
			)
		)
	)
	(zone
		(layers "B.Cu" "In5.Cu")
		(hatch none 0.5)
		(connect_pads
			(clearance 0)
		)
		(min_thickness 0.25)
		(keepout
			(tracks not_allowed)
			(vias allowed)
			(pads allowed)
			(copperpour not_allowed)
			(footprints allowed)
		)
		(placement
			(enabled no)
			(sheetname "")
		)
		(fill yes
			(thermal_gap 0.5)
			(thermal_bridge_width 0.5)
			(island_removal_mode 0)
		)
		(polygon
			(pts
				(arc
					(start 222.339154 -56.83123)
					(mid 221.727014 -56.21909)
					(end 221.114874 -56.83123)
				)
				(arc
					(start 221.114874 -57.94883)
					(mid 221.725744 -58.560969)
					(end 222.339154 -57.95137)
				)
				(arc
					(start 221.993714 -57.95137)
					(mid 221.727014 -58.215542)
					(end 221.460314 -57.95137)
				)
				(arc
					(start 221.460314 -57.94883)
					(mid 221.727014 -57.68213)
					(end 221.993714 -57.94883)
				)
				(xy 222.339154 -57.94883) (xy 222.339154 -56.83377)
				(arc
					(start 221.993714 -56.83377)
					(mid 221.727014 -57.097942)
					(end 221.460314 -56.83377)
				)
				(arc
					(start 221.460314 -56.83123)
					(mid 221.727014 -56.56453)
					(end 221.993714 -56.83123)
				)
			)
		)
	)
	(zone
		(layers "B.Cu" "In5.Cu")
		(hatch none 0.5)
		(connect_pads
			(clearance 0)
		)
		(min_thickness 0.25)
		(keepout
			(tracks not_allowed)
			(vias allowed)
			(pads allowed)
			(copperpour not_allowed)
			(footprints allowed)
		)
		(placement
			(enabled no)
			(sheetname "")
		)
		(fill yes
			(thermal_gap 0.5)
			(thermal_bridge_width 0.5)
			(island_removal_mode 0)
		)
		(polygon
			(pts
				(arc
					(start 222.339154 -280.43124)
					(mid 221.727014 -279.8191)
					(end 221.114874 -280.43124)
				)
				(arc
					(start 221.114874 -281.54884)
					(mid 221.725744 -282.160979)
					(end 222.339154 -281.55138)
				)
				(arc
					(start 221.993714 -281.55138)
					(mid 221.727014 -281.815552)
					(end 221.460314 -281.55138)
				)
				(arc
					(start 221.460314 -281.54884)
					(mid 221.727014 -281.28214)
					(end 221.993714 -281.54884)
				)
				(xy 222.339154 -281.54884) (xy 222.339154 -280.43378)
				(arc
					(start 221.993714 -280.43378)
					(mid 221.727014 -280.697952)
					(end 221.460314 -280.43378)
				)
				(arc
					(start 221.460314 -280.43124)
					(mid 221.727014 -280.16454)
					(end 221.993714 -280.43124)
				)
			)
		)
	)
	(zone
		(layers "B.Cu" "In5.Cu")
		(hatch none 0.5)
		(connect_pads
			(clearance 0)
		)
		(min_thickness 0.25)
		(keepout
			(tracks not_allowed)
			(vias allowed)
			(pads allowed)
			(copperpour not_allowed)
			(footprints allowed)
		)
		(placement
			(enabled no)
			(sheetname "")
		)
		(fill yes
			(thermal_gap 0.5)
			(thermal_bridge_width 0.5)
			(island_removal_mode 0)
		)
		(polygon
			(pts
				(arc
					(start 37.33927 -177.431192)
					(mid 36.72713 -176.819052)
					(end 36.11499 -177.431192)
				)
				(arc
					(start 36.11499 -178.548792)
					(mid 36.72586 -179.160931)
					(end 37.33927 -178.551332)
				)
				(arc
					(start 36.99383 -178.551332)
					(mid 36.72713 -178.815504)
					(end 36.46043 -178.551332)
				)
				(arc
					(start 36.46043 -178.548792)
					(mid 36.72713 -178.282092)
					(end 36.99383 -178.548792)
				)
				(xy 37.33927 -178.548792) (xy 37.33927 -177.433732)
				(arc
					(start 36.99383 -177.433732)
					(mid 36.72713 -177.697904)
					(end 36.46043 -177.433732)
				)
				(arc
					(start 36.46043 -177.431192)
					(mid 36.72713 -177.164492)
					(end 36.99383 -177.431192)
				)
			)
		)
	)
	(zone
		(layers "B.Cu" "In5.Cu")
		(hatch none 0.5)
		(connect_pads
			(clearance 0)
		)
		(min_thickness 0.25)
		(keepout
			(tracks not_allowed)
			(vias allowed)
			(pads allowed)
			(copperpour not_allowed)
			(footprints allowed)
		)
		(placement
			(enabled no)
			(sheetname "")
		)
		(fill yes
			(thermal_gap 0.5)
			(thermal_bridge_width 0.5)
			(island_removal_mode 0)
		)
		(polygon
			(pts
				(arc
					(start 222.339154 -172.6311)
					(mid 221.727014 -172.01896)
					(end 221.114874 -172.6311)
				)
				(arc
					(start 221.114874 -173.7487)
					(mid 221.725744 -174.360839)
					(end 222.339154 -173.75124)
				)
				(arc
					(start 221.993714 -173.75124)
					(mid 221.727014 -174.015412)
					(end 221.460314 -173.75124)
				)
				(arc
					(start 221.460314 -173.7487)
					(mid 221.727014 -173.482)
					(end 221.993714 -173.7487)
				)
				(xy 222.339154 -173.7487) (xy 222.339154 -172.63364)
				(arc
					(start 221.993714 -172.63364)
					(mid 221.727014 -172.897812)
					(end 221.460314 -172.63364)
				)
				(arc
					(start 221.460314 -172.6311)
					(mid 221.727014 -172.3644)
					(end 221.993714 -172.6311)
				)
			)
		)
	)
	(zone
		(layers "B.Cu" "In5.Cu")
		(hatch none 0.5)
		(connect_pads
			(clearance 0)
		)
		(min_thickness 0.25)
		(keepout
			(tracks not_allowed)
			(vias allowed)
			(pads allowed)
			(copperpour not_allowed)
			(footprints allowed)
		)
		(placement
			(enabled no)
			(sheetname "")
		)
		(fill yes
			(thermal_gap 0.5)
			(thermal_bridge_width 0.5)
			(island_removal_mode 0)
		)
		(polygon
			(pts
				(arc
					(start 25.88514 -322.65112)
					(mid 25.273 -322.03898)
					(end 24.66086 -322.65112)
				)
				(arc
					(start 24.66086 -323.768466)
					(mid 25.271603 -324.380858)
					(end 25.88514 -323.77126)
				)
				(arc
					(start 25.5397 -323.77126)
					(mid 25.273 -324.035432)
					(end 25.0063 -323.77126)
				)
				(arc
					(start 25.0063 -323.76872)
					(mid 25.273 -323.50202)
					(end 25.5397 -323.76872)
				)
				(xy 25.88514 -323.76872) (xy 25.88514 -322.65366)
				(arc
					(start 25.5397 -322.65366)
					(mid 25.273 -322.917832)
					(end 25.0063 -322.65366)
				)
				(arc
					(start 25.0063 -322.65112)
					(mid 25.273 -322.38442)
					(end 25.5397 -322.65112)
				)
			)
		)
	)
	(zone
		(layers "B.Cu" "In5.Cu")
		(hatch none 0.5)
		(connect_pads
			(clearance 0)
		)
		(min_thickness 0.25)
		(keepout
			(tracks not_allowed)
			(vias allowed)
			(pads allowed)
			(copperpour not_allowed)
			(footprints allowed)
		)
		(placement
			(enabled no)
			(sheetname "")
		)
		(fill yes
			(thermal_gap 0.5)
			(thermal_bridge_width 0.5)
			(island_removal_mode 0)
		)
		(polygon
			(pts
				(arc
					(start 25.88514 -18.451068)
					(mid 25.273 -17.838928)
					(end 24.66086 -18.451068)
				)
				(arc
					(start 24.66086 -19.568414)
					(mid 25.271603 -20.180806)
					(end 25.88514 -19.571208)
				)
				(arc
					(start 25.5397 -19.571208)
					(mid 25.273 -19.83538)
					(end 25.0063 -19.571208)
				)
				(arc
					(start 25.0063 -19.568668)
					(mid 25.273 -19.301968)
					(end 25.5397 -19.568668)
				)
				(xy 25.88514 -19.568668) (xy 25.88514 -18.453608)
				(arc
					(start 25.5397 -18.453608)
					(mid 25.273 -18.71778)
					(end 25.0063 -18.453608)
				)
				(arc
					(start 25.0063 -18.451068)
					(mid 25.273 -18.184368)
					(end 25.5397 -18.451068)
				)
			)
		)
	)
	(zone
		(layers "B.Cu" "In5.Cu")
		(hatch none 0.5)
		(connect_pads
			(clearance 0)
		)
		(min_thickness 0.25)
		(keepout
			(tracks not_allowed)
			(vias allowed)
			(pads allowed)
			(copperpour not_allowed)
			(footprints allowed)
		)
		(placement
			(enabled no)
			(sheetname "")
		)
		(fill yes
			(thermal_gap 0.5)
			(thermal_bridge_width 0.5)
			(island_removal_mode 0)
		)
		(polygon
			(pts
				(arc
					(start 37.33927 -182.231284)
					(mid 36.72713 -181.619144)
					(end 36.11499 -182.231284)
				)
				(arc
					(start 36.11499 -183.348884)
					(mid 36.72586 -183.961023)
					(end 37.33927 -183.351424)
				)
				(arc
					(start 36.99383 -183.351424)
					(mid 36.72713 -183.615596)
					(end 36.46043 -183.351424)
				)
				(arc
					(start 36.46043 -183.348884)
					(mid 36.72713 -183.082184)
					(end 36.99383 -183.348884)
				)
				(xy 37.33927 -183.348884) (xy 37.33927 -182.233824)
				(arc
					(start 36.99383 -182.233824)
					(mid 36.72713 -182.497996)
					(end 36.46043 -182.233824)
				)
				(arc
					(start 36.46043 -182.231284)
					(mid 36.72713 -181.964584)
					(end 36.99383 -182.231284)
				)
			)
		)
	)
	(zone
		(layers "B.Cu" "In5.Cu")
		(hatch none 0.5)
		(connect_pads
			(clearance 0)
		)
		(min_thickness 0.25)
		(keepout
			(tracks not_allowed)
			(vias allowed)
			(pads allowed)
			(copperpour not_allowed)
			(footprints allowed)
		)
		(placement
			(enabled no)
			(sheetname "")
		)
		(fill yes
			(thermal_gap 0.5)
			(thermal_bridge_width 0.5)
			(island_removal_mode 0)
		)
		(polygon
			(pts
				(arc
					(start 37.33927 -280.43124)
					(mid 36.72713 -279.8191)
					(end 36.11499 -280.43124)
				)
				(arc
					(start 36.11499 -281.54884)
					(mid 36.72586 -282.160979)
					(end 37.33927 -281.55138)
				)
				(arc
					(start 36.99383 -281.55138)
					(mid 36.72713 -281.815552)
					(end 36.46043 -281.55138)
				)
				(arc
					(start 36.46043 -281.54884)
					(mid 36.72713 -281.28214)
					(end 36.99383 -281.54884)
				)
				(xy 37.33927 -281.54884) (xy 37.33927 -280.43378)
				(arc
					(start 36.99383 -280.43378)
					(mid 36.72713 -280.697952)
					(end 36.46043 -280.43378)
				)
				(arc
					(start 36.46043 -280.43124)
					(mid 36.72713 -280.16454)
					(end 36.99383 -280.43124)
				)
			)
		)
	)
	(zone
		(layers "B.Cu" "In5.Cu")
		(hatch none 0.5)
		(connect_pads
			(clearance 0)
		)
		(min_thickness 0.25)
		(keepout
			(tracks not_allowed)
			(vias allowed)
			(pads allowed)
			(copperpour not_allowed)
			(footprints allowed)
		)
		(placement
			(enabled no)
			(sheetname "")
		)
		(fill yes
			(thermal_gap 0.5)
			(thermal_bridge_width 0.5)
			(island_removal_mode 0)
		)
		(polygon
			(pts
				(arc
					(start 222.339154 -69.631052)
					(mid 221.727014 -69.018912)
					(end 221.114874 -69.631052)
				)
				(arc
					(start 221.114874 -70.748652)
					(mid 221.725744 -71.360791)
					(end 222.339154 -70.751192)
				)
				(arc
					(start 221.993714 -70.751192)
					(mid 221.727014 -71.015364)
					(end 221.460314 -70.751192)
				)
				(arc
					(start 221.460314 -70.748652)
					(mid 221.727014 -70.481952)
					(end 221.993714 -70.748652)
				)
				(xy 222.339154 -70.748652) (xy 222.339154 -69.633592)
				(arc
					(start 221.993714 -69.633592)
					(mid 221.727014 -69.897764)
					(end 221.460314 -69.633592)
				)
				(arc
					(start 221.460314 -69.631052)
					(mid 221.727014 -69.364352)
					(end 221.993714 -69.631052)
				)
			)
		)
	)
	(zone
		(layers "B.Cu" "In5.Cu")
		(hatch none 0.5)
		(connect_pads
			(clearance 0)
		)
		(min_thickness 0.25)
		(keepout
			(tracks not_allowed)
			(vias allowed)
			(pads allowed)
			(copperpour not_allowed)
			(footprints allowed)
		)
		(placement
			(enabled no)
			(sheetname "")
		)
		(fill yes
			(thermal_gap 0.5)
			(thermal_bridge_width 0.5)
			(island_removal_mode 0)
		)
		(polygon
			(pts
				(arc
					(start 222.339154 -486.431336)
					(mid 221.727014 -485.819196)
					(end 221.114874 -486.431336)
				)
				(arc
					(start 221.114874 -487.548936)
					(mid 221.725744 -488.161075)
					(end 222.339154 -487.551476)
				)
				(arc
					(start 221.993714 -487.551476)
					(mid 221.727014 -487.815648)
					(end 221.460314 -487.551476)
				)
				(arc
					(start 221.460314 -487.548936)
					(mid 221.727014 -487.282236)
					(end 221.993714 -487.548936)
				)
				(xy 222.339154 -487.548936) (xy 222.339154 -486.433876)
				(arc
					(start 221.993714 -486.433876)
					(mid 221.727014 -486.698048)
					(end 221.460314 -486.433876)
				)
				(arc
					(start 221.460314 -486.431336)
					(mid 221.727014 -486.164636)
					(end 221.993714 -486.431336)
				)
			)
		)
	)
	(zone
		(layers "B.Cu" "In5.Cu")
		(hatch none 0.5)
		(connect_pads
			(clearance 0)
		)
		(min_thickness 0.25)
		(keepout
			(tracks not_allowed)
			(vias allowed)
			(pads allowed)
			(copperpour not_allowed)
			(footprints allowed)
		)
		(placement
			(enabled no)
			(sheetname "")
		)
		(fill yes
			(thermal_gap 0.5)
			(thermal_bridge_width 0.5)
			(island_removal_mode 0)
		)
		(polygon
			(pts
				(arc
					(start 25.88514 -139.05103)
					(mid 25.273 -138.43889)
					(end 24.66086 -139.05103)
				)
				(arc
					(start 24.66086 -140.16863)
					(mid 25.27173 -140.780769)
					(end 25.88514 -140.17117)
				)
				(arc
					(start 25.5397 -140.17117)
					(mid 25.273 -140.435342)
					(end 25.0063 -140.17117)
				)
				(arc
					(start 25.0063 -140.16863)
					(mid 25.273 -139.90193)
					(end 25.5397 -140.16863)
				)
				(xy 25.88514 -140.16863) (xy 25.88514 -139.05357)
				(arc
					(start 25.5397 -139.05357)
					(mid 25.273 -139.317742)
					(end 25.0063 -139.05357)
				)
				(arc
					(start 25.0063 -139.05103)
					(mid 25.273 -138.78433)
					(end 25.5397 -139.05103)
				)
			)
		)
	)
	(zone
		(layers "B.Cu" "In5.Cu")
		(hatch none 0.5)
		(connect_pads
			(clearance 0)
		)
		(min_thickness 0.25)
		(keepout
			(tracks not_allowed)
			(vias allowed)
			(pads allowed)
			(copperpour not_allowed)
			(footprints allowed)
		)
		(placement
			(enabled no)
			(sheetname "")
		)
		(fill yes
			(thermal_gap 0.5)
			(thermal_bridge_width 0.5)
			(island_removal_mode 0)
		)
		(polygon
			(pts
				(arc
					(start 37.33927 -262.831326)
					(mid 36.72713 -262.219186)
					(end 36.11499 -262.831326)
				)
				(arc
					(start 36.11499 -263.948926)
					(mid 36.72586 -264.561065)
					(end 37.33927 -263.951466)
				)
				(arc
					(start 36.99383 -263.951466)
					(mid 36.72713 -264.215638)
					(end 36.46043 -263.951466)
				)
				(arc
					(start 36.46043 -263.948926)
					(mid 36.72713 -263.682226)
					(end 36.99383 -263.948926)
				)
				(xy 37.33927 -263.948926) (xy 37.33927 -262.833866)
				(arc
					(start 36.99383 -262.833866)
					(mid 36.72713 -263.098038)
					(end 36.46043 -262.833866)
				)
				(arc
					(start 36.46043 -262.831326)
					(mid 36.72713 -262.564626)
					(end 36.99383 -262.831326)
				)
			)
		)
	)
	(zone
		(layers "B.Cu" "In5.Cu")
		(hatch none 0.5)
		(connect_pads
			(clearance 0)
		)
		(min_thickness 0.25)
		(keepout
			(tracks not_allowed)
			(vias allowed)
			(pads allowed)
			(copperpour not_allowed)
			(footprints allowed)
		)
		(placement
			(enabled no)
			(sheetname "")
		)
		(fill yes
			(thermal_gap 0.5)
			(thermal_bridge_width 0.5)
			(island_removal_mode 0)
		)
		(polygon
			(pts
				(arc
					(start 37.33927 -468.831422)
					(mid 36.72713 -468.219282)
					(end 36.11499 -468.831422)
				)
				(arc
					(start 36.11499 -469.948768)
					(mid 36.725733 -470.56116)
					(end 37.33927 -469.951562)
				)
				(arc
					(start 36.99383 -469.951562)
					(mid 36.72713 -470.215734)
					(end 36.46043 -469.951562)
				)
				(arc
					(start 36.46043 -469.949022)
					(mid 36.72713 -469.682322)
					(end 36.99383 -469.949022)
				)
				(xy 37.33927 -469.949022) (xy 37.33927 -468.833962)
				(arc
					(start 36.99383 -468.833962)
					(mid 36.72713 -469.098134)
					(end 36.46043 -468.833962)
				)
				(arc
					(start 36.46043 -468.831422)
					(mid 36.72713 -468.564722)
					(end 36.99383 -468.831422)
				)
			)
		)
	)
	(zone
		(layers "B.Cu" "In5.Cu")
		(hatch none 0.5)
		(connect_pads
			(clearance 0)
		)
		(min_thickness 0.25)
		(keepout
			(tracks not_allowed)
			(vias allowed)
			(pads allowed)
			(copperpour not_allowed)
			(footprints allowed)
		)
		(placement
			(enabled no)
			(sheetname "")
		)
		(fill yes
			(thermal_gap 0.5)
			(thermal_bridge_width 0.5)
			(island_removal_mode 0)
		)
		(polygon
			(pts
				(arc
					(start 37.33927 -275.631148)
					(mid 36.72713 -275.019008)
					(end 36.11499 -275.631148)
				)
				(arc
					(start 36.11499 -276.748748)
					(mid 36.72586 -277.360887)
					(end 37.33927 -276.751288)
				)
				(arc
					(start 36.99383 -276.751288)
					(mid 36.72713 -277.01546)
					(end 36.46043 -276.751288)
				)
				(arc
					(start 36.46043 -276.748748)
					(mid 36.72713 -276.482048)
					(end 36.99383 -276.748748)
				)
				(xy 37.33927 -276.748748) (xy 37.33927 -275.633688)
				(arc
					(start 36.99383 -275.633688)
					(mid 36.72713 -275.89786)
					(end 36.46043 -275.633688)
				)
				(arc
					(start 36.46043 -275.631148)
					(mid 36.72713 -275.364448)
					(end 36.99383 -275.631148)
				)
			)
		)
	)
	(zone
		(layers "B.Cu" "In5.Cu")
		(hatch none 0.5)
		(connect_pads
			(clearance 0)
		)
		(min_thickness 0.25)
		(keepout
			(tracks not_allowed)
			(vias allowed)
			(pads allowed)
			(copperpour not_allowed)
			(footprints allowed)
		)
		(placement
			(enabled no)
			(sheetname "")
		)
		(fill yes
			(thermal_gap 0.5)
			(thermal_bridge_width 0.5)
			(island_removal_mode 0)
		)
		(polygon
			(pts
				(arc
					(start 222.339154 -383.431288)
					(mid 221.727014 -382.819148)
					(end 221.114874 -383.431288)
				)
				(arc
					(start 221.114874 -384.548888)
					(mid 221.725744 -385.161027)
					(end 222.339154 -384.551428)
				)
				(arc
					(start 221.993714 -384.551428)
					(mid 221.727014 -384.8156)
					(end 221.460314 -384.551428)
				)
				(arc
					(start 221.460314 -384.548888)
					(mid 221.727014 -384.282188)
					(end 221.993714 -384.548888)
				)
				(xy 222.339154 -384.548888) (xy 222.339154 -383.433828)
				(arc
					(start 221.993714 -383.433828)
					(mid 221.727014 -383.698)
					(end 221.460314 -383.433828)
				)
				(arc
					(start 221.460314 -383.431288)
					(mid 221.727014 -383.164588)
					(end 221.993714 -383.431288)
				)
			)
		)
	)
	(zone
		(layers "B.Cu" "In5.Cu")
		(hatch none 0.5)
		(connect_pads
			(clearance 0)
		)
		(min_thickness 0.25)
		(keepout
			(tracks not_allowed)
			(vias allowed)
			(pads allowed)
			(copperpour not_allowed)
			(footprints allowed)
		)
		(placement
			(enabled no)
			(sheetname "")
		)
		(fill yes
			(thermal_gap 0.5)
			(thermal_bridge_width 0.5)
			(island_removal_mode 0)
		)
		(polygon
			(pts
				(arc
					(start 222.339154 -491.231428)
					(mid 221.727014 -490.619288)
					(end 221.114874 -491.231428)
				)
				(arc
					(start 221.114874 -492.349028)
					(mid 221.725744 -492.961167)
					(end 222.339154 -492.351568)
				)
				(arc
					(start 221.993714 -492.351568)
					(mid 221.727014 -492.61574)
					(end 221.460314 -492.351568)
				)
				(arc
					(start 221.460314 -492.349028)
					(mid 221.727014 -492.082328)
					(end 221.993714 -492.349028)
				)
				(xy 222.339154 -492.349028) (xy 222.339154 -491.233968)
				(arc
					(start 221.993714 -491.233968)
					(mid 221.727014 -491.49814)
					(end 221.460314 -491.233968)
				)
				(arc
					(start 221.460314 -491.231428)
					(mid 221.727014 -490.964728)
					(end 221.993714 -491.231428)
				)
			)
		)
	)
	(zone
		(layers "B.Cu" "In5.Cu")
		(hatch none 0.5)
		(connect_pads
			(clearance 0)
		)
		(min_thickness 0.25)
		(keepout
			(tracks not_allowed)
			(vias allowed)
			(pads allowed)
			(copperpour not_allowed)
			(footprints allowed)
		)
		(placement
			(enabled no)
			(sheetname "")
		)
		(fill yes
			(thermal_gap 0.5)
			(thermal_bridge_width 0.5)
			(island_removal_mode 0)
		)
		(polygon
			(pts
				(arc
					(start 37.33927 -481.631244)
					(mid 36.72713 -481.019104)
					(end 36.11499 -481.631244)
				)
				(arc
					(start 36.11499 -482.74859)
					(mid 36.725733 -483.360982)
					(end 37.33927 -482.751384)
				)
				(arc
					(start 36.99383 -482.751384)
					(mid 36.72713 -483.015556)
					(end 36.46043 -482.751384)
				)
				(arc
					(start 36.46043 -482.748844)
					(mid 36.72713 -482.482144)
					(end 36.99383 -482.748844)
				)
				(xy 37.33927 -482.748844) (xy 37.33927 -481.633784)
				(arc
					(start 36.99383 -481.633784)
					(mid 36.72713 -481.897956)
					(end 36.46043 -481.633784)
				)
				(arc
					(start 36.46043 -481.631244)
					(mid 36.72713 -481.364544)
					(end 36.99383 -481.631244)
				)
			)
		)
	)
	(zone
		(layers "B.Cu" "In5.Cu")
		(hatch none 0.5)
		(connect_pads
			(clearance 0)
		)
		(min_thickness 0.25)
		(keepout
			(tracks not_allowed)
			(vias allowed)
			(pads allowed)
			(copperpour not_allowed)
			(footprints allowed)
		)
		(placement
			(enabled no)
			(sheetname "")
		)
		(fill yes
			(thermal_gap 0.5)
			(thermal_bridge_width 0.5)
			(island_removal_mode 0)
		)
		(polygon
			(pts
				(arc
					(start 222.339154 -159.831278)
					(mid 221.727014 -159.219138)
					(end 221.114874 -159.831278)
				)
				(arc
					(start 221.114874 -160.948878)
					(mid 221.725744 -161.561017)
					(end 222.339154 -160.951418)
				)
				(arc
					(start 221.993714 -160.951418)
					(mid 221.727014 -161.21559)
					(end 221.460314 -160.951418)
				)
				(arc
					(start 221.460314 -160.948878)
					(mid 221.727014 -160.682178)
					(end 221.993714 -160.948878)
				)
				(xy 222.339154 -160.948878) (xy 222.339154 -159.833818)
				(arc
					(start 221.993714 -159.833818)
					(mid 221.727014 -160.09799)
					(end 221.460314 -159.833818)
				)
				(arc
					(start 221.460314 -159.831278)
					(mid 221.727014 -159.564578)
					(end 221.993714 -159.831278)
				)
			)
		)
	)
	(zone
		(layers "B.Cu" "In5.Cu")
		(hatch none 0.5)
		(connect_pads
			(clearance 0)
		)
		(min_thickness 0.25)
		(keepout
			(tracks not_allowed)
			(vias allowed)
			(pads allowed)
			(copperpour not_allowed)
			(footprints allowed)
		)
		(placement
			(enabled no)
			(sheetname "")
		)
		(fill yes
			(thermal_gap 0.5)
			(thermal_bridge_width 0.5)
			(island_removal_mode 0)
		)
		(polygon
			(pts
				(arc
					(start 37.33927 -69.631052)
					(mid 36.72713 -69.018912)
					(end 36.11499 -69.631052)
				)
				(arc
					(start 36.11499 -70.748652)
					(mid 36.72586 -71.360791)
					(end 37.33927 -70.751192)
				)
				(arc
					(start 36.99383 -70.751192)
					(mid 36.72713 -71.015364)
					(end 36.46043 -70.751192)
				)
				(arc
					(start 36.46043 -70.748652)
					(mid 36.72713 -70.481952)
					(end 36.99383 -70.748652)
				)
				(xy 37.33927 -70.748652) (xy 37.33927 -69.633592)
				(arc
					(start 36.99383 -69.633592)
					(mid 36.72713 -69.897764)
					(end 36.46043 -69.633592)
				)
				(arc
					(start 36.46043 -69.631052)
					(mid 36.72713 -69.364352)
					(end 36.99383 -69.631052)
				)
			)
		)
	)
	(zone
		(layers "B.Cu" "In5.Cu")
		(hatch none 0.5)
		(connect_pads
			(clearance 0)
		)
		(min_thickness 0.25)
		(keepout
			(tracks not_allowed)
			(vias allowed)
			(pads allowed)
			(copperpour not_allowed)
			(footprints allowed)
		)
		(placement
			(enabled no)
			(sheetname "")
		)
		(fill yes
			(thermal_gap 0.5)
			(thermal_bridge_width 0.5)
			(island_removal_mode 0)
		)
		(polygon
			(pts
				(arc
					(start 222.339154 -177.431192)
					(mid 221.727014 -176.819052)
					(end 221.114874 -177.431192)
				)
				(arc
					(start 221.114874 -178.548792)
					(mid 221.725744 -179.160931)
					(end 222.339154 -178.551332)
				)
				(arc
					(start 221.993714 -178.551332)
					(mid 221.727014 -178.815504)
					(end 221.460314 -178.551332)
				)
				(arc
					(start 221.460314 -178.548792)
					(mid 221.727014 -178.282092)
					(end 221.993714 -178.548792)
				)
				(xy 222.339154 -178.548792) (xy 222.339154 -177.433732)
				(arc
					(start 221.993714 -177.433732)
					(mid 221.727014 -177.697904)
					(end 221.460314 -177.433732)
				)
				(arc
					(start 221.460314 -177.431192)
					(mid 221.727014 -177.164492)
					(end 221.993714 -177.431192)
				)
			)
		)
	)
	(zone
		(layers "B.Cu" "In5.Cu")
		(hatch none 0.5)
		(connect_pads
			(clearance 0)
		)
		(min_thickness 0.25)
		(keepout
			(tracks not_allowed)
			(vias allowed)
			(pads allowed)
			(copperpour not_allowed)
			(footprints allowed)
		)
		(placement
			(enabled no)
			(sheetname "")
		)
		(fill yes
			(thermal_gap 0.5)
			(thermal_bridge_width 0.5)
			(island_removal_mode 0)
		)
		(polygon
			(pts
				(arc
					(start 222.339154 -79.231236)
					(mid 221.727014 -78.619096)
					(end 221.114874 -79.231236)
				)
				(arc
					(start 221.114874 -80.348836)
					(mid 221.725744 -80.960975)
					(end 222.339154 -80.351376)
				)
				(arc
					(start 221.993714 -80.351376)
					(mid 221.727014 -80.615548)
					(end 221.460314 -80.351376)
				)
				(arc
					(start 221.460314 -80.348836)
					(mid 221.727014 -80.082136)
					(end 221.993714 -80.348836)
				)
				(xy 222.339154 -80.348836) (xy 222.339154 -79.233776)
				(arc
					(start 221.993714 -79.233776)
					(mid 221.727014 -79.497948)
					(end 221.460314 -79.233776)
				)
				(arc
					(start 221.460314 -79.231236)
					(mid 221.727014 -78.964536)
					(end 221.993714 -79.231236)
				)
			)
		)
	)
	(zone
		(layers "B.Cu" "In5.Cu")
		(hatch none 0.5)
		(connect_pads
			(clearance 0)
		)
		(min_thickness 0.25)
		(keepout
			(tracks not_allowed)
			(vias allowed)
			(pads allowed)
			(copperpour not_allowed)
			(footprints allowed)
		)
		(placement
			(enabled no)
			(sheetname "")
		)
		(fill yes
			(thermal_gap 0.5)
			(thermal_bridge_width 0.5)
			(island_removal_mode 0)
		)
		(polygon
			(pts
				(arc
					(start 25.88514 -425.651168)
					(mid 25.273 -425.039028)
					(end 24.66086 -425.651168)
				)
				(arc
					(start 24.66086 -426.768768)
					(mid 25.27173 -427.380907)
					(end 25.88514 -426.771308)
				)
				(arc
					(start 25.5397 -426.771308)
					(mid 25.273 -427.03548)
					(end 25.0063 -426.771308)
				)
				(arc
					(start 25.0063 -426.768768)
					(mid 25.273 -426.502068)
					(end 25.5397 -426.768768)
				)
				(xy 25.88514 -426.768768) (xy 25.88514 -425.653708)
				(arc
					(start 25.5397 -425.653708)
					(mid 25.273 -425.91788)
					(end 25.0063 -425.653708)
				)
				(arc
					(start 25.0063 -425.651168)
					(mid 25.273 -425.384468)
					(end 25.5397 -425.651168)
				)
			)
		)
	)
	(zone
		(layers "B.Cu" "In5.Cu")
		(hatch none 0.5)
		(connect_pads
			(clearance 0)
		)
		(min_thickness 0.25)
		(keepout
			(tracks not_allowed)
			(vias allowed)
			(pads allowed)
			(copperpour not_allowed)
			(footprints allowed)
		)
		(placement
			(enabled no)
			(sheetname "")
		)
		(fill yes
			(thermal_gap 0.5)
			(thermal_bridge_width 0.5)
			(island_removal_mode 0)
		)
		(polygon
			(pts
				(arc
					(start 222.339154 -468.831422)
					(mid 221.727014 -468.219282)
					(end 221.114874 -468.831422)
				)
				(arc
					(start 221.114874 -469.949022)
					(mid 221.725744 -470.561161)
					(end 222.339154 -469.951562)
				)
				(arc
					(start 221.993714 -469.951562)
					(mid 221.727014 -470.215734)
					(end 221.460314 -469.951562)
				)
				(arc
					(start 221.460314 -469.949022)
					(mid 221.727014 -469.682322)
					(end 221.993714 -469.949022)
				)
				(xy 222.339154 -469.949022) (xy 222.339154 -468.833962)
				(arc
					(start 221.993714 -468.833962)
					(mid 221.727014 -469.098134)
					(end 221.460314 -468.833962)
				)
				(arc
					(start 221.460314 -468.831422)
					(mid 221.727014 -468.564722)
					(end 221.993714 -468.831422)
				)
			)
		)
	)
	(zone
		(layers "B.Cu" "In5.Cu")
		(hatch none 0.5)
		(connect_pads
			(clearance 0)
		)
		(min_thickness 0.25)
		(keepout
			(tracks not_allowed)
			(vias allowed)
			(pads allowed)
			(copperpour not_allowed)
			(footprints allowed)
		)
		(placement
			(enabled no)
			(sheetname "")
		)
		(fill yes
			(thermal_gap 0.5)
			(thermal_bridge_width 0.5)
			(island_removal_mode 0)
		)
		(polygon
			(pts
				(arc
					(start 25.88514 -332.251304)
					(mid 25.273 -331.639164)
					(end 24.66086 -332.251304)
				)
				(arc
					(start 24.66086 -333.36865)
					(mid 25.271603 -333.981042)
					(end 25.88514 -333.371444)
				)
				(arc
					(start 25.5397 -333.371444)
					(mid 25.273 -333.635616)
					(end 25.0063 -333.371444)
				)
				(arc
					(start 25.0063 -333.368904)
					(mid 25.273 -333.102204)
					(end 25.5397 -333.368904)
				)
				(xy 25.88514 -333.368904) (xy 25.88514 -332.253844)
				(arc
					(start 25.5397 -332.253844)
					(mid 25.273 -332.518016)
					(end 25.0063 -332.253844)
				)
				(arc
					(start 25.0063 -332.251304)
					(mid 25.273 -331.984604)
					(end 25.5397 -332.251304)
				)
			)
		)
	)
	(zone
		(layers "B.Cu" "In5.Cu")
		(hatch none 0.5)
		(connect_pads
			(clearance 0)
		)
		(min_thickness 0.25)
		(keepout
			(tracks not_allowed)
			(vias allowed)
			(pads allowed)
			(copperpour not_allowed)
			(footprints allowed)
		)
		(placement
			(enabled no)
			(sheetname "")
		)
		(fill yes
			(thermal_gap 0.5)
			(thermal_bridge_width 0.5)
			(island_removal_mode 0)
		)
		(polygon
			(pts
				(arc
					(start 222.339154 -378.631196)
					(mid 221.727014 -378.019056)
					(end 221.114874 -378.631196)
				)
				(arc
					(start 221.114874 -379.748796)
					(mid 221.725744 -380.360935)
					(end 222.339154 -379.751336)
				)
				(arc
					(start 221.993714 -379.751336)
					(mid 221.727014 -380.015508)
					(end 221.460314 -379.751336)
				)
				(arc
					(start 221.460314 -379.748796)
					(mid 221.727014 -379.482096)
					(end 221.993714 -379.748796)
				)
				(xy 222.339154 -379.748796) (xy 222.339154 -378.633736)
				(arc
					(start 221.993714 -378.633736)
					(mid 221.727014 -378.897908)
					(end 221.460314 -378.633736)
				)
				(arc
					(start 221.460314 -378.631196)
					(mid 221.727014 -378.364496)
					(end 221.993714 -378.631196)
				)
			)
		)
	)
	(zone
		(layers "B.Cu" "In5.Cu")
		(hatch none 0.5)
		(connect_pads
			(clearance 0)
		)
		(min_thickness 0.25)
		(keepout
			(tracks not_allowed)
			(vias allowed)
			(pads allowed)
			(copperpour not_allowed)
			(footprints allowed)
		)
		(placement
			(enabled no)
			(sheetname "")
		)
		(fill yes
			(thermal_gap 0.5)
			(thermal_bridge_width 0.5)
			(island_removal_mode 0)
		)
		(polygon
			(pts
				(arc
					(start 25.88514 -23.25116)
					(mid 25.273 -22.63902)
					(end 24.66086 -23.25116)
				)
				(arc
					(start 24.66086 -24.368506)
					(mid 25.271603 -24.980898)
					(end 25.88514 -24.3713)
				)
				(arc
					(start 25.5397 -24.3713)
					(mid 25.273 -24.635472)
					(end 25.0063 -24.3713)
				)
				(arc
					(start 25.0063 -24.36876)
					(mid 25.273 -24.10206)
					(end 25.5397 -24.36876)
				)
				(xy 25.88514 -24.36876) (xy 25.88514 -23.2537)
				(arc
					(start 25.5397 -23.2537)
					(mid 25.273 -23.517872)
					(end 25.0063 -23.2537)
				)
				(arc
					(start 25.0063 -23.25116)
					(mid 25.273 -22.98446)
					(end 25.5397 -23.25116)
				)
			)
		)
	)
	(zone
		(layers "B.Cu" "In5.Cu")
		(hatch none 0.5)
		(connect_pads
			(clearance 0)
		)
		(min_thickness 0.25)
		(keepout
			(tracks not_allowed)
			(vias allowed)
			(pads allowed)
			(copperpour not_allowed)
			(footprints allowed)
		)
		(placement
			(enabled no)
			(sheetname "")
		)
		(fill yes
			(thermal_gap 0.5)
			(thermal_bridge_width 0.5)
			(island_removal_mode 0)
		)
		(polygon
			(pts
				(arc
					(start 25.88514 -448.051174)
					(mid 25.273 -447.439034)
					(end 24.66086 -448.051174)
				)
				(arc
					(start 24.66086 -449.168774)
					(mid 25.27173 -449.780913)
					(end 25.88514 -449.171314)
				)
				(arc
					(start 25.5397 -449.171314)
					(mid 25.273 -449.435486)
					(end 25.0063 -449.171314)
				)
				(arc
					(start 25.0063 -449.168774)
					(mid 25.273 -448.902074)
					(end 25.5397 -449.168774)
				)
				(xy 25.88514 -449.168774) (xy 25.88514 -448.053714)
				(arc
					(start 25.5397 -448.053714)
					(mid 25.273 -448.317886)
					(end 25.0063 -448.053714)
				)
				(arc
					(start 25.0063 -448.051174)
					(mid 25.273 -447.784474)
					(end 25.5397 -448.051174)
				)
			)
		)
	)
	(zone
		(layers "B.Cu" "In5.Cu")
		(hatch none 0.5)
		(connect_pads
			(clearance 0)
		)
		(min_thickness 0.25)
		(keepout
			(tracks not_allowed)
			(vias allowed)
			(pads allowed)
			(copperpour not_allowed)
			(footprints allowed)
		)
		(placement
			(enabled no)
			(sheetname "")
		)
		(fill yes
			(thermal_gap 0.5)
			(thermal_bridge_width 0.5)
			(island_removal_mode 0)
		)
		(polygon
			(pts
				(arc
					(start 37.33927 -56.83123)
					(mid 36.72713 -56.21909)
					(end 36.11499 -56.83123)
				)
				(arc
					(start 36.11499 -57.94883)
					(mid 36.72586 -58.560969)
					(end 37.33927 -57.95137)
				)
				(arc
					(start 36.99383 -57.95137)
					(mid 36.72713 -58.215542)
					(end 36.46043 -57.95137)
				)
				(arc
					(start 36.46043 -57.94883)
					(mid 36.72713 -57.68213)
					(end 36.99383 -57.94883)
				)
				(xy 37.33927 -57.94883) (xy 37.33927 -56.83377)
				(arc
					(start 36.99383 -56.83377)
					(mid 36.72713 -57.097942)
					(end 36.46043 -56.83377)
				)
				(arc
					(start 36.46043 -56.83123)
					(mid 36.72713 -56.56453)
					(end 36.99383 -56.83123)
				)
			)
		)
	)
	(zone
		(layers "B.Cu" "In5.Cu")
		(hatch none 0.5)
		(connect_pads
			(clearance 0)
		)
		(min_thickness 0.25)
		(keepout
			(tracks not_allowed)
			(vias allowed)
			(pads allowed)
			(copperpour not_allowed)
			(footprints allowed)
		)
		(placement
			(enabled no)
			(sheetname "")
		)
		(fill yes
			(thermal_gap 0.5)
			(thermal_bridge_width 0.5)
			(island_removal_mode 0)
		)
		(polygon
			(pts
				(arc
					(start 25.88514 -242.051078)
					(mid 25.273 -241.438938)
					(end 24.66086 -242.051078)
				)
				(arc
					(start 24.66086 -243.168424)
					(mid 25.271603 -243.780816)
					(end 25.88514 -243.171218)
				)
				(arc
					(start 25.5397 -243.171218)
					(mid 25.273 -243.43539)
					(end 25.0063 -243.171218)
				)
				(arc
					(start 25.0063 -243.168678)
					(mid 25.273 -242.901978)
					(end 25.5397 -243.168678)
				)
				(xy 25.88514 -243.168678) (xy 25.88514 -242.053618)
				(arc
					(start 25.5397 -242.053618)
					(mid 25.273 -242.31779)
					(end 25.0063 -242.053618)
				)
				(arc
					(start 25.0063 -242.051078)
					(mid 25.273 -241.784378)
					(end 25.5397 -242.051078)
				)
			)
		)
	)
	(zone
		(layers "B.Cu" "In5.Cu")
		(hatch none 0.5)
		(connect_pads
			(clearance 0)
		)
		(min_thickness 0.25)
		(keepout
			(tracks not_allowed)
			(vias allowed)
			(pads allowed)
			(copperpour not_allowed)
			(footprints allowed)
		)
		(placement
			(enabled no)
			(sheetname "")
		)
		(fill yes
			(thermal_gap 0.5)
			(thermal_bridge_width 0.5)
			(island_removal_mode 0)
		)
		(polygon
			(pts
				(arc
					(start 222.339154 -275.631148)
					(mid 221.727014 -275.019008)
					(end 221.114874 -275.631148)
				)
				(arc
					(start 221.114874 -276.748748)
					(mid 221.725744 -277.360887)
					(end 222.339154 -276.751288)
				)
				(arc
					(start 221.993714 -276.751288)
					(mid 221.727014 -277.01546)
					(end 221.460314 -276.751288)
				)
				(arc
					(start 221.460314 -276.748748)
					(mid 221.727014 -276.482048)
					(end 221.993714 -276.748748)
				)
				(xy 222.339154 -276.748748) (xy 222.339154 -275.633688)
				(arc
					(start 221.993714 -275.633688)
					(mid 221.727014 -275.89786)
					(end 221.460314 -275.633688)
				)
				(arc
					(start 221.460314 -275.631148)
					(mid 221.727014 -275.364448)
					(end 221.993714 -275.631148)
				)
			)
		)
	)
	(zone
		(layers "B.Cu" "In5.Cu")
		(hatch none 0.5)
		(connect_pads
			(clearance 0)
		)
		(min_thickness 0.25)
		(keepout
			(tracks not_allowed)
			(vias allowed)
			(pads allowed)
			(copperpour not_allowed)
			(footprints allowed)
		)
		(placement
			(enabled no)
			(sheetname "")
		)
		(fill yes
			(thermal_gap 0.5)
			(thermal_bridge_width 0.5)
			(island_removal_mode 0)
		)
		(polygon
			(pts
				(arc
					(start 37.33927 -383.431288)
					(mid 36.72713 -382.819148)
					(end 36.11499 -383.431288)
				)
				(arc
					(start 36.11499 -384.548888)
					(mid 36.72586 -385.161027)
					(end 37.33927 -384.551428)
				)
				(arc
					(start 36.99383 -384.551428)
					(mid 36.72713 -384.8156)
					(end 36.46043 -384.551428)
				)
				(arc
					(start 36.46043 -384.548888)
					(mid 36.72713 -384.282188)
					(end 36.99383 -384.548888)
				)
				(xy 37.33927 -384.548888) (xy 37.33927 -383.433828)
				(arc
					(start 36.99383 -383.433828)
					(mid 36.72713 -383.698)
					(end 36.46043 -383.433828)
				)
				(arc
					(start 36.46043 -383.431288)
					(mid 36.72713 -383.164588)
					(end 36.99383 -383.431288)
				)
			)
		)
	)
	(zone
		(layers "B.Cu" "In5.Cu")
		(hatch none 0.5)
		(connect_pads
			(clearance 0)
		)
		(min_thickness 0.25)
		(keepout
			(tracks not_allowed)
			(vias allowed)
			(pads allowed)
			(copperpour not_allowed)
			(footprints allowed)
		)
		(placement
			(enabled no)
			(sheetname "")
		)
		(fill yes
			(thermal_gap 0.5)
			(thermal_bridge_width 0.5)
			(island_removal_mode 0)
		)
		(polygon
			(pts
				(arc
					(start 25.88514 -219.651072)
					(mid 25.273 -219.038932)
					(end 24.66086 -219.651072)
				)
				(arc
					(start 24.66086 -220.768672)
					(mid 25.27173 -221.380811)
					(end 25.88514 -220.771212)
				)
				(arc
					(start 25.5397 -220.771212)
					(mid 25.273 -221.035384)
					(end 25.0063 -220.771212)
				)
				(arc
					(start 25.0063 -220.768672)
					(mid 25.273 -220.501972)
					(end 25.5397 -220.768672)
				)
				(xy 25.88514 -220.768672) (xy 25.88514 -219.653612)
				(arc
					(start 25.5397 -219.653612)
					(mid 25.273 -219.917784)
					(end 25.0063 -219.653612)
				)
				(arc
					(start 25.0063 -219.651072)
					(mid 25.273 -219.384372)
					(end 25.5397 -219.651072)
				)
			)
		)
	)
	(zone
		(layer "In1.Cu")
		(hatch none 0.5)
		(connect_pads
			(clearance 0)
		)
		(min_thickness 0.25)
		(keepout
			(tracks not_allowed)
			(vias allowed)
			(pads allowed)
			(copperpour not_allowed)
			(footprints allowed)
		)
		(placement
			(enabled no)
			(sheetname "")
		)
		(fill
			(thermal_gap 0.5)
			(thermal_bridge_width 0.5)
			(island_removal_mode 0)
		)
		(polygon
			(pts
				(xy 97.574862 -300.17339) (xy 96.384618 -300.17339) (xy 96.384618 -301.34179) (xy 97.574862 -301.34179)
			)
		)
	)
	(zone
		(layer "In1.Cu")
		(hatch none 0.5)
		(connect_pads
			(clearance 0)
		)
		(min_thickness 0.25)
		(keepout
			(tracks not_allowed)
			(vias allowed)
			(pads allowed)
			(copperpour not_allowed)
			(footprints allowed)
		)
		(placement
			(enabled no)
			(sheetname "")
		)
		(fill
			(thermal_gap 0.5)
			(thermal_bridge_width 0.5)
			(island_removal_mode 0)
		)
		(polygon
			(pts
				(arc
					(start 78.74 -304.43424)
					(mid 78.813638 -304.403738)
					(end 78.84414 -304.3301)
				)
				(arc
					(start 78.84414 -303.9745)
					(mid 78.813638 -303.900862)
					(end 78.74 -303.87036)
				)
				(arc
					(start 78.3844 -303.87036)
					(mid 78.310762 -303.900862)
					(end 78.28026 -303.9745)
				)
				(arc
					(start 78.28026 -304.3301)
					(mid 78.310762 -304.403738)
					(end 78.3844 -304.43424)
				)
			)
		)
	)
	(zone
		(layer "In1.Cu")
		(hatch none 0.5)
		(connect_pads
			(clearance 0)
		)
		(min_thickness 0.25)
		(keepout
			(tracks not_allowed)
			(vias allowed)
			(pads allowed)
			(copperpour not_allowed)
			(footprints allowed)
		)
		(placement
			(enabled no)
			(sheetname "")
		)
		(fill
			(thermal_gap 0.5)
			(thermal_bridge_width 0.5)
			(island_removal_mode 0)
		)
		(polygon
			(pts
				(arc
					(start 95.3262 -218.7448)
					(mid 95.254358 -218.774558)
					(end 95.2246 -218.8464)
				)
				(arc
					(start 95.2246 -220.0656)
					(mid 95.254358 -220.137442)
					(end 95.3262 -220.1672)
				)
				(arc
					(start 96.6978 -220.1672)
					(mid 96.769642 -220.137442)
					(end 96.7994 -220.0656)
				)
				(arc
					(start 96.7994 -218.8464)
					(mid 96.769642 -218.774558)
					(end 96.6978 -218.7448)
				)
			)
		)
	)
	(zone
		(layer "In1.Cu")
		(hatch none 0.5)
		(connect_pads
			(clearance 0)
		)
		(min_thickness 0.25)
		(keepout
			(tracks not_allowed)
			(vias allowed)
			(pads allowed)
			(copperpour not_allowed)
			(footprints allowed)
		)
		(placement
			(enabled no)
			(sheetname "")
		)
		(fill
			(thermal_gap 0.5)
			(thermal_bridge_width 0.5)
			(island_removal_mode 0)
		)
		(polygon
			(pts
				(arc
					(start 85.70214 -209.9183)
					(mid 85.686517 -209.880583)
					(end 85.6488 -209.86496)
				)
				(arc
					(start 85.4456 -209.86496)
					(mid 85.407883 -209.880583)
					(end 85.39226 -209.9183)
				)
				(arc
					(start 85.39226 -210.1723)
					(mid 85.407883 -210.210017)
					(end 85.4456 -210.22564)
				)
				(arc
					(start 85.6488 -210.22564)
					(mid 85.686517 -210.210017)
					(end 85.70214 -210.1723)
				)
			)
		)
	)
	(zone
		(layer "In1.Cu")
		(hatch none 0.5)
		(connect_pads
			(clearance 0)
		)
		(min_thickness 0.25)
		(keepout
			(tracks not_allowed)
			(vias allowed)
			(pads allowed)
			(copperpour not_allowed)
			(footprints allowed)
		)
		(placement
			(enabled no)
			(sheetname "")
		)
		(fill
			(thermal_gap 0.5)
			(thermal_bridge_width 0.5)
			(island_removal_mode 0)
		)
		(polygon
			(pts
				(arc
					(start 95.3262 -295.8338)
					(mid 95.254358 -295.863558)
					(end 95.2246 -295.9354)
				)
				(arc
					(start 95.2246 -297.1546)
					(mid 95.254358 -297.226442)
					(end 95.3262 -297.2562)
				)
				(arc
					(start 96.6978 -297.2562)
					(mid 96.769642 -297.226442)
					(end 96.7994 -297.1546)
				)
				(arc
					(start 96.7994 -295.9354)
					(mid 96.769642 -295.863558)
					(end 96.6978 -295.8338)
				)
			)
		)
	)
	(zone
		(layer "In1.Cu")
		(hatch none 0.5)
		(connect_pads
			(clearance 0)
		)
		(min_thickness 0.25)
		(keepout
			(tracks not_allowed)
			(vias allowed)
			(pads allowed)
			(copperpour not_allowed)
			(footprints allowed)
		)
		(placement
			(enabled no)
			(sheetname "")
		)
		(fill
			(thermal_gap 0.5)
			(thermal_bridge_width 0.5)
			(island_removal_mode 0)
		)
		(polygon
			(pts
				(arc
					(start 7.2644 -450.6341)
					(mid 7.192558 -450.663858)
					(end 7.1628 -450.7357)
				)
				(arc
					(start 7.1628 -452.0311)
					(mid 7.192558 -452.102942)
					(end 7.2644 -452.1327)
				)
				(arc
					(start 8.5852 -452.1327)
					(mid 8.657042 -452.102942)
					(end 8.6868 -452.0311)
				)
				(arc
					(start 8.6868 -450.7357)
					(mid 8.657042 -450.663858)
					(end 8.5852 -450.6341)
				)
			)
		)
	)
	(zone
		(layer "In1.Cu")
		(hatch none 0.5)
		(connect_pads
			(clearance 0)
		)
		(min_thickness 0.25)
		(keepout
			(tracks not_allowed)
			(vias allowed)
			(pads allowed)
			(copperpour not_allowed)
			(footprints allowed)
		)
		(placement
			(enabled no)
			(sheetname "")
		)
		(fill
			(thermal_gap 0.5)
			(thermal_bridge_width 0.5)
			(island_removal_mode 0)
		)
		(polygon
			(pts
				(arc
					(start 8.1407 -383.3368)
					(mid 8.068858 -383.366558)
					(end 8.0391 -383.4384)
				)
				(arc
					(start 8.0391 -384.7592)
					(mid 8.068858 -384.831042)
					(end 8.1407 -384.8608)
				)
				(arc
					(start 9.4361 -384.8608)
					(mid 9.507942 -384.831042)
					(end 9.5377 -384.7592)
				)
				(arc
					(start 9.5377 -383.4384)
					(mid 9.507942 -383.366558)
					(end 9.4361 -383.3368)
				)
			)
		)
	)
	(zone
		(layer "In1.Cu")
		(hatch none 0.5)
		(connect_pads
			(clearance 0)
		)
		(min_thickness 0.25)
		(keepout
			(tracks not_allowed)
			(vias allowed)
			(pads allowed)
			(copperpour not_allowed)
			(footprints allowed)
		)
		(placement
			(enabled no)
			(sheetname "")
		)
		(fill
			(thermal_gap 0.5)
			(thermal_bridge_width 0.5)
			(island_removal_mode 0)
		)
		(polygon
			(pts
				(xy 96.383602 -215.82761) (xy 97.575878 -215.82761) (xy 97.575878 -214.65921) (xy 96.383602 -214.65921)
			)
		)
	)
	(zone
		(layer "In1.Cu")
		(hatch none 0.5)
		(connect_pads
			(clearance 0)
		)
		(min_thickness 0.25)
		(keepout
			(tracks not_allowed)
			(vias allowed)
			(pads allowed)
			(copperpour not_allowed)
			(footprints allowed)
		)
		(placement
			(enabled no)
			(sheetname "")
		)
		(fill
			(thermal_gap 0.5)
			(thermal_bridge_width 0.5)
			(island_removal_mode 0)
		)
		(polygon
			(pts
				(arc
					(start 77.343 -303.87036)
					(mid 77.269362 -303.900862)
					(end 77.23886 -303.9745)
				)
				(arc
					(start 77.23886 -304.3301)
					(mid 77.269362 -304.403738)
					(end 77.343 -304.43424)
				)
				(arc
					(start 77.6986 -304.43424)
					(mid 77.772238 -304.403738)
					(end 77.80274 -304.3301)
				)
				(arc
					(start 77.80274 -303.9745)
					(mid 77.772238 -303.900862)
					(end 77.6986 -303.87036)
				)
			)
		)
	)
	(zone
		(layer "In1.Cu")
		(hatch none 0.5)
		(connect_pads
			(clearance 0)
		)
		(min_thickness 0.25)
		(keepout
			(tracks not_allowed)
			(vias allowed)
			(pads allowed)
			(copperpour not_allowed)
			(footprints allowed)
		)
		(placement
			(enabled no)
			(sheetname "")
		)
		(fill
			(thermal_gap 0.5)
			(thermal_bridge_width 0.5)
			(island_removal_mode 0)
		)
		(polygon
			(pts
				(xy 93.075252 -96.59239) (xy 91.882722 -96.59239) (xy 91.882722 -97.76079) (xy 93.075252 -97.76079)
			)
		)
	)
	(zone
		(layer "In1.Cu")
		(hatch none 0.5)
		(connect_pads
			(clearance 0)
		)
		(min_thickness 0.25)
		(keepout
			(tracks not_allowed)
			(vias allowed)
			(pads allowed)
			(copperpour not_allowed)
			(footprints allowed)
		)
		(placement
			(enabled no)
			(sheetname "")
		)
		(fill
			(thermal_gap 0.5)
			(thermal_bridge_width 0.5)
			(island_removal_mode 0)
		)
		(polygon
			(pts
				(xy 91.076018 -426.790104) (xy 89.889838 -426.790104) (xy 89.889838 -427.958504) (xy 91.076018 -427.958504)
			)
		)
	)
	(zone
		(layer "In1.Cu")
		(hatch none 0.5)
		(connect_pads
			(clearance 0)
		)
		(min_thickness 0.25)
		(keepout
			(tracks not_allowed)
			(vias allowed)
			(pads allowed)
			(copperpour not_allowed)
			(footprints allowed)
		)
		(placement
			(enabled no)
			(sheetname "")
		)
		(fill
			(thermal_gap 0.5)
			(thermal_bridge_width 0.5)
			(island_removal_mode 0)
		)
		(polygon
			(pts
				(xy 91.883738 -436.80761) (xy 93.074744 -436.80761) (xy 93.074744 -435.63921) (xy 91.883738 -435.63921)
			)
		)
	)
	(zone
		(layer "In1.Cu")
		(hatch none 0.5)
		(connect_pads
			(clearance 0)
		)
		(min_thickness 0.25)
		(keepout
			(tracks not_allowed)
			(vias allowed)
			(pads allowed)
			(copperpour not_allowed)
			(footprints allowed)
		)
		(placement
			(enabled no)
			(sheetname "")
		)
		(fill
			(thermal_gap 0.5)
			(thermal_bridge_width 0.5)
			(island_removal_mode 0)
		)
		(polygon
			(pts
				(arc
					(start 78.5622 -210.08594)
					(mid 78.635838 -210.055438)
					(end 78.66634 -209.9818)
				)
				(arc
					(start 78.66634 -209.6262)
					(mid 78.635838 -209.552562)
					(end 78.5622 -209.52206)
				)
				(arc
					(start 78.2066 -209.52206)
					(mid 78.132962 -209.552562)
					(end 78.10246 -209.6262)
				)
				(arc
					(start 78.10246 -209.9818)
					(mid 78.132962 -210.055438)
					(end 78.2066 -210.08594)
				)
			)
		)
	)
	(zone
		(layer "In1.Cu")
		(hatch none 0.5)
		(connect_pads
			(clearance 0)
		)
		(min_thickness 0.25)
		(keepout
			(tracks not_allowed)
			(vias allowed)
			(pads allowed)
			(copperpour not_allowed)
			(footprints allowed)
		)
		(placement
			(enabled no)
			(sheetname "")
		)
		(fill
			(thermal_gap 0.5)
			(thermal_bridge_width 0.5)
			(island_removal_mode 0)
		)
		(polygon
			(pts
				(xy 98.98761 -208.416398) (xy 98.98761 -207.223106) (xy 97.81921 -207.223106) (xy 97.81921 -208.416398)
			)
		)
	)
	(zone
		(layer "In1.Cu")
		(hatch none 0.5)
		(connect_pads
			(clearance 0)
		)
		(min_thickness 0.25)
		(keepout
			(tracks not_allowed)
			(vias allowed)
			(pads allowed)
			(copperpour not_allowed)
			(footprints allowed)
		)
		(placement
			(enabled no)
			(sheetname "")
		)
		(fill
			(thermal_gap 0.5)
			(thermal_bridge_width 0.5)
			(island_removal_mode 0)
		)
		(polygon
			(pts
				(xy 98.98761 -433.396898) (xy 98.98761 -432.202844) (xy 97.81921 -432.202844) (xy 97.81921 -433.396898)
			)
		)
	)
	(zone
		(layer "In1.Cu")
		(hatch none 0.5)
		(connect_pads
			(clearance 0)
		)
		(min_thickness 0.25)
		(keepout
			(tracks not_allowed)
			(vias allowed)
			(pads allowed)
			(copperpour not_allowed)
			(footprints allowed)
		)
		(placement
			(enabled no)
			(sheetname "")
		)
		(fill
			(thermal_gap 0.5)
			(thermal_bridge_width 0.5)
			(island_removal_mode 0)
		)
		(polygon
			(pts
				(arc
					(start 78.3844 -304.91176)
					(mid 78.310762 -304.942262)
					(end 78.28026 -305.0159)
				)
				(arc
					(start 78.28026 -305.3715)
					(mid 78.310762 -305.445138)
					(end 78.3844 -305.47564)
				)
				(arc
					(start 78.74 -305.47564)
					(mid 78.813638 -305.445138)
					(end 78.84414 -305.3715)
				)
				(arc
					(start 78.84414 -305.0159)
					(mid 78.813638 -304.942262)
					(end 78.74 -304.91176)
				)
			)
		)
	)
	(zone
		(layer "In1.Cu")
		(hatch none 0.5)
		(connect_pads
			(clearance 0)
		)
		(min_thickness 0.25)
		(keepout
			(tracks not_allowed)
			(vias allowed)
			(pads allowed)
			(copperpour not_allowed)
			(footprints allowed)
		)
		(placement
			(enabled no)
			(sheetname "")
		)
		(fill
			(thermal_gap 0.5)
			(thermal_bridge_width 0.5)
			(island_removal_mode 0)
		)
		(polygon
			(pts
				(xy 95.577406 -205.81239) (xy 94.382844 -205.81239) (xy 94.382844 -206.98079) (xy 95.577406 -206.98079)
			)
		)
	)
	(zone
		(layer "In1.Cu")
		(hatch none 0.5)
		(connect_pads
			(clearance 0)
		)
		(min_thickness 0.25)
		(keepout
			(tracks not_allowed)
			(vias allowed)
			(pads allowed)
			(copperpour not_allowed)
			(footprints allowed)
		)
		(placement
			(enabled no)
			(sheetname "")
		)
		(fill
			(thermal_gap 0.5)
			(thermal_bridge_width 0.5)
			(island_removal_mode 0)
		)
		(polygon
			(pts
				(arc
					(start 85.95614 -101.3968)
					(mid 85.940517 -101.359083)
					(end 85.9028 -101.34346)
				)
				(arc
					(start 85.6996 -101.34346)
					(mid 85.661883 -101.359083)
					(end 85.64626 -101.3968)
				)
				(arc
					(start 85.64626 -101.6508)
					(mid 85.661883 -101.688517)
					(end 85.6996 -101.70414)
				)
				(arc
					(start 85.9028 -101.70414)
					(mid 85.940517 -101.688517)
					(end 85.95614 -101.6508)
				)
			)
		)
	)
	(zone
		(layer "In1.Cu")
		(hatch none 0.5)
		(connect_pads
			(clearance 0)
		)
		(min_thickness 0.25)
		(keepout
			(tracks not_allowed)
			(vias allowed)
			(pads allowed)
			(copperpour not_allowed)
			(footprints allowed)
		)
		(placement
			(enabled no)
			(sheetname "")
		)
		(fill
			(thermal_gap 0.5)
			(thermal_bridge_width 0.5)
			(island_removal_mode 0)
		)
		(polygon
			(pts
				(arc
					(start 83.61934 -430.8983)
					(mid 83.603717 -430.860583)
					(end 83.566 -430.84496)
				)
				(arc
					(start 83.3628 -430.84496)
					(mid 83.325083 -430.860583)
					(end 83.30946 -430.8983)
				)
				(arc
					(start 83.30946 -431.1523)
					(mid 83.325083 -431.190017)
					(end 83.3628 -431.20564)
				)
				(arc
					(start 83.566 -431.20564)
					(mid 83.603717 -431.190017)
					(end 83.61934 -431.1523)
				)
			)
		)
	)
	(zone
		(layer "In1.Cu")
		(hatch none 0.5)
		(connect_pads
			(clearance 0)
		)
		(min_thickness 0.25)
		(keepout
			(tracks not_allowed)
			(vias allowed)
			(pads allowed)
			(copperpour not_allowed)
			(footprints allowed)
		)
		(placement
			(enabled no)
			(sheetname "")
		)
		(fill
			(thermal_gap 0.5)
			(thermal_bridge_width 0.5)
			(island_removal_mode 0)
		)
		(polygon
			(pts
				(arc
					(start 93.6752 -201.4728)
					(mid 93.603358 -201.502558)
					(end 93.5736 -201.5744)
				)
				(arc
					(start 93.5736 -202.7936)
					(mid 93.603358 -202.865442)
					(end 93.6752 -202.8952)
				)
				(arc
					(start 95.0468 -202.8952)
					(mid 95.118642 -202.865442)
					(end 95.1484 -202.7936)
				)
				(arc
					(start 95.1484 -201.5744)
					(mid 95.118642 -201.502558)
					(end 95.0468 -201.4728)
				)
			)
		)
	)
	(zone
		(layer "In1.Cu")
		(hatch none 0.5)
		(connect_pads
			(clearance 0)
		)
		(min_thickness 0.25)
		(keepout
			(tracks not_allowed)
			(vias allowed)
			(pads allowed)
			(copperpour not_allowed)
			(footprints allowed)
		)
		(placement
			(enabled no)
			(sheetname "")
		)
		(fill
			(thermal_gap 0.5)
			(thermal_bridge_width 0.5)
			(island_removal_mode 0)
		)
		(polygon
			(pts
				(xy 93.074998 -426.79239) (xy 91.882722 -426.79239) (xy 91.882722 -427.96079) (xy 93.074998 -427.96079)
			)
		)
	)
	(zone
		(layer "In1.Cu")
		(hatch none 0.5)
		(connect_pads
			(clearance 0)
		)
		(min_thickness 0.25)
		(keepout
			(tracks not_allowed)
			(vias allowed)
			(pads allowed)
			(copperpour not_allowed)
			(footprints allowed)
		)
		(placement
			(enabled no)
			(sheetname "")
		)
		(fill
			(thermal_gap 0.5)
			(thermal_bridge_width 0.5)
			(island_removal_mode 0)
		)
		(polygon
			(pts
				(xy 94.383098 -106.60761) (xy 95.577152 -106.60761) (xy 95.577152 -105.43921) (xy 94.383098 -105.43921)
			)
		)
	)
	(zone
		(layer "In1.Cu")
		(hatch none 0.5)
		(connect_pads
			(clearance 0)
		)
		(min_thickness 0.25)
		(keepout
			(tracks not_allowed)
			(vias allowed)
			(pads allowed)
			(copperpour not_allowed)
			(footprints allowed)
		)
		(placement
			(enabled no)
			(sheetname "")
		)
		(fill
			(thermal_gap 0.5)
			(thermal_bridge_width 0.5)
			(island_removal_mode 0)
		)
		(polygon
			(pts
				(arc
					(start 78.994 -431.05324)
					(mid 79.067638 -431.022738)
					(end 79.09814 -430.9491)
				)
				(arc
					(start 79.09814 -430.5935)
					(mid 79.067638 -430.519862)
					(end 78.994 -430.48936)
				)
				(arc
					(start 78.6384 -430.48936)
					(mid 78.564762 -430.519862)
					(end 78.53426 -430.5935)
				)
				(arc
					(start 78.53426 -430.9491)
					(mid 78.564762 -431.022738)
					(end 78.6384 -431.05324)
				)
			)
		)
	)
	(zone
		(layer "In1.Cu")
		(hatch none 0.5)
		(connect_pads
			(clearance 0)
		)
		(min_thickness 0.25)
		(keepout
			(tracks not_allowed)
			(vias allowed)
			(pads allowed)
			(copperpour not_allowed)
			(footprints allowed)
		)
		(placement
			(enabled no)
			(sheetname "")
		)
		(fill
			(thermal_gap 0.5)
			(thermal_bridge_width 0.5)
			(island_removal_mode 0)
		)
		(polygon
			(pts
				(xy 91.883484 -106.60761) (xy 93.074998 -106.60761) (xy 93.074998 -105.43921) (xy 91.883484 -105.43921)
			)
		)
	)
	(zone
		(layer "In1.Cu")
		(hatch none 0.5)
		(connect_pads
			(clearance 0)
		)
		(min_thickness 0.25)
		(keepout
			(tracks not_allowed)
			(vias allowed)
			(pads allowed)
			(copperpour not_allowed)
			(footprints allowed)
		)
		(placement
			(enabled no)
			(sheetname "")
		)
		(fill
			(thermal_gap 0.5)
			(thermal_bridge_width 0.5)
			(island_removal_mode 0)
		)
		(polygon
			(pts
				(xy 96.383348 -106.60761) (xy 97.577148 -106.60761) (xy 97.577148 -105.43921) (xy 96.383348 -105.43921)
			)
		)
	)
	(zone
		(layer "In1.Cu")
		(hatch none 0.5)
		(connect_pads
			(clearance 0)
		)
		(min_thickness 0.25)
		(keepout
			(tracks not_allowed)
			(vias allowed)
			(pads allowed)
			(copperpour not_allowed)
			(footprints allowed)
		)
		(placement
			(enabled no)
			(sheetname "")
		)
		(fill
			(thermal_gap 0.5)
			(thermal_bridge_width 0.5)
			(island_removal_mode 0)
		)
		(polygon
			(pts
				(arc
					(start 90.1192 -92.2528)
					(mid 90.047358 -92.282558)
					(end 90.0176 -92.3544)
				)
				(arc
					(start 90.0176 -93.5736)
					(mid 90.047358 -93.645442)
					(end 90.1192 -93.6752)
				)
				(arc
					(start 91.4908 -93.6752)
					(mid 91.562642 -93.645442)
					(end 91.5924 -93.5736)
				)
				(arc
					(start 91.5924 -92.3544)
					(mid 91.562642 -92.282558)
					(end 91.4908 -92.2528)
				)
			)
		)
	)
	(zone
		(layer "In1.Cu")
		(hatch none 0.5)
		(connect_pads
			(clearance 0)
		)
		(min_thickness 0.25)
		(keepout
			(tracks not_allowed)
			(vias allowed)
			(pads allowed)
			(copperpour not_allowed)
			(footprints allowed)
		)
		(placement
			(enabled no)
			(sheetname "")
		)
		(fill
			(thermal_gap 0.5)
			(thermal_bridge_width 0.5)
			(island_removal_mode 0)
		)
		(polygon
			(pts
				(arc
					(start 90.1192 -218.7448)
					(mid 90.047358 -218.774558)
					(end 90.0176 -218.8464)
				)
				(arc
					(start 90.0176 -220.0656)
					(mid 90.047358 -220.137442)
					(end 90.1192 -220.1672)
				)
				(arc
					(start 91.4908 -220.1672)
					(mid 91.562642 -220.137442)
					(end 91.5924 -220.0656)
				)
				(arc
					(start 91.5924 -218.8464)
					(mid 91.562642 -218.774558)
					(end 91.4908 -218.7448)
				)
			)
		)
	)
	(zone
		(layer "In1.Cu")
		(hatch none 0.5)
		(connect_pads
			(clearance 0)
		)
		(min_thickness 0.25)
		(keepout
			(tracks not_allowed)
			(vias allowed)
			(pads allowed)
			(copperpour not_allowed)
			(footprints allowed)
		)
		(placement
			(enabled no)
			(sheetname "")
		)
		(fill
			(thermal_gap 0.5)
			(thermal_bridge_width 0.5)
			(island_removal_mode 0)
		)
		(polygon
			(pts
				(arc
					(start 101.9048 -209.4738)
					(mid 101.934558 -209.545642)
					(end 102.0064 -209.5754)
				)
				(arc
					(start 103.2256 -209.5754)
					(mid 103.297442 -209.545642)
					(end 103.3272 -209.4738)
				)
				(arc
					(start 103.3272 -208.1022)
					(mid 103.297442 -208.030358)
					(end 103.2256 -208.0006)
				)
				(arc
					(start 102.0064 -208.0006)
					(mid 101.934558 -208.030358)
					(end 101.9048 -208.1022)
				)
			)
		)
	)
	(zone
		(layer "In1.Cu")
		(hatch none 0.5)
		(connect_pads
			(clearance 0)
		)
		(min_thickness 0.25)
		(keepout
			(tracks not_allowed)
			(vias allowed)
			(pads allowed)
			(copperpour not_allowed)
			(footprints allowed)
		)
		(placement
			(enabled no)
			(sheetname "")
		)
		(fill
			(thermal_gap 0.5)
			(thermal_bridge_width 0.5)
			(island_removal_mode 0)
		)
		(polygon
			(pts
				(xy 97.577148 -205.81239) (xy 96.383348 -205.81239) (xy 96.383348 -206.98079) (xy 97.577148 -206.98079)
			)
		)
	)
	(zone
		(layer "In1.Cu")
		(hatch none 0.5)
		(connect_pads
			(clearance 0)
		)
		(min_thickness 0.25)
		(keepout
			(tracks not_allowed)
			(vias allowed)
			(pads allowed)
			(copperpour not_allowed)
			(footprints allowed)
		)
		(placement
			(enabled no)
			(sheetname "")
		)
		(fill
			(thermal_gap 0.5)
			(thermal_bridge_width 0.5)
			(island_removal_mode 0)
		)
		(polygon
			(pts
				(xy 88.97239 -304.084736) (xy 88.97239 -305.277774) (xy 90.14079 -305.277774) (xy 90.14079 -304.084736)
			)
		)
	)
	(zone
		(layer "In1.Cu")
		(hatch none 0.5)
		(connect_pads
			(clearance 0)
		)
		(min_thickness 0.25)
		(keepout
			(tracks not_allowed)
			(vias allowed)
			(pads allowed)
			(copperpour not_allowed)
			(footprints allowed)
		)
		(placement
			(enabled no)
			(sheetname "")
		)
		(fill
			(thermal_gap 0.5)
			(thermal_bridge_width 0.5)
			(island_removal_mode 0)
		)
		(polygon
			(pts
				(arc
					(start 101.9048 -205.6638)
					(mid 101.934558 -205.735642)
					(end 102.0064 -205.7654)
				)
				(arc
					(start 103.2256 -205.7654)
					(mid 103.297442 -205.735642)
					(end 103.3272 -205.6638)
				)
				(arc
					(start 103.3272 -204.2922)
					(mid 103.297442 -204.220358)
					(end 103.2256 -204.1906)
				)
				(arc
					(start 102.0064 -204.1906)
					(mid 101.934558 -204.220358)
					(end 101.9048 -204.2922)
				)
			)
		)
	)
	(zone
		(layer "In1.Cu")
		(hatch none 0.5)
		(connect_pads
			(clearance 0)
		)
		(min_thickness 0.25)
		(keepout
			(tracks not_allowed)
			(vias allowed)
			(pads allowed)
			(copperpour not_allowed)
			(footprints allowed)
		)
		(placement
			(enabled no)
			(sheetname "")
		)
		(fill
			(thermal_gap 0.5)
			(thermal_bridge_width 0.5)
			(island_removal_mode 0)
		)
		(polygon
			(pts
				(arc
					(start 78.6384 -431.53076)
					(mid 78.564762 -431.561262)
					(end 78.53426 -431.6349)
				)
				(arc
					(start 78.53426 -431.9905)
					(mid 78.564762 -432.064138)
					(end 78.6384 -432.09464)
				)
				(arc
					(start 78.994 -432.09464)
					(mid 79.067638 -432.064138)
					(end 79.09814 -431.9905)
				)
				(arc
					(start 79.09814 -431.6349)
					(mid 79.067638 -431.561262)
					(end 78.994 -431.53076)
				)
			)
		)
	)
	(zone
		(layer "In1.Cu")
		(hatch none 0.5)
		(connect_pads
			(clearance 0)
		)
		(min_thickness 0.25)
		(keepout
			(tracks not_allowed)
			(vias allowed)
			(pads allowed)
			(copperpour not_allowed)
			(footprints allowed)
		)
		(placement
			(enabled no)
			(sheetname "")
		)
		(fill
			(thermal_gap 0.5)
			(thermal_bridge_width 0.5)
			(island_removal_mode 0)
		)
		(polygon
			(pts
				(arc
					(start 95.3262 -92.2528)
					(mid 95.254358 -92.282558)
					(end 95.2246 -92.3544)
				)
				(arc
					(start 95.2246 -93.5736)
					(mid 95.254358 -93.645442)
					(end 95.3262 -93.6752)
				)
				(arc
					(start 96.6978 -93.6752)
					(mid 96.769642 -93.645442)
					(end 96.7994 -93.5736)
				)
				(arc
					(start 96.7994 -92.3544)
					(mid 96.769642 -92.282558)
					(end 96.6978 -92.2528)
				)
			)
		)
	)
	(zone
		(layer "In1.Cu")
		(hatch none 0.5)
		(connect_pads
			(clearance 0)
		)
		(min_thickness 0.25)
		(keepout
			(tracks not_allowed)
			(vias allowed)
			(pads allowed)
			(copperpour not_allowed)
			(footprints allowed)
		)
		(placement
			(enabled no)
			(sheetname "")
		)
		(fill
			(thermal_gap 0.5)
			(thermal_bridge_width 0.5)
			(island_removal_mode 0)
		)
		(polygon
			(pts
				(arc
					(start 13.632688 -426.503592)
					(mid 13.662446 -426.575434)
					(end 13.734288 -426.605192)
				)
				(arc
					(start 15.029688 -426.605192)
					(mid 15.10153 -426.575434)
					(end 15.131288 -426.503592)
				)
				(arc
					(start 15.131288 -425.182792)
					(mid 15.10153 -425.11095)
					(end 15.029688 -425.081192)
				)
				(arc
					(start 13.734288 -425.081192)
					(mid 13.662446 -425.11095)
					(end 13.632688 -425.182792)
				)
			)
		)
	)
	(zone
		(layer "In1.Cu")
		(hatch none 0.5)
		(connect_pads
			(clearance 0)
		)
		(min_thickness 0.25)
		(keepout
			(tracks not_allowed)
			(vias allowed)
			(pads allowed)
			(copperpour not_allowed)
			(footprints allowed)
		)
		(placement
			(enabled no)
			(sheetname "")
		)
		(fill
			(thermal_gap 0.5)
			(thermal_bridge_width 0.5)
			(island_removal_mode 0)
		)
		(polygon
			(pts
				(xy 98.98761 -210.416648) (xy 98.98761 -209.222594) (xy 97.81921 -209.222594) (xy 97.81921 -210.416648)
			)
		)
	)
	(zone
		(layer "In1.Cu")
		(hatch none 0.5)
		(connect_pads
			(clearance 0)
		)
		(min_thickness 0.25)
		(keepout
			(tracks not_allowed)
			(vias allowed)
			(pads allowed)
			(copperpour not_allowed)
			(footprints allowed)
		)
		(placement
			(enabled no)
			(sheetname "")
		)
		(fill
			(thermal_gap 0.5)
			(thermal_bridge_width 0.5)
			(island_removal_mode 0)
		)
		(polygon
			(pts
				(xy 91.076272 -435.63921) (xy 89.892632 -435.63921) (xy 89.892632 -436.80761) (xy 91.076272 -436.80761)
			)
		)
	)
	(zone
		(layer "In1.Cu")
		(hatch none 0.5)
		(connect_pads
			(clearance 0)
		)
		(min_thickness 0.25)
		(keepout
			(tracks not_allowed)
			(vias allowed)
			(pads allowed)
			(copperpour not_allowed)
			(footprints allowed)
		)
		(placement
			(enabled no)
			(sheetname "")
		)
		(fill
			(thermal_gap 0.5)
			(thermal_bridge_width 0.5)
			(island_removal_mode 0)
		)
		(polygon
			(pts
				(arc
					(start 101.9048 -434.5178)
					(mid 101.934558 -434.589642)
					(end 102.0064 -434.6194)
				)
				(arc
					(start 103.2256 -434.6194)
					(mid 103.297442 -434.589642)
					(end 103.3272 -434.5178)
				)
				(arc
					(start 103.3272 -433.1462)
					(mid 103.297442 -433.074358)
					(end 103.2256 -433.0446)
				)
				(arc
					(start 102.0064 -433.0446)
					(mid 101.934558 -433.074358)
					(end 101.9048 -433.1462)
				)
			)
		)
	)
	(zone
		(layer "In1.Cu")
		(hatch none 0.5)
		(connect_pads
			(clearance 0)
		)
		(min_thickness 0.25)
		(keepout
			(tracks not_allowed)
			(vias allowed)
			(pads allowed)
			(copperpour not_allowed)
			(footprints allowed)
		)
		(placement
			(enabled no)
			(sheetname "")
		)
		(fill
			(thermal_gap 0.5)
			(thermal_bridge_width 0.5)
			(island_removal_mode 0)
		)
		(polygon
			(pts
				(arc
					(start 99.1362 -109.5248)
					(mid 99.064358 -109.554558)
					(end 99.0346 -109.6264)
				)
				(arc
					(start 99.0346 -110.8456)
					(mid 99.064358 -110.917442)
					(end 99.1362 -110.9472)
				)
				(arc
					(start 100.5078 -110.9472)
					(mid 100.579642 -110.917442)
					(end 100.6094 -110.8456)
				)
				(arc
					(start 100.6094 -109.6264)
					(mid 100.579642 -109.554558)
					(end 100.5078 -109.5248)
				)
			)
		)
	)
	(zone
		(layer "In1.Cu")
		(hatch none 0.5)
		(connect_pads
			(clearance 0)
		)
		(min_thickness 0.25)
		(keepout
			(tracks not_allowed)
			(vias allowed)
			(pads allowed)
			(copperpour not_allowed)
			(footprints allowed)
		)
		(placement
			(enabled no)
			(sheetname "")
		)
		(fill
			(thermal_gap 0.5)
			(thermal_bridge_width 0.5)
			(island_removal_mode 0)
		)
		(polygon
			(pts
				(arc
					(start 85.70214 -210.4771)
					(mid 85.686517 -210.439383)
					(end 85.6488 -210.42376)
				)
				(arc
					(start 85.4456 -210.42376)
					(mid 85.407883 -210.439383)
					(end 85.39226 -210.4771)
				)
				(arc
					(start 85.39226 -210.7311)
					(mid 85.407883 -210.768817)
					(end 85.4456 -210.78444)
				)
				(arc
					(start 85.6488 -210.78444)
					(mid 85.686517 -210.768817)
					(end 85.70214 -210.7311)
				)
			)
		)
	)
	(zone
		(layer "In1.Cu")
		(hatch none 0.5)
		(connect_pads
			(clearance 0)
		)
		(min_thickness 0.25)
		(keepout
			(tracks not_allowed)
			(vias allowed)
			(pads allowed)
			(copperpour not_allowed)
			(footprints allowed)
		)
		(placement
			(enabled no)
			(sheetname "")
		)
		(fill
			(thermal_gap 0.5)
			(thermal_bridge_width 0.5)
			(island_removal_mode 0)
		)
		(polygon
			(pts
				(xy 94.383352 -215.82761) (xy 95.576136 -215.82761) (xy 95.576136 -214.65921) (xy 94.383352 -214.65921)
			)
		)
	)
	(zone
		(layer "In1.Cu")
		(hatch none 0.5)
		(connect_pads
			(clearance 0)
		)
		(min_thickness 0.25)
		(keepout
			(tracks not_allowed)
			(vias allowed)
			(pads allowed)
			(copperpour not_allowed)
			(footprints allowed)
		)
		(placement
			(enabled no)
			(sheetname "")
		)
		(fill
			(thermal_gap 0.5)
			(thermal_bridge_width 0.5)
			(island_removal_mode 0)
		)
		(polygon
			(pts
				(arc
					(start 95.3262 -313.1058)
					(mid 95.254358 -313.135558)
					(end 95.2246 -313.2074)
				)
				(arc
					(start 95.2246 -314.4266)
					(mid 95.254358 -314.498442)
					(end 95.3262 -314.5282)
				)
				(arc
					(start 96.6978 -314.5282)
					(mid 96.769642 -314.498442)
					(end 96.7994 -314.4266)
				)
				(arc
					(start 96.7994 -313.2074)
					(mid 96.769642 -313.135558)
					(end 96.6978 -313.1058)
				)
			)
		)
	)
	(zone
		(layer "In1.Cu")
		(hatch none 0.5)
		(connect_pads
			(clearance 0)
		)
		(min_thickness 0.25)
		(keepout
			(tracks not_allowed)
			(vias allowed)
			(pads allowed)
			(copperpour not_allowed)
			(footprints allowed)
		)
		(placement
			(enabled no)
			(sheetname "")
		)
		(fill
			(thermal_gap 0.5)
			(thermal_bridge_width 0.5)
			(island_removal_mode 0)
		)
		(polygon
			(pts
				(arc
					(start 99.1362 -295.8338)
					(mid 99.064358 -295.863558)
					(end 99.0346 -295.9354)
				)
				(arc
					(start 99.0346 -297.1546)
					(mid 99.064358 -297.226442)
					(end 99.1362 -297.2562)
				)
				(arc
					(start 100.5078 -297.2562)
					(mid 100.579642 -297.226442)
					(end 100.6094 -297.1546)
				)
				(arc
					(start 100.6094 -295.9354)
					(mid 100.579642 -295.863558)
					(end 100.5078 -295.8338)
				)
			)
		)
	)
	(zone
		(layer "In1.Cu")
		(hatch none 0.5)
		(connect_pads
			(clearance 0)
		)
		(min_thickness 0.25)
		(keepout
			(tracks not_allowed)
			(vias allowed)
			(pads allowed)
			(copperpour not_allowed)
			(footprints allowed)
		)
		(placement
			(enabled no)
			(sheetname "")
		)
		(fill
			(thermal_gap 0.5)
			(thermal_bridge_width 0.5)
			(island_removal_mode 0)
		)
		(polygon
			(pts
				(arc
					(start 99.1362 -92.2528)
					(mid 99.064358 -92.282558)
					(end 99.0346 -92.3544)
				)
				(arc
					(start 99.0346 -93.5736)
					(mid 99.064358 -93.645442)
					(end 99.1362 -93.6752)
				)
				(arc
					(start 100.5078 -93.6752)
					(mid 100.579642 -93.645442)
					(end 100.6094 -93.5736)
				)
				(arc
					(start 100.6094 -92.3544)
					(mid 100.579642 -92.282558)
					(end 100.5078 -92.2528)
				)
			)
		)
	)
	(zone
		(layer "In1.Cu")
		(hatch none 0.5)
		(connect_pads
			(clearance 0)
		)
		(min_thickness 0.25)
		(keepout
			(tracks not_allowed)
			(vias allowed)
			(pads allowed)
			(copperpour not_allowed)
			(footprints allowed)
		)
		(placement
			(enabled no)
			(sheetname "")
		)
		(fill
			(thermal_gap 0.5)
			(thermal_bridge_width 0.5)
			(island_removal_mode 0)
		)
		(polygon
			(pts
				(arc
					(start 77.597 -430.48936)
					(mid 77.523362 -430.519862)
					(end 77.49286 -430.5935)
				)
				(arc
					(start 77.49286 -430.9491)
					(mid 77.523362 -431.022738)
					(end 77.597 -431.05324)
				)
				(arc
					(start 77.9526 -431.05324)
					(mid 78.026238 -431.022738)
					(end 78.05674 -430.9491)
				)
				(arc
					(start 78.05674 -430.5935)
					(mid 78.026238 -430.519862)
					(end 77.9526 -430.48936)
				)
			)
		)
	)
	(zone
		(layer "In1.Cu")
		(hatch none 0.5)
		(connect_pads
			(clearance 0)
		)
		(min_thickness 0.25)
		(keepout
			(tracks not_allowed)
			(vias allowed)
			(pads allowed)
			(copperpour not_allowed)
			(footprints allowed)
		)
		(placement
			(enabled no)
			(sheetname "")
		)
		(fill
			(thermal_gap 0.5)
			(thermal_bridge_width 0.5)
			(island_removal_mode 0)
		)
		(polygon
			(pts
				(arc
					(start 101.9048 -438.3278)
					(mid 101.934558 -438.399642)
					(end 102.0064 -438.4294)
				)
				(arc
					(start 103.2256 -438.4294)
					(mid 103.297442 -438.399642)
					(end 103.3272 -438.3278)
				)
				(arc
					(start 103.3272 -436.9562)
					(mid 103.297442 -436.884358)
					(end 103.2256 -436.8546)
				)
				(arc
					(start 102.0064 -436.8546)
					(mid 101.934558 -436.884358)
					(end 101.9048 -436.9562)
				)
			)
		)
	)
	(zone
		(layer "In1.Cu")
		(hatch none 0.5)
		(connect_pads
			(clearance 0)
		)
		(min_thickness 0.25)
		(keepout
			(tracks not_allowed)
			(vias allowed)
			(pads allowed)
			(copperpour not_allowed)
			(footprints allowed)
		)
		(placement
			(enabled no)
			(sheetname "")
		)
		(fill
			(thermal_gap 0.5)
			(thermal_bridge_width 0.5)
			(island_removal_mode 0)
		)
		(polygon
			(pts
				(xy 98.98761 -435.395116) (xy 98.98761 -434.203856) (xy 97.81921 -434.203856) (xy 97.81921 -435.395116)
			)
		)
	)
	(zone
		(layer "In1.Cu")
		(hatch none 0.5)
		(connect_pads
			(clearance 0)
		)
		(min_thickness 0.25)
		(keepout
			(tracks not_allowed)
			(vias allowed)
			(pads allowed)
			(copperpour not_allowed)
			(footprints allowed)
		)
		(placement
			(enabled no)
			(sheetname "")
		)
		(fill
			(thermal_gap 0.5)
			(thermal_bridge_width 0.5)
			(island_removal_mode 0)
		)
		(polygon
			(pts
				(arc
					(start 78.2066 -210.56346)
					(mid 78.132962 -210.593962)
					(end 78.10246 -210.6676)
				)
				(arc
					(start 78.10246 -211.0232)
					(mid 78.132962 -211.096838)
					(end 78.2066 -211.12734)
				)
				(arc
					(start 78.5622 -211.12734)
					(mid 78.635838 -211.096838)
					(end 78.66634 -211.0232)
				)
				(arc
					(start 78.66634 -210.6676)
					(mid 78.635838 -210.593962)
					(end 78.5622 -210.56346)
				)
			)
		)
	)
	(zone
		(layer "In1.Cu")
		(hatch none 0.5)
		(connect_pads
			(clearance 0)
		)
		(min_thickness 0.25)
		(keepout
			(tracks not_allowed)
			(vias allowed)
			(pads allowed)
			(copperpour not_allowed)
			(footprints allowed)
		)
		(placement
			(enabled no)
			(sheetname "")
		)
		(fill
			(thermal_gap 0.5)
			(thermal_bridge_width 0.5)
			(island_removal_mode 0)
		)
		(polygon
			(pts
				(xy 95.577152 -96.59239) (xy 94.383098 -96.59239) (xy 94.383098 -97.76079) (xy 95.577152 -97.76079)
			)
		)
	)
	(zone
		(layer "In1.Cu")
		(hatch none 0.5)
		(connect_pads
			(clearance 0)
		)
		(min_thickness 0.25)
		(keepout
			(tracks not_allowed)
			(vias allowed)
			(pads allowed)
			(copperpour not_allowed)
			(footprints allowed)
		)
		(placement
			(enabled no)
			(sheetname "")
		)
		(fill
			(thermal_gap 0.5)
			(thermal_bridge_width 0.5)
			(island_removal_mode 0)
		)
		(polygon
			(pts
				(arc
					(start 77.6732 -102.03434)
					(mid 77.746838 -102.003838)
					(end 77.77734 -101.9302)
				)
				(arc
					(start 77.77734 -101.5746)
					(mid 77.746838 -101.500962)
					(end 77.6732 -101.47046)
				)
				(arc
					(start 77.3176 -101.47046)
					(mid 77.243962 -101.500962)
					(end 77.21346 -101.5746)
				)
				(arc
					(start 77.21346 -101.9302)
					(mid 77.243962 -102.003838)
					(end 77.3176 -102.03434)
				)
			)
		)
	)
	(zone
		(net "GND")
		(layer "In1.Cu")
		(hatch none 0.5)
		(connect_pads
			(clearance 0.5)
		)
		(min_thickness 0.25)
		(fill yes
			(thermal_gap 0.5)
			(thermal_bridge_width 0.5)
			(island_removal_mode 0)
		)
		(polygon
			(pts
				(arc
					(start 0.999998 -0.763016)
					(mid 0.832426 -0.832426)
					(end 0.763016 -0.999998)
				)
				(xy 0.763016 -186.42584) (xy 0.816102 -186.478926)
				(arc
					(start 4.400042 -186.478926)
					(mid 6.263132 -188.342016)
					(end 4.400042 -190.205106)
				)
				(xy 0.816102 -190.205106) (xy 0.763016 -190.258192) (xy 0.763016 -312.425842) (xy 0.816102 -312.478928)
				(arc
					(start 4.400042 -312.478928)
					(mid 6.263132 -314.342018)
					(end 4.400042 -316.205108)
				)
				(xy 0.816102 -316.205108) (xy 0.763016 -316.258194) (xy 0.763016 -418.425884) (xy 0.816102 -418.47897)
				(arc
					(start 4.400042 -418.47897)
					(mid 6.263132 -420.34206)
					(end 4.400042 -422.204896)
				)
				(xy 0.816356 -422.204896) (xy 0.763016 -422.258236)
				(arc
					(start 0.763016 -505.000006)
					(mid 0.832426 -505.167578)
					(end 0.999998 -505.236988)
				)
				(arc
					(start 262.50011 -505.236988)
					(mid 262.667682 -505.167578)
					(end 262.737092 -505.000006)
				)
				(xy 262.737092 -428.396146) (xy 262.18388 -427.842934)
				(arc
					(start 261.2898 -427.842934)
					(mid 259.767467 -427.212363)
					(end 259.136896 -425.69003)
				)
				(xy 259.136896 -411.80131) (xy 258.583684 -411.248098)
				(arc
					(start 252.394974 -411.248098)
					(mid 251.097034 -409.950158)
					(end 252.394974 -408.651964)
				)
				(xy 258.583684 -408.651964) (xy 259.136896 -408.098752)
				(arc
					(start 259.136896 -364.309914)
					(mid 259.767541 -362.787655)
					(end 261.2898 -362.15701)
				)
				(xy 262.18388 -362.15701) (xy 262.737092 -361.603798)
				(arc
					(start 262.737092 -0.999998)
					(mid 262.667682 -0.832426)
					(end 262.50011 -0.763016)
				)
				(xy 37.667692 -0.763016)
				(arc
					(start 36.343336 -3.365754)
					(mid 36.283478 -3.527891)
					(end 36.263072 -3.69951)
				)
				(arc
					(start 36.263072 -4.500118)
					(mid 34.000186 -6.763004)
					(end 31.737046 -4.500118)
				)
				(arc
					(start 31.737046 -3.700018)
					(mid 31.716858 -3.528435)
					(end 31.65729 -3.366262)
				)
				(xy 31.657036 -3.366262) (xy 30.332426 -0.763016)
			)
		)
		(polygon
			(pts
				(xy 225.203004 -490.844078) (xy 223.196658 -490.844078) (xy 223.196658 -492.736124) (xy 225.203258 -492.736124)
				(xy 225.203258 -490.844332)
			)
		)
		(polygon
			(pts
				(xy 40.20312 -490.844078) (xy 38.196774 -490.844078) (xy 38.196774 -492.736124) (xy 40.203374 -492.736124)
				(xy 40.203374 -490.844332)
			)
		)
		(polygon
			(pts
				(arc
					(start 37.33927 -491.231428)
					(mid 36.72713 -490.619288)
					(end 36.11499 -491.231428)
				)
				(arc
					(start 36.11499 -492.349282)
					(mid 36.727257 -492.961168)
					(end 37.33927 -492.349028)
				)
			)
		)
		(polygon
			(pts
				(arc
					(start 222.339154 -491.231174)
					(mid 221.726887 -490.619288)
					(end 221.114874 -491.231428)
				)
				(arc
					(start 221.114874 -492.349028)
					(mid 221.727014 -492.961168)
					(end 222.339154 -492.349028)
				)
			)
		)
		(polygon
			(pts
				(arc
					(start 35.84067 -488.983782)
					(mid 35.33013 -488.473242)
					(end 34.81959 -488.983782)
				)
				(arc
					(start 34.81959 -489.796836)
					(mid 35.330257 -490.307122)
					(end 35.84067 -489.796582)
				)
			)
		)
		(polygon
			(pts
				(arc
					(start 220.840554 -488.983528)
					(mid 220.329887 -488.473242)
					(end 219.819474 -488.983782)
				)
				(arc
					(start 219.819474 -489.796582)
					(mid 220.330014 -490.307122)
					(end 220.840554 -489.796582)
				)
			)
		)
		(polygon
			(pts
				(xy 225.203004 -488.444032) (xy 223.196658 -488.444032) (xy 223.196658 -490.336332) (xy 225.203258 -490.336332)
				(xy 225.203258 -488.444286)
			)
		)
		(polygon
			(pts
				(xy 40.20312 -488.444032) (xy 38.196774 -488.444032) (xy 38.196774 -490.336332) (xy 40.203374 -490.336332)
				(xy 40.203374 -488.444286)
			)
		)
		(polygon
			(pts
				(xy 225.203004 -486.043986) (xy 223.196658 -486.043986) (xy 223.196658 -487.936286) (xy 225.203258 -487.936286)
				(xy 225.203258 -486.04424)
			)
		)
		(polygon
			(pts
				(xy 40.20312 -486.043986) (xy 38.196774 -486.043986) (xy 38.196774 -487.936286) (xy 40.203374 -487.936286)
				(xy 40.203374 -486.04424)
			)
		)
		(polygon
			(pts
				(arc
					(start 222.339154 -486.431082)
					(mid 221.726887 -485.819196)
					(end 221.114874 -486.431336)
				)
				(arc
					(start 221.114874 -487.548936)
					(mid 221.727014 -488.161076)
					(end 222.339154 -487.548936)
				)
			)
		)
		(polygon
			(pts
				(arc
					(start 37.33927 -486.431082)
					(mid 36.727003 -485.819196)
					(end 36.11499 -486.431336)
				)
				(arc
					(start 36.11499 -487.548936)
					(mid 36.72713 -488.161076)
					(end 37.33927 -487.548936)
				)
			)
		)
		(polygon
			(pts
				(arc
					(start 35.84067 -484.18369)
					(mid 35.33013 -483.67315)
					(end 34.81959 -484.18369)
				)
				(arc
					(start 34.81959 -484.996744)
					(mid 35.330257 -485.50703)
					(end 35.84067 -484.99649)
				)
			)
		)
		(polygon
			(pts
				(arc
					(start 220.840554 -484.183436)
					(mid 220.329887 -483.67315)
					(end 219.819474 -484.18369)
				)
				(arc
					(start 219.819474 -484.99649)
					(mid 220.330014 -485.50703)
					(end 220.840554 -484.99649)
				)
			)
		)
		(polygon
			(pts
				(xy 225.203258 -483.64394) (xy 223.196658 -483.64394) (xy 223.196658 -485.535986) (xy 223.196912 -485.53624)
				(xy 225.203258 -485.53624)
			)
		)
		(polygon
			(pts
				(xy 40.203374 -483.64394) (xy 38.196774 -483.64394) (xy 38.196774 -485.535986) (xy 38.197028 -485.53624)
				(xy 40.203374 -485.53624)
			)
		)
		(polygon
			(pts
				(xy 225.203004 -481.243894) (xy 223.196658 -481.243894) (xy 223.196658 -483.136194) (xy 225.203258 -483.136194)
				(xy 225.203258 -481.244148)
			)
		)
		(polygon
			(pts
				(xy 40.20312 -481.243894) (xy 38.196774 -481.243894) (xy 38.196774 -483.136194) (xy 40.203374 -483.136194)
				(xy 40.203374 -481.244148)
			)
		)
		(polygon
			(pts
				(arc
					(start 37.33927 -481.631244)
					(mid 36.72713 -481.019104)
					(end 36.11499 -481.631244)
				)
				(arc
					(start 36.11499 -482.749098)
					(mid 36.727257 -483.360984)
					(end 37.33927 -482.748844)
				)
			)
		)
		(polygon
			(pts
				(arc
					(start 222.339154 -481.63099)
					(mid 221.726887 -481.019104)
					(end 221.114874 -481.631244)
				)
				(arc
					(start 221.114874 -482.748844)
					(mid 221.727014 -483.360984)
					(end 222.339154 -482.748844)
				)
			)
		)
		(polygon
			(pts
				(arc
					(start 35.84067 -479.383852)
					(mid 35.33013 -478.873312)
					(end 34.81959 -479.383852)
				)
				(arc
					(start 34.81959 -480.196906)
					(mid 35.330257 -480.707192)
					(end 35.84067 -480.196652)
				)
			)
		)
		(polygon
			(pts
				(arc
					(start 220.840554 -479.383598)
					(mid 220.329887 -478.873312)
					(end 219.819474 -479.383852)
				)
				(arc
					(start 219.819474 -480.196652)
					(mid 220.330014 -480.707192)
					(end 220.840554 -480.196652)
				)
			)
		)
		(polygon
			(pts
				(xy 225.203004 -478.844102) (xy 223.196658 -478.844102) (xy 223.196658 -480.736148) (xy 225.203258 -480.736148)
				(xy 225.203258 -478.844356)
			)
		)
		(polygon
			(pts
				(xy 40.20312 -478.844102) (xy 38.196774 -478.844102) (xy 38.196774 -480.736148) (xy 40.203374 -480.736148)
				(xy 40.203374 -478.844356)
			)
		)
		(polygon
			(pts
				(arc
					(start 233.897424 -472.579446)
					(mid 233.386884 -472.068906)
					(end 232.876344 -472.579446)
				)
				(arc
					(start 232.876344 -473.3925)
					(mid 233.387011 -473.902786)
					(end 233.897424 -473.392246)
				)
			)
		)
		(polygon
			(pts
				(arc
					(start 48.89754 -472.579192)
					(mid 48.386873 -472.068906)
					(end 47.87646 -472.579446)
				)
				(arc
					(start 47.87646 -473.392246)
					(mid 48.387 -473.902786)
					(end 48.89754 -473.392246)
				)
			)
		)
		(polygon
			(pts
				(xy 228.39299 -472.044014) (xy 226.386644 -472.044014) (xy 226.386644 -473.936314) (xy 228.393244 -473.936314)
				(xy 228.393244 -472.044268)
			)
		)
		(polygon
			(pts
				(xy 43.393106 -472.044014) (xy 41.38676 -472.044014) (xy 41.38676 -473.936314) (xy 43.39336 -473.936314)
				(xy 43.39336 -472.044268)
			)
		)
		(polygon
			(pts
				(arc
					(start 230.720138 -472.300808)
					(mid 231.230424 -471.790141)
					(end 230.719884 -471.279728)
				)
				(arc
					(start 229.907084 -471.279728)
					(mid 229.396544 -471.790268)
					(end 229.907084 -472.300808)
				)
			)
		)
		(polygon
			(pts
				(arc
					(start 45.720254 -472.300808)
					(mid 46.23054 -471.790141)
					(end 45.72 -471.279728)
				)
				(arc
					(start 44.9072 -471.279728)
					(mid 44.39666 -471.790268)
					(end 44.9072 -472.300808)
				)
			)
		)
		(polygon
			(pts
				(xy 225.203004 -468.444072) (xy 223.196658 -468.444072) (xy 223.196658 -470.336118) (xy 225.203258 -470.336118)
				(xy 225.203258 -468.444326)
			)
		)
		(polygon
			(pts
				(xy 40.20312 -468.444072) (xy 38.196774 -468.444072) (xy 38.196774 -470.336118) (xy 40.203374 -470.336118)
				(xy 40.203374 -468.444326)
			)
		)
		(polygon
			(pts
				(arc
					(start 37.33927 -468.831422)
					(mid 36.72713 -468.219282)
					(end 36.11499 -468.831422)
				)
				(arc
					(start 36.11499 -469.949276)
					(mid 36.727257 -470.561162)
					(end 37.33927 -469.949022)
				)
			)
		)
		(polygon
			(pts
				(arc
					(start 222.339154 -468.831168)
					(mid 221.726887 -468.219282)
					(end 221.114874 -468.831422)
				)
				(arc
					(start 221.114874 -469.949022)
					(mid 221.727014 -470.561162)
					(end 222.339154 -469.949022)
				)
			)
		)
		(polygon
			(pts
				(arc
					(start 35.84067 -466.583776)
					(mid 35.33013 -466.073236)
					(end 34.81959 -466.583776)
				)
				(arc
					(start 34.81959 -467.39683)
					(mid 35.330257 -467.907116)
					(end 35.84067 -467.396576)
				)
			)
		)
		(polygon
			(pts
				(arc
					(start 220.840554 -466.583522)
					(mid 220.329887 -466.073236)
					(end 219.819474 -466.583776)
				)
				(arc
					(start 219.819474 -467.396576)
					(mid 220.330014 -467.907116)
					(end 220.840554 -467.396576)
				)
			)
		)
		(polygon
			(pts
				(xy 225.203004 -466.044026) (xy 223.196658 -466.044026) (xy 223.196658 -467.936326) (xy 225.203258 -467.936326)
				(xy 225.203258 -466.04428)
			)
		)
		(polygon
			(pts
				(xy 40.20312 -466.044026) (xy 38.196774 -466.044026) (xy 38.196774 -467.936326) (xy 40.203374 -467.936326)
				(xy 40.203374 -466.04428)
			)
		)
		(polygon
			(pts
				(xy 225.203004 -463.64398) (xy 223.196658 -463.64398) (xy 223.196658 -465.53628) (xy 225.203258 -465.53628)
				(xy 225.203258 -463.644234)
			)
		)
		(polygon
			(pts
				(xy 40.20312 -463.64398) (xy 38.196774 -463.64398) (xy 38.196774 -465.53628) (xy 40.203374 -465.53628)
				(xy 40.203374 -463.644234)
			)
		)
		(polygon
			(pts
				(xy 23.803356 -452.463916) (xy 21.796756 -452.463916) (xy 21.796756 -454.355962) (xy 21.79701 -454.356216)
				(xy 23.803356 -454.356216)
			)
		)
		(polygon
			(pts
				(arc
					(start 8.6868 -450.7357)
					(mid 8.657042 -450.663858)
					(end 8.5852 -450.6341)
				)
				(arc
					(start 7.2644 -450.6341)
					(mid 7.192558 -450.663858)
					(end 7.1628 -450.7357)
				)
				(arc
					(start 7.1628 -452.0311)
					(mid 7.192558 -452.102942)
					(end 7.2644 -452.1327)
				)
				(arc
					(start 8.5852 -452.1327)
					(mid 8.657042 -452.102942)
					(end 8.6868 -452.0311)
				)
			)
		)
		(polygon
			(pts
				(arc
					(start 27.18054 -450.603366)
					(mid 26.669873 -450.09308)
					(end 26.15946 -450.60362)
				)
				(arc
					(start 26.15946 -451.41642)
					(mid 26.67 -451.92696)
					(end 27.18054 -451.41642)
				)
			)
		)
		(polygon
			(pts
				(xy 23.803356 -450.06387) (xy 21.796756 -450.06387) (xy 21.796756 -451.955916) (xy 21.79701 -451.95617)
				(xy 23.803356 -451.95617)
			)
		)
		(polygon
			(pts
				(arc
					(start 7.2898 -449.978272)
					(mid 7.80034 -449.467732)
					(end 7.2898 -448.957192)
				)
				(arc
					(start 6.476746 -448.957192)
					(mid 5.96646 -449.467859)
					(end 6.477 -449.978272)
				)
			)
		)
		(polygon
			(pts
				(xy 3.494532 -448.4878) (xy 1.005332 -448.4878) (xy 1.005332 -449.7959) (xy 3.494532 -449.7959)
			)
		)
		(polygon
			(pts
				(xy 23.803356 -447.664078) (xy 21.796756 -447.664078) (xy 21.796756 -449.55587) (xy 21.79701 -449.556124)
				(xy 23.803356 -449.556124)
			)
		)
		(polygon
			(pts
				(arc
					(start 25.88514 -448.05092)
					(mid 25.272873 -447.439034)
					(end 24.66086 -448.051174)
				)
				(arc
					(start 24.66086 -449.168774)
					(mid 25.273 -449.780914)
					(end 25.88514 -449.168774)
				)
			)
		)
		(polygon
			(pts
				(xy 3.494532 -446.088008) (xy 1.005332 -446.088008) (xy 1.005332 -447.395854) (xy 3.494532 -447.395854)
			)
		)
		(polygon
			(pts
				(arc
					(start 7.502906 -446.384172)
					(mid 6.992366 -445.873632)
					(end 6.481826 -446.384172)
				)
				(arc
					(start 6.481826 -447.197226)
					(mid 6.992493 -447.707512)
					(end 7.502906 -447.196972)
				)
			)
		)
		(polygon
			(pts
				(arc
					(start 5.59054 -444.735204)
					(mid 5.08 -444.224664)
					(end 4.56946 -444.735204)
				)
				(arc
					(start 4.56946 -445.548258)
					(mid 5.080127 -446.058544)
					(end 5.59054 -445.548004)
				)
			)
		)
		(polygon
			(pts
				(arc
					(start 17.78254 -444.603378)
					(mid 17.272 -444.092838)
					(end 16.76146 -444.603378)
				)
				(arc
					(start 16.76146 -445.416432)
					(mid 17.272127 -445.926718)
					(end 17.78254 -445.416178)
				)
			)
		)
		(polygon
			(pts
				(arc
					(start 32.26054 -444.584582)
					(mid 31.749873 -444.074296)
					(end 31.23946 -444.584836)
				)
				(arc
					(start 31.23946 -445.397636)
					(mid 31.75 -445.908176)
					(end 32.26054 -445.397636)
				)
			)
		)
		(polygon
			(pts
				(xy 20.61337 -444.063882) (xy 18.60677 -444.063882) (xy 18.60677 -445.955928) (xy 18.607024 -445.956182)
				(xy 20.61337 -445.956182)
			)
		)
		(polygon
			(pts
				(xy 3.494532 -442.887862) (xy 1.005332 -442.887862) (xy 1.005332 -444.195962) (xy 3.494532 -444.195962)
			)
		)
		(polygon
			(pts
				(arc
					(start 7.502906 -443.18428)
					(mid 6.992366 -442.67374)
					(end 6.481826 -443.18428)
				)
				(arc
					(start 6.481826 -443.997334)
					(mid 6.992493 -444.50762)
					(end 7.502906 -443.99708)
				)
			)
		)
		(polygon
			(pts
				(arc
					(start 5.59054 -441.535312)
					(mid 5.08 -441.024772)
					(end 4.56946 -441.535312)
				)
				(arc
					(start 4.56946 -442.348366)
					(mid 5.080127 -442.858652)
					(end 5.59054 -442.348112)
				)
			)
		)
		(polygon
			(pts
				(arc
					(start 91.5924 -439.8264)
					(mid 91.562642 -439.754558)
					(end 91.4908 -439.7248)
				)
				(arc
					(start 90.1192 -439.7248)
					(mid 90.047358 -439.754558)
					(end 90.0176 -439.8264)
				)
				(arc
					(start 90.0176 -441.0456)
					(mid 90.047358 -441.117442)
					(end 90.1192 -441.1472)
				)
				(arc
					(start 91.4908 -441.1472)
					(mid 91.562642 -441.117442)
					(end 91.5924 -441.0456)
				)
			)
		)
		(polygon
			(pts
				(arc
					(start 87.7824 -439.8264)
					(mid 87.752642 -439.754558)
					(end 87.6808 -439.7248)
				)
				(arc
					(start 86.3092 -439.7248)
					(mid 86.237358 -439.754558)
					(end 86.2076 -439.8264)
				)
				(arc
					(start 86.2076 -441.0456)
					(mid 86.237358 -441.117442)
					(end 86.3092 -441.1472)
				)
				(arc
					(start 87.6808 -441.1472)
					(mid 87.752642 -441.117442)
					(end 87.7824 -441.0456)
				)
			)
		)
		(polygon
			(pts
				(xy 3.494532 -439.68797) (xy 1.005332 -439.68797) (xy 1.005332 -440.995816) (xy 3.494532 -440.995816)
			)
		)
		(polygon
			(pts
				(arc
					(start 7.502906 -439.984134)
					(mid 6.992366 -439.473594)
					(end 6.481826 -439.984134)
				)
				(arc
					(start 6.481826 -440.797188)
					(mid 6.992493 -441.307474)
					(end 7.502906 -440.796934)
				)
			)
		)
		(polygon
			(pts
				(arc
					(start 5.59054 -438.335166)
					(mid 5.08 -437.824626)
					(end 4.56946 -438.335166)
				)
				(arc
					(start 4.56946 -439.14822)
					(mid 5.080127 -439.658506)
					(end 5.59054 -439.147966)
				)
			)
		)
		(polygon
			(pts
				(arc
					(start 27.18054 -437.80329)
					(mid 26.669873 -437.293004)
					(end 26.15946 -437.803544)
				)
				(arc
					(start 26.15946 -438.616344)
					(mid 26.67 -439.126884)
					(end 27.18054 -438.616344)
				)
			)
		)
		(polygon
			(pts
				(xy 23.803356 -437.264048) (xy 21.796756 -437.264048) (xy 21.796756 -439.15584) (xy 21.79701 -439.156094)
				(xy 23.803356 -439.156094)
			)
		)
		(polygon
			(pts
				(arc
					(start 103.3272 -436.9562)
					(mid 103.297442 -436.884358)
					(end 103.2256 -436.8546)
				)
				(arc
					(start 102.0064 -436.8546)
					(mid 101.934558 -436.884358)
					(end 101.9048 -436.9562)
				)
				(arc
					(start 101.9048 -438.3278)
					(mid 101.934558 -438.399642)
					(end 102.0064 -438.4294)
				)
				(arc
					(start 103.2256 -438.4294)
					(mid 103.297442 -438.399642)
					(end 103.3272 -438.3278)
				)
			)
		)
		(polygon
			(pts
				(xy 3.494532 -436.487824) (xy 1.005332 -436.487824) (xy 1.005332 -437.795924) (xy 3.494532 -437.795924)
			)
		)
		(polygon
			(pts
				(arc
					(start 7.502906 -436.784242)
					(mid 6.992366 -436.273702)
					(end 6.481826 -436.784242)
				)
				(arc
					(start 6.481826 -437.597296)
					(mid 6.992493 -438.107582)
					(end 7.502906 -437.597042)
				)
			)
		)
		(polygon
			(pts
				(xy 93.074744 -435.63921) (xy 91.883738 -435.63921) (xy 91.883738 -436.80761) (xy 93.074744 -436.80761)
			)
		)
		(polygon
			(pts
				(xy 91.076272 -435.63921) (xy 89.892632 -435.63921) (xy 89.892632 -436.80761) (xy 91.076272 -436.80761)
			)
		)
		(polygon
			(pts
				(xy 23.803356 -434.864002) (xy 21.796756 -434.864002) (xy 21.796756 -436.756048) (xy 21.79701 -436.756302)
				(xy 23.803356 -436.756302)
			)
		)
		(polygon
			(pts
				(arc
					(start 25.88514 -435.251098)
					(mid 25.272873 -434.639212)
					(end 24.66086 -435.251352)
				)
				(arc
					(start 24.66086 -436.368952)
					(mid 25.273 -436.981092)
					(end 25.88514 -436.368952)
				)
			)
		)
		(polygon
			(pts
				(arc
					(start 5.59054 -435.135274)
					(mid 5.08 -434.624734)
					(end 4.56946 -435.135274)
				)
				(arc
					(start 4.56946 -435.948328)
					(mid 5.080127 -436.458614)
					(end 5.59054 -435.948074)
				)
			)
		)
		(polygon
			(pts
				(xy 98.98761 -434.203856) (xy 97.81921 -434.203856) (xy 97.81921 -435.395116) (xy 98.98761 -435.395116)
			)
		)
		(polygon
			(pts
				(arc
					(start 103.3272 -433.1462)
					(mid 103.297442 -433.074358)
					(end 103.2256 -433.0446)
				)
				(arc
					(start 102.0064 -433.0446)
					(mid 101.934558 -433.074358)
					(end 101.9048 -433.1462)
				)
				(arc
					(start 101.9048 -434.5178)
					(mid 101.934558 -434.589642)
					(end 102.0064 -434.6194)
				)
				(arc
					(start 103.2256 -434.6194)
					(mid 103.297442 -434.589642)
					(end 103.3272 -434.5178)
				)
			)
		)
		(polygon
			(pts
				(arc
					(start 27.18054 -433.003452)
					(mid 26.669873 -432.493166)
					(end 26.15946 -433.003706)
				)
				(arc
					(start 26.15946 -433.816506)
					(mid 26.67 -434.327046)
					(end 27.18054 -433.816506)
				)
			)
		)
		(polygon
			(pts
				(xy 23.803356 -432.463956) (xy 21.796756 -432.463956) (xy 21.796756 -434.356002) (xy 21.79701 -434.356256)
				(xy 23.803356 -434.356256)
			)
		)
		(polygon
			(pts
				(xy 98.98761 -432.202844) (xy 97.81921 -432.202844) (xy 97.81921 -433.396898) (xy 98.98761 -433.396898)
			)
		)
		(polygon
			(pts
				(arc
					(start 79.09814 -431.6349)
					(mid 79.067638 -431.561262)
					(end 78.994 -431.53076)
				)
				(arc
					(start 78.6384 -431.53076)
					(mid 78.564762 -431.561262)
					(end 78.53426 -431.6349)
				)
				(arc
					(start 78.53426 -431.9905)
					(mid 78.564762 -432.064138)
					(end 78.6384 -432.09464)
				)
				(arc
					(start 78.994 -432.09464)
					(mid 79.067638 -432.064138)
					(end 79.09814 -431.9905)
				)
			)
		)
		(polygon
			(pts
				(arc
					(start 78.05674 -431.6349)
					(mid 78.026238 -431.561262)
					(end 77.9526 -431.53076)
				)
				(arc
					(start 77.597 -431.53076)
					(mid 77.523362 -431.561262)
					(end 77.49286 -431.6349)
				)
				(arc
					(start 77.49286 -431.9905)
					(mid 77.523362 -432.064138)
					(end 77.597 -432.09464)
				)
				(arc
					(start 77.9526 -432.09464)
					(mid 78.026238 -432.064138)
					(end 78.05674 -431.9905)
				)
			)
		)
		(polygon
			(pts
				(arc
					(start 83.61934 -431.4571)
					(mid 83.603717 -431.419383)
					(end 83.566 -431.40376)
				)
				(arc
					(start 83.3628 -431.40376)
					(mid 83.325083 -431.419383)
					(end 83.30946 -431.4571)
				)
				(arc
					(start 83.30946 -431.7111)
					(mid 83.325083 -431.748817)
					(end 83.3628 -431.76444)
				)
				(arc
					(start 83.566 -431.76444)
					(mid 83.603717 -431.748817)
					(end 83.61934 -431.7111)
				)
			)
		)
		(polygon
			(pts
				(xy 3.494532 -430.887886) (xy 1.005332 -430.887886) (xy 1.005332 -432.195986) (xy 3.494532 -432.195986)
			)
		)
		(polygon
			(pts
				(arc
					(start 83.61934 -430.8983)
					(mid 83.603717 -430.860583)
					(end 83.566 -430.84496)
				)
				(arc
					(start 83.3628 -430.84496)
					(mid 83.325083 -430.860583)
					(end 83.30946 -430.8983)
				)
				(arc
					(start 83.30946 -431.1523)
					(mid 83.325083 -431.190017)
					(end 83.3628 -431.20564)
				)
				(arc
					(start 83.566 -431.20564)
					(mid 83.603717 -431.190017)
					(end 83.61934 -431.1523)
				)
			)
		)
		(polygon
			(pts
				(xy 90.14079 -430.703736) (xy 88.97239 -430.703736) (xy 88.97239 -431.895504) (xy 90.14079 -431.895504)
			)
		)
		(polygon
			(pts
				(arc
					(start 7.502906 -431.18405)
					(mid 6.992239 -430.673764)
					(end 6.481826 -431.184304)
				)
				(arc
					(start 6.481826 -431.997104)
					(mid 6.992366 -432.507644)
					(end 7.502906 -431.997104)
				)
			)
		)
		(polygon
			(pts
				(arc
					(start 72.90054 -431.139346)
					(mid 72.389873 -430.62906)
					(end 71.87946 -431.1396)
				)
				(arc
					(start 71.87946 -431.9524)
					(mid 72.39 -432.46294)
					(end 72.90054 -431.9524)
				)
			)
		)
		(polygon
			(pts
				(arc
					(start 79.09814 -430.5935)
					(mid 79.067638 -430.519862)
					(end 78.994 -430.48936)
				)
				(arc
					(start 78.6384 -430.48936)
					(mid 78.564762 -430.519862)
					(end 78.53426 -430.5935)
				)
				(arc
					(start 78.53426 -430.9491)
					(mid 78.564762 -431.022738)
					(end 78.6384 -431.05324)
				)
				(arc
					(start 78.994 -431.05324)
					(mid 79.067638 -431.022738)
					(end 79.09814 -430.9491)
				)
			)
		)
		(polygon
			(pts
				(arc
					(start 78.05674 -430.5935)
					(mid 78.026238 -430.519862)
					(end 77.9526 -430.48936)
				)
				(arc
					(start 77.597 -430.48936)
					(mid 77.523362 -430.519862)
					(end 77.49286 -430.5935)
				)
				(arc
					(start 77.49286 -430.9491)
					(mid 77.523362 -431.022738)
					(end 77.597 -431.05324)
				)
				(arc
					(start 77.9526 -431.05324)
					(mid 78.026238 -431.022738)
					(end 78.05674 -430.9491)
				)
			)
		)
		(polygon
			(pts
				(xy 23.803356 -430.06391) (xy 21.796756 -430.06391) (xy 21.796756 -431.955956) (xy 21.79701 -431.95621)
				(xy 23.803356 -431.95621)
			)
		)
		(polygon
			(pts
				(arc
					(start 25.88514 -430.451006)
					(mid 25.272873 -429.83912)
					(end 24.66086 -430.45126)
				)
				(arc
					(start 24.66086 -431.56886)
					(mid 25.273 -432.181)
					(end 25.88514 -431.56886)
				)
			)
		)
		(polygon
			(pts
				(arc
					(start 75.0824 -430.63414)
					(mid 75.59294 -430.1236)
					(end 75.0824 -429.61306)
				)
				(arc
					(start 74.269346 -429.61306)
					(mid 73.75906 -430.123727)
					(end 74.2696 -430.63414)
				)
			)
		)
		(polygon
			(pts
				(arc
					(start 5.59054 -429.534828)
					(mid 5.079873 -429.024542)
					(end 4.56946 -429.535082)
				)
				(arc
					(start 4.56946 -430.347882)
					(mid 5.08 -430.858422)
					(end 5.59054 -430.347882)
				)
			)
		)
		(polygon
			(pts
				(arc
					(start 27.18054 -428.20336)
					(mid 26.669873 -427.693074)
					(end 26.15946 -428.203614)
				)
				(arc
					(start 26.15946 -429.016414)
					(mid 26.67 -429.526954)
					(end 27.18054 -429.016414)
				)
			)
		)
		(polygon
			(pts
				(xy 3.494532 -427.687994) (xy 1.005332 -427.687994) (xy 1.005332 -428.99584) (xy 3.494532 -428.99584)
			)
		)
		(polygon
			(pts
				(xy 23.803356 -427.663864) (xy 21.796756 -427.663864) (xy 21.796756 -429.55591) (xy 21.79701 -429.556164)
				(xy 23.803356 -429.556164)
			)
		)
		(polygon
			(pts
				(arc
					(start 7.502906 -427.983904)
					(mid 6.992239 -427.473618)
					(end 6.481826 -427.984158)
				)
				(arc
					(start 6.481826 -428.796958)
					(mid 6.992366 -429.307498)
					(end 7.502906 -428.796958)
				)
			)
		)
		(polygon
			(pts
				(xy 93.074998 -426.79239) (xy 91.882722 -426.79239) (xy 91.882722 -427.96079) (xy 93.074998 -427.96079)
			)
		)
		(polygon
			(pts
				(xy 91.076018 -426.790104) (xy 89.889838 -426.790104) (xy 89.889838 -427.958504) (xy 91.076018 -427.958504)
			)
		)
		(polygon
			(pts
				(arc
					(start 5.59054 -426.334936)
					(mid 5.079873 -425.82465)
					(end 4.56946 -426.33519)
				)
				(arc
					(start 4.56946 -427.14799)
					(mid 5.08 -427.65853)
					(end 5.59054 -427.14799)
				)
			)
		)
		(polygon
			(pts
				(xy 23.803356 -425.263818) (xy 21.796756 -425.263818) (xy 21.796756 -427.155864) (xy 21.79701 -427.156118)
				(xy 23.803356 -427.156118)
			)
		)
		(polygon
			(pts
				(arc
					(start 15.131288 -425.182792)
					(mid 15.10153 -425.11095)
					(end 15.029688 -425.081192)
				)
				(arc
					(start 13.734288 -425.081192)
					(mid 13.662446 -425.11095)
					(end 13.632688 -425.182792)
				)
				(arc
					(start 13.632688 -426.503592)
					(mid 13.662446 -426.575434)
					(end 13.734288 -426.605192)
				)
				(arc
					(start 15.029688 -426.605192)
					(mid 15.10153 -426.575434)
					(end 15.131288 -426.503592)
				)
			)
		)
		(polygon
			(pts
				(arc
					(start 25.88514 -425.650914)
					(mid 25.272873 -425.039028)
					(end 24.66086 -425.651168)
				)
				(arc
					(start 24.66086 -426.768768)
					(mid 25.273 -427.380908)
					(end 25.88514 -426.768768)
				)
			)
		)
		(polygon
			(pts
				(xy 3.494532 -424.487848) (xy 1.005332 -424.487848) (xy 1.005332 -425.795948) (xy 3.494532 -425.795948)
			)
		)
		(polygon
			(pts
				(arc
					(start 7.502906 -424.784012)
					(mid 6.992239 -424.273726)
					(end 6.481826 -424.784266)
				)
				(arc
					(start 6.481826 -425.597066)
					(mid 6.992366 -426.107606)
					(end 7.502906 -425.597066)
				)
			)
		)
		(polygon
			(pts
				(arc
					(start 5.59054 -423.135044)
					(mid 5.079873 -422.624758)
					(end 4.56946 -423.135298)
				)
				(arc
					(start 4.56946 -423.948098)
					(mid 5.08 -424.458638)
					(end 5.59054 -423.948098)
				)
			)
		)
		(polygon
			(pts
				(arc
					(start 91.5924 -422.5544)
					(mid 91.562642 -422.482558)
					(end 91.4908 -422.4528)
				)
				(arc
					(start 90.1192 -422.4528)
					(mid 90.047358 -422.482558)
					(end 90.0176 -422.5544)
				)
				(arc
					(start 90.0176 -423.7736)
					(mid 90.047358 -423.845442)
					(end 90.1192 -423.8752)
				)
				(arc
					(start 91.4908 -423.8752)
					(mid 91.562642 -423.845442)
					(end 91.5924 -423.7736)
				)
			)
		)
		(polygon
			(pts
				(arc
					(start 87.7824 -422.5544)
					(mid 87.752642 -422.482558)
					(end 87.6808 -422.4528)
				)
				(arc
					(start 86.3092 -422.4528)
					(mid 86.237358 -422.482558)
					(end 86.2076 -422.5544)
				)
				(arc
					(start 86.2076 -423.7736)
					(mid 86.237358 -423.845442)
					(end 86.3092 -423.8752)
				)
				(arc
					(start 87.6808 -423.8752)
					(mid 87.752642 -423.845442)
					(end 87.7824 -423.7736)
				)
			)
		)
		(polygon
			(pts
				(arc
					(start 5.59054 -416.735006)
					(mid 5.079873 -416.22472)
					(end 4.56946 -416.73526)
				)
				(arc
					(start 4.56946 -417.54806)
					(mid 5.08 -418.0586)
					(end 5.59054 -417.54806)
				)
			)
		)
		(polygon
			(pts
				(xy 3.494532 -414.887918) (xy 1.005332 -414.887918) (xy 1.005332 -416.196018) (xy 3.494532 -416.196018)
			)
		)
		(polygon
			(pts
				(arc
					(start 7.502906 -415.135568)
					(mid 6.992239 -414.625282)
					(end 6.481826 -415.135822)
				)
				(arc
					(start 6.481826 -415.948622)
					(mid 6.992366 -416.459162)
					(end 7.502906 -415.948622)
				)
			)
		)
		(polygon
			(pts
				(arc
					(start 5.59054 -413.535114)
					(mid 5.08 -413.024574)
					(end 4.56946 -413.535114)
				)
				(arc
					(start 4.56946 -414.348168)
					(mid 5.080127 -414.858454)
					(end 5.59054 -414.347914)
				)
			)
		)
		(polygon
			(pts
				(xy 3.494532 -411.687772) (xy 1.005332 -411.687772) (xy 1.005332 -412.995872) (xy 3.494532 -412.995872)
			)
		)
		(polygon
			(pts
				(arc
					(start 7.502906 -411.935676)
					(mid 6.992366 -411.425136)
					(end 6.481826 -411.935676)
				)
				(arc
					(start 6.481826 -412.74873)
					(mid 6.992493 -413.259016)
					(end 7.502906 -412.748476)
				)
			)
		)
		(polygon
			(pts
				(arc
					(start 5.59054 -410.335222)
					(mid 5.08 -409.824682)
					(end 4.56946 -410.335222)
				)
				(arc
					(start 4.56946 -411.148276)
					(mid 5.080127 -411.658562)
					(end 5.59054 -411.148022)
				)
			)
		)
		(polygon
			(pts
				(xy 3.494532 -408.48788) (xy 1.005332 -408.48788) (xy 1.005332 -409.79598) (xy 3.494532 -409.79598)
			)
		)
		(polygon
			(pts
				(arc
					(start 7.502906 -408.735784)
					(mid 6.992366 -408.225244)
					(end 6.481826 -408.735784)
				)
				(arc
					(start 6.481826 -409.548838)
					(mid 6.992493 -410.059124)
					(end 7.502906 -409.548584)
				)
			)
		)
		(polygon
			(pts
				(arc
					(start 5.59054 -407.135076)
					(mid 5.08 -406.624536)
					(end 4.56946 -407.135076)
				)
				(arc
					(start 4.56946 -407.94813)
					(mid 5.080127 -408.458416)
					(end 5.59054 -407.947876)
				)
			)
		)
		(polygon
			(pts
				(xy 3.494532 -405.287988) (xy 1.005332 -405.287988) (xy 1.005332 -406.595834) (xy 3.494532 -406.595834)
			)
		)
		(polygon
			(pts
				(arc
					(start 7.502906 -405.535638)
					(mid 6.992366 -405.025098)
					(end 6.481826 -405.535638)
				)
				(arc
					(start 6.481826 -406.348692)
					(mid 6.992493 -406.858978)
					(end 7.502906 -406.348438)
				)
			)
		)
		(polygon
			(pts
				(arc
					(start 5.59054 -403.935184)
					(mid 5.08 -403.424644)
					(end 4.56946 -403.935184)
				)
				(arc
					(start 4.56946 -404.748238)
					(mid 5.080127 -405.258524)
					(end 5.59054 -404.747984)
				)
			)
		)
		(polygon
			(pts
				(xy 3.494532 -402.087842) (xy 1.005332 -402.087842) (xy 1.005332 -403.395942) (xy 3.494532 -403.395942)
			)
		)
		(polygon
			(pts
				(arc
					(start 7.502906 -402.335746)
					(mid 6.992366 -401.825206)
					(end 6.481826 -402.335746)
				)
				(arc
					(start 6.481826 -403.1488)
					(mid 6.992493 -403.659086)
					(end 7.502906 -403.148546)
				)
			)
		)
		(polygon
			(pts
				(arc
					(start 5.59054 -398.334992)
					(mid 5.079873 -397.824706)
					(end 4.56946 -398.335246)
				)
				(arc
					(start 4.56946 -399.148046)
					(mid 5.08 -399.658586)
					(end 5.59054 -399.148046)
				)
			)
		)
		(polygon
			(pts
				(xy 3.494532 -396.487904) (xy 1.005332 -396.487904) (xy 1.005332 -397.796004) (xy 3.494532 -397.796004)
			)
		)
		(polygon
			(pts
				(arc
					(start 7.502906 -396.735554)
					(mid 6.992239 -396.225268)
					(end 6.481826 -396.735808)
				)
				(arc
					(start 6.481826 -397.548608)
					(mid 6.992366 -398.059148)
					(end 7.502906 -397.548608)
				)
			)
		)
		(polygon
			(pts
				(arc
					(start 5.59054 -395.134846)
					(mid 5.079873 -394.62456)
					(end 4.56946 -395.1351)
				)
				(arc
					(start 4.56946 -395.9479)
					(mid 5.08 -396.45844)
					(end 5.59054 -395.9479)
				)
			)
		)
		(polygon
			(pts
				(xy 3.494532 -393.288012) (xy 1.005332 -393.288012) (xy 1.005332 -394.595858) (xy 3.494532 -394.595858)
			)
		)
		(polygon
			(pts
				(arc
					(start 7.502906 -393.535408)
					(mid 6.992239 -393.025122)
					(end 6.481826 -393.535662)
				)
				(arc
					(start 6.481826 -394.348462)
					(mid 6.992366 -394.859002)
					(end 7.502906 -394.348462)
				)
			)
		)
		(polygon
			(pts
				(arc
					(start 5.59054 -391.934954)
					(mid 5.079873 -391.424668)
					(end 4.56946 -391.935208)
				)
				(arc
					(start 4.56946 -392.748008)
					(mid 5.08 -393.258548)
					(end 5.59054 -392.748008)
				)
			)
		)
		(polygon
			(pts
				(xy 3.494532 -390.087866) (xy 1.005332 -390.087866) (xy 1.005332 -391.395966) (xy 3.494532 -391.395966)
			)
		)
		(polygon
			(pts
				(arc
					(start 7.502906 -390.335516)
					(mid 6.992239 -389.82523)
					(end 6.481826 -390.33577)
				)
				(arc
					(start 6.481826 -391.14857)
					(mid 6.992366 -391.65911)
					(end 7.502906 -391.14857)
				)
			)
		)
		(polygon
			(pts
				(arc
					(start 5.59054 -388.735062)
					(mid 5.079873 -388.224776)
					(end 4.56946 -388.735316)
				)
				(arc
					(start 4.56946 -389.548116)
					(mid 5.08 -390.058656)
					(end 5.59054 -389.548116)
				)
			)
		)
		(polygon
			(pts
				(xy 225.203004 -387.84403) (xy 223.196658 -387.84403) (xy 223.196658 -389.736076) (xy 225.203258 -389.736076)
				(xy 225.203258 -387.844284)
			)
		)
		(polygon
			(pts
				(xy 40.20312 -387.84403) (xy 38.196774 -387.84403) (xy 38.196774 -389.736076) (xy 40.203374 -389.736076)
				(xy 40.203374 -387.844284)
			)
		)
		(polygon
			(pts
				(arc
					(start 222.339154 -388.231126)
					(mid 221.726887 -387.61924)
					(end 221.114874 -388.23138)
				)
				(arc
					(start 221.114874 -389.34898)
					(mid 221.727014 -389.96112)
					(end 222.339154 -389.34898)
				)
			)
		)
		(polygon
			(pts
				(arc
					(start 37.33927 -388.231126)
					(mid 36.727003 -387.61924)
					(end 36.11499 -388.23138)
				)
				(arc
					(start 36.11499 -389.34898)
					(mid 36.72713 -389.96112)
					(end 37.33927 -389.34898)
				)
			)
		)
		(polygon
			(pts
				(xy 3.494532 -386.887974) (xy 1.005332 -386.887974) (xy 1.005332 -388.19582) (xy 3.494532 -388.19582)
			)
		)
		(polygon
			(pts
				(arc
					(start 7.502906 -387.13537)
					(mid 6.992239 -386.625084)
					(end 6.481826 -387.135624)
				)
				(arc
					(start 6.481826 -387.948424)
					(mid 6.992366 -388.458964)
					(end 7.502906 -387.948424)
				)
			)
		)
		(polygon
			(pts
				(arc
					(start 220.840554 -385.98348)
					(mid 220.329887 -385.473194)
					(end 219.819474 -385.983734)
				)
				(arc
					(start 219.819474 -386.796534)
					(mid 220.330014 -387.307074)
					(end 220.840554 -386.796534)
				)
			)
		)
		(polygon
			(pts
				(arc
					(start 35.84067 -385.98348)
					(mid 35.330003 -385.473194)
					(end 34.81959 -385.983734)
				)
				(arc
					(start 34.81959 -386.796534)
					(mid 35.33013 -387.307074)
					(end 35.84067 -386.796534)
				)
			)
		)
		(polygon
			(pts
				(xy 225.203004 -385.443984) (xy 223.196658 -385.443984) (xy 223.196658 -387.336284) (xy 225.203258 -387.336284)
				(xy 225.203258 -385.444238)
			)
		)
		(polygon
			(pts
				(xy 40.20312 -385.443984) (xy 38.196774 -385.443984) (xy 38.196774 -387.336284) (xy 40.203374 -387.336284)
				(xy 40.203374 -385.444238)
			)
		)
		(polygon
			(pts
				(arc
					(start 9.195308 -386.113782)
					(mid 9.705594 -385.603115)
					(end 9.195054 -385.092702)
				)
				(arc
					(start 8.382254 -385.092702)
					(mid 7.871714 -385.603242)
					(end 8.382254 -386.113782)
				)
			)
		)
		(polygon
			(pts
				(xy 3.494532 -384.487928) (xy 1.005332 -384.487928) (xy 1.005332 -385.795774) (xy 3.494532 -385.795774)
			)
		)
		(polygon
			(pts
				(arc
					(start 9.5377 -383.4384)
					(mid 9.507942 -383.366558)
					(end 9.4361 -383.3368)
				)
				(arc
					(start 8.1407 -383.3368)
					(mid 8.068858 -383.366558)
					(end 8.0391 -383.4384)
				)
				(arc
					(start 8.0391 -384.7592)
					(mid 8.068858 -384.831042)
					(end 8.1407 -384.8608)
				)
				(arc
					(start 9.4361 -384.8608)
					(mid 9.507942 -384.831042)
					(end 9.5377 -384.7592)
				)
			)
		)
		(polygon
			(pts
				(xy 225.203004 -383.043938) (xy 223.196658 -383.043938) (xy 223.196658 -384.936238) (xy 225.203258 -384.936238)
				(xy 225.203258 -383.044192)
			)
		)
		(polygon
			(pts
				(xy 40.20312 -383.043938) (xy 38.196774 -383.043938) (xy 38.196774 -384.936238) (xy 40.203374 -384.936238)
				(xy 40.203374 -383.044192)
			)
		)
		(polygon
			(pts
				(arc
					(start 222.339154 -383.431034)
					(mid 221.726887 -382.819148)
					(end 221.114874 -383.431288)
				)
				(arc
					(start 221.114874 -384.548888)
					(mid 221.727014 -385.161028)
					(end 222.339154 -384.548888)
				)
			)
		)
		(polygon
			(pts
				(arc
					(start 37.33927 -383.431034)
					(mid 36.727003 -382.819148)
					(end 36.11499 -383.431288)
				)
				(arc
					(start 36.11499 -384.548888)
					(mid 36.72713 -385.161028)
					(end 37.33927 -384.548888)
				)
			)
		)
		(polygon
			(pts
				(arc
					(start 220.840554 -381.183388)
					(mid 220.329887 -380.673102)
					(end 219.819474 -381.183642)
				)
				(arc
					(start 219.819474 -381.996442)
					(mid 220.330014 -382.506982)
					(end 220.840554 -381.996442)
				)
			)
		)
		(polygon
			(pts
				(arc
					(start 35.84067 -381.183388)
					(mid 35.330003 -380.673102)
					(end 34.81959 -381.183642)
				)
				(arc
					(start 34.81959 -381.996442)
					(mid 35.33013 -382.506982)
					(end 35.84067 -381.996442)
				)
			)
		)
		(polygon
			(pts
				(xy 225.203004 -380.643892) (xy 223.196658 -380.643892) (xy 223.196658 -382.536192) (xy 225.203258 -382.536192)
				(xy 225.203258 -380.644146)
			)
		)
		(polygon
			(pts
				(xy 40.20312 -380.643892) (xy 38.196774 -380.643892) (xy 38.196774 -382.536192) (xy 40.203374 -382.536192)
				(xy 40.203374 -380.644146)
			)
		)
		(polygon
			(pts
				(xy 225.203004 -378.243846) (xy 223.196658 -378.243846) (xy 223.196658 -380.136146) (xy 225.203258 -380.136146)
				(xy 225.203258 -378.2441)
			)
		)
		(polygon
			(pts
				(xy 40.20312 -378.243846) (xy 38.196774 -378.243846) (xy 38.196774 -380.136146) (xy 40.203374 -380.136146)
				(xy 40.203374 -378.2441)
			)
		)
		(polygon
			(pts
				(arc
					(start 222.339154 -378.630942)
					(mid 221.726887 -378.019056)
					(end 221.114874 -378.631196)
				)
				(arc
					(start 221.114874 -379.748796)
					(mid 221.727014 -380.360936)
					(end 222.339154 -379.748796)
				)
			)
		)
		(polygon
			(pts
				(arc
					(start 37.33927 -378.630942)
					(mid 36.727003 -378.019056)
					(end 36.11499 -378.631196)
				)
				(arc
					(start 36.11499 -379.748796)
					(mid 36.72713 -380.360936)
					(end 37.33927 -379.748796)
				)
			)
		)
		(polygon
			(pts
				(arc
					(start 7.9756 -377.825)
					(mid 7.945842 -377.753158)
					(end 7.874 -377.7234)
				)
				(arc
					(start 6.5532 -377.7234)
					(mid 6.481358 -377.753158)
					(end 6.4516 -377.825)
				)
				(arc
					(start 6.4516 -379.1458)
					(mid 6.481358 -379.217642)
					(end 6.5532 -379.2474)
				)
				(arc
					(start 7.874 -379.2474)
					(mid 7.945842 -379.217642)
					(end 7.9756 -379.1458)
				)
			)
		)
		(polygon
			(pts
				(arc
					(start 220.840554 -376.38355)
					(mid 220.329887 -375.873264)
					(end 219.819474 -376.383804)
				)
				(arc
					(start 219.819474 -377.196604)
					(mid 220.330014 -377.707144)
					(end 220.840554 -377.196604)
				)
			)
		)
		(polygon
			(pts
				(arc
					(start 35.84067 -376.38355)
					(mid 35.330003 -375.873264)
					(end 34.81959 -376.383804)
				)
				(arc
					(start 34.81959 -377.196604)
					(mid 35.33013 -377.707144)
					(end 35.84067 -377.196604)
				)
			)
		)
		(polygon
			(pts
				(xy 225.203004 -375.844054) (xy 223.196658 -375.844054) (xy 223.196658 -377.7361) (xy 225.203258 -377.7361)
				(xy 225.203258 -375.844308)
			)
		)
		(polygon
			(pts
				(xy 40.20312 -375.844054) (xy 38.196774 -375.844054) (xy 38.196774 -377.7361) (xy 40.203374 -377.7361)
				(xy 40.203374 -375.844308)
			)
		)
		(polygon
			(pts
				(arc
					(start 233.897424 -369.579398)
					(mid 233.386884 -369.068858)
					(end 232.876344 -369.579398)
				)
				(arc
					(start 232.876344 -370.392452)
					(mid 233.387011 -370.902738)
					(end 233.897424 -370.392198)
				)
			)
		)
		(polygon
			(pts
				(arc
					(start 48.89754 -369.579144)
					(mid 48.386873 -369.068858)
					(end 47.87646 -369.579398)
				)
				(arc
					(start 47.87646 -370.392198)
					(mid 48.387 -370.902738)
					(end 48.89754 -370.392198)
				)
			)
		)
		(polygon
			(pts
				(xy 228.39299 -369.043966) (xy 226.386644 -369.043966) (xy 226.386644 -370.936266) (xy 228.393244 -370.936266)
				(xy 228.393244 -369.04422)
			)
		)
		(polygon
			(pts
				(xy 43.393106 -369.043966) (xy 41.38676 -369.043966) (xy 41.38676 -370.936266) (xy 43.39336 -370.936266)
				(xy 43.39336 -369.04422)
			)
		)
		(polygon
			(pts
				(arc
					(start 230.720138 -369.30076)
					(mid 231.230424 -368.790093)
					(end 230.719884 -368.27968)
				)
				(arc
					(start 229.907084 -368.27968)
					(mid 229.396544 -368.79022)
					(end 229.907084 -369.30076)
				)
			)
		)
		(polygon
			(pts
				(arc
					(start 45.72 -369.30076)
					(mid 46.23054 -368.79022)
					(end 45.72 -368.27968)
				)
				(arc
					(start 44.906946 -368.27968)
					(mid 44.39666 -368.790347)
					(end 44.9072 -369.30076)
				)
			)
		)
		(polygon
			(pts
				(xy 225.203004 -365.444024) (xy 223.196658 -365.444024) (xy 223.196658 -367.33607) (xy 225.203258 -367.33607)
				(xy 225.203258 -365.444278)
			)
		)
		(polygon
			(pts
				(xy 40.20312 -365.444024) (xy 38.196774 -365.444024) (xy 38.196774 -367.33607) (xy 40.203374 -367.33607)
				(xy 40.203374 -365.444278)
			)
		)
		(polygon
			(pts
				(arc
					(start 222.339154 -365.83112)
					(mid 221.726887 -365.219234)
					(end 221.114874 -365.831374)
				)
				(arc
					(start 221.114874 -366.948974)
					(mid 221.727014 -367.561114)
					(end 222.339154 -366.948974)
				)
			)
		)
		(polygon
			(pts
				(arc
					(start 37.33927 -365.83112)
					(mid 36.727003 -365.219234)
					(end 36.11499 -365.831374)
				)
				(arc
					(start 36.11499 -366.948974)
					(mid 36.72713 -367.561114)
					(end 37.33927 -366.948974)
				)
			)
		)
		(polygon
			(pts
				(arc
					(start 220.840554 -363.583474)
					(mid 220.329887 -363.073188)
					(end 219.819474 -363.583728)
				)
				(arc
					(start 219.819474 -364.396528)
					(mid 220.330014 -364.907068)
					(end 220.840554 -364.396528)
				)
			)
		)
		(polygon
			(pts
				(arc
					(start 35.84067 -363.583474)
					(mid 35.330003 -363.073188)
					(end 34.81959 -363.583728)
				)
				(arc
					(start 34.81959 -364.396528)
					(mid 35.33013 -364.907068)
					(end 35.84067 -364.396528)
				)
			)
		)
		(polygon
			(pts
				(xy 225.203004 -363.043978) (xy 223.196658 -363.043978) (xy 223.196658 -364.936278) (xy 225.203258 -364.936278)
				(xy 225.203258 -363.044232)
			)
		)
		(polygon
			(pts
				(xy 40.20312 -363.043978) (xy 38.196774 -363.043978) (xy 38.196774 -364.936278) (xy 40.203374 -364.936278)
				(xy 40.203374 -363.044232)
			)
		)
		(polygon
			(pts
				(xy 225.203004 -360.643932) (xy 223.196658 -360.643932) (xy 223.196658 -362.536232) (xy 225.203258 -362.536232)
				(xy 225.203258 -360.644186)
			)
		)
		(polygon
			(pts
				(xy 40.20312 -360.643932) (xy 38.196774 -360.643932) (xy 38.196774 -362.536232) (xy 40.203374 -362.536232)
				(xy 40.203374 -360.644186)
			)
		)
		(polygon
			(pts
				(arc
					(start 5.59054 -357.935276)
					(mid 5.079873 -357.42499)
					(end 4.56946 -357.93553)
				)
				(arc
					(start 4.56946 -358.74833)
					(mid 5.08 -359.25887)
					(end 5.59054 -358.74833)
				)
			)
		)
		(polygon
			(pts
				(xy 3.494532 -356.088188) (xy 1.005332 -356.088188) (xy 1.005332 -357.396034) (xy 3.494532 -357.396034)
			)
		)
		(polygon
			(pts
				(arc
					(start 7.502906 -356.335838)
					(mid 6.992366 -355.825298)
					(end 6.481826 -356.335838)
				)
				(arc
					(start 6.481826 -357.148892)
					(mid 6.992493 -357.659178)
					(end 7.502906 -357.148638)
				)
			)
		)
		(polygon
			(pts
				(arc
					(start 5.59054 -354.73513)
					(mid 5.079873 -354.224844)
					(end 4.56946 -354.735384)
				)
				(arc
					(start 4.56946 -355.548184)
					(mid 5.08 -356.058724)
					(end 5.59054 -355.548184)
				)
			)
		)
		(polygon
			(pts
				(xy 3.494532 -352.888042) (xy 1.005332 -352.888042) (xy 1.005332 -354.196142) (xy 3.494532 -354.196142)
			)
		)
		(polygon
			(pts
				(arc
					(start 7.502906 -353.135692)
					(mid 6.992239 -352.625406)
					(end 6.481826 -353.135946)
				)
				(arc
					(start 6.481826 -353.948746)
					(mid 6.992366 -354.459286)
					(end 7.502906 -353.948746)
				)
			)
		)
		(polygon
			(pts
				(arc
					(start 5.59054 -351.535238)
					(mid 5.079873 -351.024952)
					(end 4.56946 -351.535492)
				)
				(arc
					(start 4.56946 -352.348292)
					(mid 5.08 -352.858832)
					(end 5.59054 -352.348292)
				)
			)
		)
		(polygon
			(pts
				(xy 3.494532 -349.68815) (xy 1.005332 -349.68815) (xy 1.005332 -350.995996) (xy 3.494532 -350.995996)
			)
		)
		(polygon
			(pts
				(xy 23.803356 -349.463868) (xy 21.796756 -349.463868) (xy 21.796756 -351.355914) (xy 21.79701 -351.356168)
				(xy 23.803356 -351.356168)
			)
		)
		(polygon
			(pts
				(arc
					(start 7.502906 -349.9358)
					(mid 6.992366 -349.42526)
					(end 6.481826 -349.9358)
				)
				(arc
					(start 6.481826 -350.748854)
					(mid 6.992493 -351.25914)
					(end 7.502906 -350.7486)
				)
			)
		)
		(polygon
			(pts
				(arc
					(start 5.59054 -348.335092)
					(mid 5.079873 -347.824806)
					(end 4.56946 -348.335346)
				)
				(arc
					(start 4.56946 -349.148146)
					(mid 5.08 -349.658686)
					(end 5.59054 -349.148146)
				)
			)
		)
		(polygon
			(pts
				(arc
					(start 27.18054 -347.603572)
					(mid 26.67 -347.093032)
					(end 26.15946 -347.603572)
				)
				(arc
					(start 26.15946 -348.416626)
					(mid 26.670127 -348.926912)
					(end 27.18054 -348.416372)
				)
			)
		)
		(polygon
			(pts
				(xy 23.803356 -347.063822) (xy 21.796756 -347.063822) (xy 21.796756 -348.955868) (xy 21.79701 -348.956122)
				(xy 23.803356 -348.956122)
			)
		)
		(polygon
			(pts
				(xy 3.494532 -346.488004) (xy 1.005332 -346.488004) (xy 1.005332 -347.796104) (xy 3.494532 -347.796104)
			)
		)
		(polygon
			(pts
				(arc
					(start 7.502906 -346.735908)
					(mid 6.992366 -346.225368)
					(end 6.481826 -346.735908)
				)
				(arc
					(start 6.481826 -347.548962)
					(mid 6.992493 -348.059248)
					(end 7.502906 -347.548708)
				)
			)
		)
		(polygon
			(pts
				(xy 23.803356 -344.663776) (xy 21.796756 -344.663776) (xy 21.796756 -346.555822) (xy 21.79701 -346.556076)
				(xy 23.803356 -346.556076)
			)
		)
		(polygon
			(pts
				(arc
					(start 5.59054 -345.1352)
					(mid 5.079873 -344.624914)
					(end 4.56946 -345.135454)
				)
				(arc
					(start 4.56946 -345.948254)
					(mid 5.08 -346.458794)
					(end 5.59054 -345.948254)
				)
			)
		)
		(polygon
			(pts
				(arc
					(start 25.88514 -345.050872)
					(mid 25.272873 -344.438986)
					(end 24.66086 -345.051126)
				)
				(arc
					(start 24.66086 -346.168726)
					(mid 25.273 -346.780866)
					(end 25.88514 -346.168726)
				)
			)
		)
		(polygon
			(pts
				(xy 3.494532 -343.288112) (xy 1.005332 -343.288112) (xy 1.005332 -344.596212) (xy 3.494532 -344.596212)
			)
		)
		(polygon
			(pts
				(arc
					(start 7.502906 -343.586562)
					(mid 6.992239 -343.076276)
					(end 6.481826 -343.586816)
				)
				(arc
					(start 6.481826 -344.399616)
					(mid 6.992366 -344.910156)
					(end 7.502906 -344.399616)
				)
			)
		)
		(polygon
			(pts
				(arc
					(start 5.59054 -341.935054)
					(mid 5.079873 -341.424768)
					(end 4.56946 -341.935308)
				)
				(arc
					(start 4.56946 -342.748108)
					(mid 5.08 -343.258648)
					(end 5.59054 -342.748108)
				)
			)
		)
		(polygon
			(pts
				(arc
					(start 17.78254 -341.60333)
					(mid 17.272 -341.09279)
					(end 16.76146 -341.60333)
				)
				(arc
					(start 16.76146 -342.416384)
					(mid 17.272127 -342.92667)
					(end 17.78254 -342.41613)
				)
			)
		)
		(polygon
			(pts
				(arc
					(start 33.40354 -341.58428)
					(mid 32.892873 -341.073994)
					(end 32.38246 -341.584534)
				)
				(arc
					(start 32.38246 -342.397334)
					(mid 32.893 -342.907874)
					(end 33.40354 -342.397334)
				)
			)
		)
		(polygon
			(pts
				(xy 20.61337 -341.063834) (xy 18.60677 -341.063834) (xy 18.60677 -342.95588) (xy 18.607024 -342.956134)
				(xy 20.61337 -342.956134)
			)
		)
		(polygon
			(pts
				(xy 3.494532 -340.08822) (xy 1.005332 -340.08822) (xy 1.005332 -341.396066) (xy 3.494532 -341.396066)
			)
		)
		(polygon
			(pts
				(arc
					(start 7.502906 -340.386416)
					(mid 6.992239 -339.87613)
					(end 6.481826 -340.38667)
				)
				(arc
					(start 6.481826 -341.19947)
					(mid 6.992366 -341.71001)
					(end 7.502906 -341.19947)
				)
			)
		)
		(polygon
			(pts
				(arc
					(start 5.59054 -338.735162)
					(mid 5.079873 -338.224876)
					(end 4.56946 -338.735416)
				)
				(arc
					(start 4.56946 -339.548216)
					(mid 5.08 -340.058756)
					(end 5.59054 -339.548216)
				)
			)
		)
		(polygon
			(pts
				(xy 3.494532 -336.888074) (xy 1.005332 -336.888074) (xy 1.005332 -338.196174) (xy 3.494532 -338.196174)
			)
		)
		(polygon
			(pts
				(arc
					(start 7.502906 -337.186524)
					(mid 6.992239 -336.676238)
					(end 6.481826 -337.186778)
				)
				(arc
					(start 6.481826 -337.999578)
					(mid 6.992366 -338.510118)
					(end 7.502906 -337.999578)
				)
			)
		)
		(polygon
			(pts
				(arc
					(start 5.59054 -335.53527)
					(mid 5.079873 -335.024984)
					(end 4.56946 -335.535524)
				)
				(arc
					(start 4.56946 -336.348324)
					(mid 5.08 -336.858864)
					(end 5.59054 -336.348324)
				)
			)
		)
		(polygon
			(pts
				(arc
					(start 27.18054 -334.803496)
					(mid 26.67 -334.292956)
					(end 26.15946 -334.803496)
				)
				(arc
					(start 26.15946 -335.61655)
					(mid 26.670127 -336.126836)
					(end 27.18054 -335.616296)
				)
			)
		)
		(polygon
			(pts
				(xy 23.803356 -334.264) (xy 21.796756 -334.264) (xy 21.796756 -336.155792) (xy 21.79701 -336.156046)
				(xy 23.803356 -336.156046)
			)
		)
		(polygon
			(pts
				(xy 3.494532 -333.688182) (xy 1.005332 -333.688182) (xy 1.005332 -334.996028) (xy 3.494532 -334.996028)
			)
		)
		(polygon
			(pts
				(arc
					(start 7.502906 -333.986378)
					(mid 6.992239 -333.476092)
					(end 6.481826 -333.986632)
				)
				(arc
					(start 6.481826 -334.799432)
					(mid 6.992366 -335.309972)
					(end 7.502906 -334.799432)
				)
			)
		)
		(polygon
			(pts
				(xy 23.803356 -331.863954) (xy 21.796756 -331.863954) (xy 21.796756 -333.756) (xy 21.79701 -333.756254)
				(xy 23.803356 -333.756254)
			)
		)
		(polygon
			(pts
				(arc
					(start 25.88514 -332.251304)
					(mid 25.273 -331.639164)
					(end 24.66086 -332.251304)
				)
				(arc
					(start 24.66086 -333.369158)
					(mid 25.273127 -333.981044)
					(end 25.88514 -333.368904)
				)
			)
		)
		(polygon
			(pts
				(arc
					(start 27.18054 -330.003658)
					(mid 26.67 -329.493118)
					(end 26.15946 -330.003658)
				)
				(arc
					(start 26.15946 -330.816712)
					(mid 26.670127 -331.326998)
					(end 27.18054 -330.816458)
				)
			)
		)
		(polygon
			(pts
				(xy 23.803356 -329.463908) (xy 21.796756 -329.463908) (xy 21.796756 -331.355954) (xy 21.79701 -331.356208)
				(xy 23.803356 -331.356208)
			)
		)
		(polygon
			(pts
				(arc
					(start 5.59054 -329.935078)
					(mid 5.079873 -329.424792)
					(end 4.56946 -329.935332)
				)
				(arc
					(start 4.56946 -330.748132)
					(mid 5.08 -331.258672)
					(end 5.59054 -330.748132)
				)
			)
		)
		(polygon
			(pts
				(xy 3.494532 -328.08799) (xy 1.005332 -328.08799) (xy 1.005332 -329.39609) (xy 3.494532 -329.39609)
			)
		)
		(polygon
			(pts
				(arc
					(start 7.502906 -328.335894)
					(mid 6.992366 -327.825354)
					(end 6.481826 -328.335894)
				)
				(arc
					(start 6.481826 -329.148948)
					(mid 6.992493 -329.659234)
					(end 7.502906 -329.148694)
				)
			)
		)
		(polygon
			(pts
				(xy 23.803356 -327.063862) (xy 21.796756 -327.063862) (xy 21.796756 -328.955908) (xy 21.79701 -328.956162)
				(xy 23.803356 -328.956162)
			)
		)
		(polygon
			(pts
				(arc
					(start 25.88514 -327.451212)
					(mid 25.273 -326.839072)
					(end 24.66086 -327.451212)
				)
				(arc
					(start 24.66086 -328.569066)
					(mid 25.273127 -329.180952)
					(end 25.88514 -328.568812)
				)
			)
		)
		(polygon
			(pts
				(arc
					(start 5.59054 -326.735186)
					(mid 5.079873 -326.2249)
					(end 4.56946 -326.73544)
				)
				(arc
					(start 4.56946 -327.54824)
					(mid 5.08 -328.05878)
					(end 5.59054 -327.54824)
				)
			)
		)
		(polygon
			(pts
				(xy 3.494532 -324.888098) (xy 1.005332 -324.888098) (xy 1.005332 -326.196198) (xy 3.494532 -326.196198)
			)
		)
		(polygon
			(pts
				(arc
					(start 27.18054 -325.203566)
					(mid 26.67 -324.693026)
					(end 26.15946 -325.203566)
				)
				(arc
					(start 26.15946 -326.01662)
					(mid 26.670127 -326.526906)
					(end 27.18054 -326.016366)
				)
			)
		)
		(polygon
			(pts
				(xy 23.803356 -324.663816) (xy 21.796756 -324.663816) (xy 21.796756 -326.555862) (xy 21.79701 -326.556116)
				(xy 23.803356 -326.556116)
			)
		)
		(polygon
			(pts
				(arc
					(start 7.502906 -325.136002)
					(mid 6.992366 -324.625462)
					(end 6.481826 -325.136002)
				)
				(arc
					(start 6.481826 -325.949056)
					(mid 6.992493 -326.459342)
					(end 7.502906 -325.948802)
				)
			)
		)
		(polygon
			(pts
				(arc
					(start 5.59054 -323.53504)
					(mid 5.079873 -323.024754)
					(end 4.56946 -323.535294)
				)
				(arc
					(start 4.56946 -324.348094)
					(mid 5.08 -324.858634)
					(end 5.59054 -324.348094)
				)
			)
		)
		(polygon
			(pts
				(xy 23.803356 -322.264024) (xy 21.796756 -322.264024) (xy 21.796756 -324.155816) (xy 21.79701 -324.15607)
				(xy 23.803356 -324.15607)
			)
		)
		(polygon
			(pts
				(arc
					(start 25.88514 -322.65112)
					(mid 25.273 -322.03898)
					(end 24.66086 -322.65112)
				)
				(arc
					(start 24.66086 -323.768974)
					(mid 25.273127 -324.38086)
					(end 25.88514 -323.76872)
				)
			)
		)
		(polygon
			(pts
				(xy 3.494532 -321.688206) (xy 1.005332 -321.688206) (xy 1.005332 -322.996052) (xy 3.494532 -322.996052)
			)
		)
		(polygon
			(pts
				(arc
					(start 7.502906 -321.935856)
					(mid 6.992366 -321.425316)
					(end 6.481826 -321.935856)
				)
				(arc
					(start 6.481826 -322.74891)
					(mid 6.992493 -323.259196)
					(end 7.502906 -322.748656)
				)
			)
		)
		(polygon
			(pts
				(arc
					(start 5.59054 -320.335148)
					(mid 5.079873 -319.824862)
					(end 4.56946 -320.335402)
				)
				(arc
					(start 4.56946 -321.148202)
					(mid 5.08 -321.658742)
					(end 5.59054 -321.148202)
				)
			)
		)
		(polygon
			(pts
				(xy 3.494532 -318.48806) (xy 1.005332 -318.48806) (xy 1.005332 -319.79616) (xy 3.494532 -319.79616)
			)
		)
		(polygon
			(pts
				(arc
					(start 7.502906 -318.735964)
					(mid 6.992366 -318.225424)
					(end 6.481826 -318.735964)
				)
				(arc
					(start 6.481826 -319.549018)
					(mid 6.992493 -320.059304)
					(end 7.502906 -319.548764)
				)
			)
		)
		(polygon
			(pts
				(arc
					(start 5.59054 -317.135256)
					(mid 5.079873 -316.62497)
					(end 4.56946 -317.13551)
				)
				(arc
					(start 4.56946 -317.94831)
					(mid 5.08 -318.45885)
					(end 5.59054 -317.94831)
				)
			)
		)
		(polygon
			(pts
				(arc
					(start 100.6094 -313.2074)
					(mid 100.579642 -313.135558)
					(end 100.5078 -313.1058)
				)
				(arc
					(start 99.1362 -313.1058)
					(mid 99.064358 -313.135558)
					(end 99.0346 -313.2074)
				)
				(arc
					(start 99.0346 -314.4266)
					(mid 99.064358 -314.498442)
					(end 99.1362 -314.5282)
				)
				(arc
					(start 100.5078 -314.5282)
					(mid 100.579642 -314.498442)
					(end 100.6094 -314.4266)
				)
			)
		)
		(polygon
			(pts
				(arc
					(start 96.7994 -313.2074)
					(mid 96.769642 -313.135558)
					(end 96.6978 -313.1058)
				)
				(arc
					(start 95.3262 -313.1058)
					(mid 95.254358 -313.135558)
					(end 95.2246 -313.2074)
				)
				(arc
					(start 95.2246 -314.4266)
					(mid 95.254358 -314.498442)
					(end 95.3262 -314.5282)
				)
				(arc
					(start 96.6978 -314.5282)
					(mid 96.769642 -314.498442)
					(end 96.7994 -314.4266)
				)
			)
		)
		(polygon
			(pts
				(arc
					(start 91.5924 -313.2074)
					(mid 91.562642 -313.135558)
					(end 91.4908 -313.1058)
				)
				(arc
					(start 90.1192 -313.1058)
					(mid 90.047358 -313.135558)
					(end 90.0176 -313.2074)
				)
				(arc
					(start 90.0176 -314.4266)
					(mid 90.047358 -314.498442)
					(end 90.1192 -314.5282)
				)
				(arc
					(start 91.4908 -314.5282)
					(mid 91.562642 -314.498442)
					(end 91.5924 -314.4266)
				)
			)
		)
		(polygon
			(pts
				(arc
					(start 87.7824 -313.2074)
					(mid 87.752642 -313.135558)
					(end 87.6808 -313.1058)
				)
				(arc
					(start 86.3092 -313.1058)
					(mid 86.237358 -313.135558)
					(end 86.2076 -313.2074)
				)
				(arc
					(start 86.2076 -314.4266)
					(mid 86.237358 -314.498442)
					(end 86.3092 -314.5282)
				)
				(arc
					(start 87.6808 -314.5282)
					(mid 87.752642 -314.498442)
					(end 87.7824 -314.4266)
				)
			)
		)
		(polygon
			(pts
				(xy 3.494532 -310.488076) (xy 1.005332 -310.488076) (xy 1.005332 -311.796176) (xy 3.494532 -311.796176)
			)
		)
		(polygon
			(pts
				(arc
					(start 103.3272 -310.3372)
					(mid 103.297442 -310.265358)
					(end 103.2256 -310.2356)
				)
				(arc
					(start 102.0064 -310.2356)
					(mid 101.934558 -310.265358)
					(end 101.9048 -310.3372)
				)
				(arc
					(start 101.9048 -311.7088)
					(mid 101.934558 -311.780642)
					(end 102.0064 -311.8104)
				)
				(arc
					(start 103.2256 -311.8104)
					(mid 103.297442 -311.780642)
					(end 103.3272 -311.7088)
				)
			)
		)
		(polygon
			(pts
				(arc
					(start 7.502906 -310.73598)
					(mid 6.992366 -310.22544)
					(end 6.481826 -310.73598)
				)
				(arc
					(start 6.481826 -311.549034)
					(mid 6.992493 -312.05932)
					(end 7.502906 -311.54878)
				)
			)
		)
		(polygon
			(pts
				(xy 97.575624 -309.02021) (xy 96.384364 -309.02021) (xy 96.384364 -310.18861) (xy 97.575624 -310.18861)
			)
		)
		(polygon
			(pts
				(xy 95.575628 -309.02021) (xy 94.384876 -309.02021) (xy 94.384876 -310.18861) (xy 95.575628 -310.18861)
			)
		)
		(polygon
			(pts
				(xy 93.073728 -309.02021) (xy 91.883992 -309.02021) (xy 91.883992 -310.18861) (xy 93.073728 -310.18861)
			)
		)
		(polygon
			(pts
				(xy 91.077288 -309.02021) (xy 89.91854 -309.02021) (xy 89.91854 -310.18861) (xy 91.077288 -310.18861)
			)
		)
		(polygon
			(pts
				(arc
					(start 5.59054 -309.135272)
					(mid 5.079873 -308.624986)
					(end 4.56946 -309.135526)
				)
				(arc
					(start 4.56946 -309.948326)
					(mid 5.08 -310.458866)
					(end 5.59054 -309.948326)
				)
			)
		)
		(polygon
			(pts
				(xy 98.98761 -307.58638) (xy 97.81921 -307.58638) (xy 97.81921 -308.777894) (xy 98.98761 -308.777894)
			)
		)
		(polygon
			(pts
				(xy 3.494532 -307.288184) (xy 1.005332 -307.288184) (xy 1.005332 -308.59603) (xy 3.494532 -308.59603)
			)
		)
		(polygon
			(pts
				(arc
					(start 7.502906 -307.535834)
					(mid 6.992366 -307.025294)
					(end 6.481826 -307.535834)
				)
				(arc
					(start 6.481826 -308.348888)
					(mid 6.992493 -308.859174)
					(end 7.502906 -308.348634)
				)
			)
		)
		(polygon
			(pts
				(arc
					(start 103.3272 -306.5272)
					(mid 103.297442 -306.455358)
					(end 103.2256 -306.4256)
				)
				(arc
					(start 102.0064 -306.4256)
					(mid 101.934558 -306.455358)
					(end 101.9048 -306.5272)
				)
				(arc
					(start 101.9048 -307.8988)
					(mid 101.934558 -307.970642)
					(end 102.0064 -308.0004)
				)
				(arc
					(start 103.2256 -308.0004)
					(mid 103.297442 -307.970642)
					(end 103.3272 -307.8988)
				)
			)
		)
		(polygon
			(pts
				(xy 98.98761 -305.58486) (xy 97.81921 -305.58486) (xy 97.81921 -306.777136) (xy 98.98761 -306.777136)
			)
		)
		(polygon
			(pts
				(arc
					(start 5.59054 -305.935126)
					(mid 5.079873 -305.42484)
					(end 4.56946 -305.93538)
				)
				(arc
					(start 4.56946 -306.74818)
					(mid 5.08 -307.25872)
					(end 5.59054 -306.74818)
				)
			)
		)
		(polygon
			(pts
				(arc
					(start 78.84414 -305.0159)
					(mid 78.813638 -304.942262)
					(end 78.74 -304.91176)
				)
				(arc
					(start 78.3844 -304.91176)
					(mid 78.310762 -304.942262)
					(end 78.28026 -305.0159)
				)
				(arc
					(start 78.28026 -305.3715)
					(mid 78.310762 -305.445138)
					(end 78.3844 -305.47564)
				)
				(arc
					(start 78.74 -305.47564)
					(mid 78.813638 -305.445138)
					(end 78.84414 -305.3715)
				)
			)
		)
		(polygon
			(pts
				(arc
					(start 77.80274 -305.0159)
					(mid 77.772238 -304.942262)
					(end 77.6986 -304.91176)
				)
				(arc
					(start 77.343 -304.91176)
					(mid 77.269362 -304.942262)
					(end 77.23886 -305.0159)
				)
				(arc
					(start 77.23886 -305.3715)
					(mid 77.269362 -305.445138)
					(end 77.343 -305.47564)
				)
				(arc
					(start 77.6986 -305.47564)
					(mid 77.772238 -305.445138)
					(end 77.80274 -305.3715)
				)
			)
		)
		(polygon
			(pts
				(arc
					(start 85.87994 -304.8381)
					(mid 85.864317 -304.800383)
					(end 85.8266 -304.78476)
				)
				(arc
					(start 85.6234 -304.78476)
					(mid 85.585683 -304.800383)
					(end 85.57006 -304.8381)
				)
				(arc
					(start 85.57006 -305.0921)
					(mid 85.585683 -305.129817)
					(end 85.6234 -305.14544)
				)
				(arc
					(start 85.8266 -305.14544)
					(mid 85.864317 -305.129817)
					(end 85.87994 -305.0921)
				)
			)
		)
		(polygon
			(pts
				(arc
					(start 85.87994 -304.2793)
					(mid 85.864317 -304.241583)
					(end 85.8266 -304.22596)
				)
				(arc
					(start 85.6234 -304.22596)
					(mid 85.585683 -304.241583)
					(end 85.57006 -304.2793)
				)
				(arc
					(start 85.57006 -304.5333)
					(mid 85.585683 -304.571017)
					(end 85.6234 -304.58664)
				)
				(arc
					(start 85.8266 -304.58664)
					(mid 85.864317 -304.571017)
					(end 85.87994 -304.5333)
				)
			)
		)
		(polygon
			(pts
				(xy 3.494532 -304.088038) (xy 1.005332 -304.088038) (xy 1.005332 -305.396138) (xy 3.494532 -305.396138)
			)
		)
		(polygon
			(pts
				(xy 90.14079 -304.084736) (xy 88.97239 -304.084736) (xy 88.97239 -305.277774) (xy 90.14079 -305.277774)
			)
		)
		(polygon
			(pts
				(arc
					(start 78.84414 -303.9745)
					(mid 78.813638 -303.900862)
					(end 78.74 -303.87036)
				)
				(arc
					(start 78.3844 -303.87036)
					(mid 78.310762 -303.900862)
					(end 78.28026 -303.9745)
				)
				(arc
					(start 78.28026 -304.3301)
					(mid 78.310762 -304.403738)
					(end 78.3844 -304.43424)
				)
				(arc
					(start 78.74 -304.43424)
					(mid 78.813638 -304.403738)
					(end 78.84414 -304.3301)
				)
			)
		)
		(polygon
			(pts
				(arc
					(start 77.80274 -303.9745)
					(mid 77.772238 -303.900862)
					(end 77.6986 -303.87036)
				)
				(arc
					(start 77.343 -303.87036)
					(mid 77.269362 -303.900862)
					(end 77.23886 -303.9745)
				)
				(arc
					(start 77.23886 -304.3301)
					(mid 77.269362 -304.403738)
					(end 77.343 -304.43424)
				)
				(arc
					(start 77.6986 -304.43424)
					(mid 77.772238 -304.403738)
					(end 77.80274 -304.3301)
				)
			)
		)
		(polygon
			(pts
				(arc
					(start 7.502906 -304.335942)
					(mid 6.992366 -303.825402)
					(end 6.481826 -304.335942)
				)
				(arc
					(start 6.481826 -305.148996)
					(mid 6.992493 -305.659282)
					(end 7.502906 -305.148742)
				)
			)
		)
		(polygon
			(pts
				(arc
					(start 5.59054 -302.735234)
					(mid 5.079873 -302.224948)
					(end 4.56946 -302.735488)
				)
				(arc
					(start 4.56946 -303.548288)
					(mid 5.08 -304.058828)
					(end 5.59054 -303.548288)
				)
			)
		)
		(polygon
			(pts
				(xy 3.494532 -300.888146) (xy 1.005332 -300.888146) (xy 1.005332 -302.195992) (xy 3.494532 -302.195992)
			)
		)
		(polygon
			(pts
				(arc
					(start 7.502906 -301.135796)
					(mid 6.992366 -300.625256)
					(end 6.481826 -301.135796)
				)
				(arc
					(start 6.481826 -301.94885)
					(mid 6.992493 -302.459136)
					(end 7.502906 -301.948596)
				)
			)
		)
		(polygon
			(pts
				(xy 97.574862 -300.17339) (xy 96.384618 -300.17339) (xy 96.384618 -301.34179) (xy 97.574862 -301.34179)
			)
		)
		(polygon
			(pts
				(xy 95.576898 -300.17339) (xy 94.383098 -300.17339) (xy 94.383098 -301.34179) (xy 95.576898 -301.34179)
			)
		)
		(polygon
			(pts
				(arc
					(start 5.59054 -299.535088)
					(mid 5.079873 -299.024802)
					(end 4.56946 -299.535342)
				)
				(arc
					(start 4.56946 -300.348142)
					(mid 5.08 -300.858682)
					(end 5.59054 -300.348142)
				)
			)
		)
		(polygon
			(pts
				(xy 3.494532 -297.688) (xy 1.005332 -297.688) (xy 1.005332 -298.9961) (xy 3.494532 -298.9961)
			)
		)
		(polygon
			(pts
				(arc
					(start 7.502906 -297.935904)
					(mid 6.992366 -297.425364)
					(end 6.481826 -297.935904)
				)
				(arc
					(start 6.481826 -298.748958)
					(mid 6.992493 -299.259244)
					(end 7.502906 -298.748704)
				)
			)
		)
		(polygon
			(pts
				(arc
					(start 100.6094 -295.9354)
					(mid 100.579642 -295.863558)
					(end 100.5078 -295.8338)
				)
				(arc
					(start 99.1362 -295.8338)
					(mid 99.064358 -295.863558)
					(end 99.0346 -295.9354)
				)
				(arc
					(start 99.0346 -297.1546)
					(mid 99.064358 -297.226442)
					(end 99.1362 -297.2562)
				)
				(arc
					(start 100.5078 -297.2562)
					(mid 100.579642 -297.226442)
					(end 100.6094 -297.1546)
				)
			)
		)
		(polygon
			(pts
				(arc
					(start 96.7994 -295.9354)
					(mid 96.769642 -295.863558)
					(end 96.6978 -295.8338)
				)
				(arc
					(start 95.3262 -295.8338)
					(mid 95.254358 -295.863558)
					(end 95.2246 -295.9354)
				)
				(arc
					(start 95.2246 -297.1546)
					(mid 95.254358 -297.226442)
					(end 95.3262 -297.2562)
				)
				(arc
					(start 96.6978 -297.2562)
					(mid 96.769642 -297.226442)
					(end 96.7994 -297.1546)
				)
			)
		)
		(polygon
			(pts
				(arc
					(start 5.59054 -296.335196)
					(mid 5.079873 -295.82491)
					(end 4.56946 -296.33545)
				)
				(arc
					(start 4.56946 -297.14825)
					(mid 5.08 -297.65879)
					(end 5.59054 -297.14825)
				)
			)
		)
		(polygon
			(pts
				(xy 3.494532 -294.488108) (xy 1.005332 -294.488108) (xy 1.005332 -295.796208) (xy 3.494532 -295.796208)
			)
		)
		(polygon
			(pts
				(arc
					(start 7.502906 -294.736012)
					(mid 6.992366 -294.225472)
					(end 6.481826 -294.736012)
				)
				(arc
					(start 6.481826 -295.549066)
					(mid 6.992493 -296.059352)
					(end 7.502906 -295.548812)
				)
			)
		)
		(polygon
			(pts
				(arc
					(start 5.59054 -293.13505)
					(mid 5.079873 -292.624764)
					(end 4.56946 -293.135304)
				)
				(arc
					(start 4.56946 -293.948104)
					(mid 5.08 -294.458644)
					(end 5.59054 -293.948104)
				)
			)
		)
		(polygon
			(pts
				(xy 3.494532 -291.288216) (xy 1.005332 -291.288216) (xy 1.005332 -292.596062) (xy 3.494532 -292.596062)
			)
		)
		(polygon
			(pts
				(arc
					(start 7.502906 -291.535866)
					(mid 6.992366 -291.025326)
					(end 6.481826 -291.535866)
				)
				(arc
					(start 6.481826 -292.34892)
					(mid 6.992493 -292.859206)
					(end 7.502906 -292.348666)
				)
			)
		)
		(polygon
			(pts
				(arc
					(start 5.59054 -289.935158)
					(mid 5.079873 -289.424872)
					(end 4.56946 -289.935412)
				)
				(arc
					(start 4.56946 -290.748212)
					(mid 5.08 -291.258752)
					(end 5.59054 -290.748212)
				)
			)
		)
		(polygon
			(pts
				(xy 3.494532 -288.08807) (xy 1.005332 -288.08807) (xy 1.005332 -289.39617) (xy 3.494532 -289.39617)
			)
		)
		(polygon
			(pts
				(arc
					(start 7.502906 -288.33572)
					(mid 6.992239 -287.825434)
					(end 6.481826 -288.335974)
				)
				(arc
					(start 6.481826 -289.148774)
					(mid 6.992366 -289.659314)
					(end 7.502906 -289.148774)
				)
			)
		)
		(polygon
			(pts
				(xy 225.203004 -284.843982) (xy 223.196658 -284.843982) (xy 223.196658 -286.736028) (xy 225.203258 -286.736028)
				(xy 225.203258 -284.844236)
			)
		)
		(polygon
			(pts
				(xy 40.20312 -284.843982) (xy 38.196774 -284.843982) (xy 38.196774 -286.736028) (xy 40.203374 -286.736028)
				(xy 40.203374 -284.844236)
			)
		)
		(polygon
			(pts
				(arc
					(start 222.339154 -285.231078)
					(mid 221.726887 -284.619192)
					(end 221.114874 -285.231332)
				)
				(arc
					(start 221.114874 -286.348932)
					(mid 221.727014 -286.961072)
					(end 222.339154 -286.348932)
				)
			)
		)
		(polygon
			(pts
				(arc
					(start 37.33927 -285.231078)
					(mid 36.727003 -284.619192)
					(end 36.11499 -285.231332)
				)
				(arc
					(start 36.11499 -286.348932)
					(mid 36.72713 -286.961072)
					(end 37.33927 -286.348932)
				)
			)
		)
		(polygon
			(pts
				(arc
					(start 5.59054 -283.53512)
					(mid 5.079873 -283.024834)
					(end 4.56946 -283.535374)
				)
				(arc
					(start 4.56946 -284.348174)
					(mid 5.08 -284.858714)
					(end 5.59054 -284.348174)
				)
			)
		)
		(polygon
			(pts
				(arc
					(start 220.840554 -282.983432)
					(mid 220.329887 -282.473146)
					(end 219.819474 -282.983686)
				)
				(arc
					(start 219.819474 -283.796486)
					(mid 220.330014 -284.307026)
					(end 220.840554 -283.796486)
				)
			)
		)
		(polygon
			(pts
				(arc
					(start 35.84067 -282.983432)
					(mid 35.330003 -282.473146)
					(end 34.81959 -282.983686)
				)
				(arc
					(start 34.81959 -283.796486)
					(mid 35.33013 -284.307026)
					(end 35.84067 -283.796486)
				)
			)
		)
		(polygon
			(pts
				(xy 225.203004 -282.443936) (xy 223.196658 -282.443936) (xy 223.196658 -284.336236) (xy 225.203258 -284.336236)
				(xy 225.203258 -282.44419)
			)
		)
		(polygon
			(pts
				(xy 40.20312 -282.443936) (xy 38.196774 -282.443936) (xy 38.196774 -284.336236) (xy 40.203374 -284.336236)
				(xy 40.203374 -282.44419)
			)
		)
		(polygon
			(pts
				(xy 3.494532 -281.688032) (xy 1.005332 -281.688032) (xy 1.005332 -282.996132) (xy 3.494532 -282.996132)
			)
		)
		(polygon
			(pts
				(arc
					(start 7.502906 -281.986482)
					(mid 6.992239 -281.476196)
					(end 6.481826 -281.986736)
				)
				(arc
					(start 6.481826 -282.799536)
					(mid 6.992366 -283.310076)
					(end 7.502906 -282.799536)
				)
			)
		)
		(polygon
			(pts
				(xy 225.203004 -280.04389) (xy 223.196658 -280.04389) (xy 223.196658 -281.93619) (xy 225.203258 -281.93619)
				(xy 225.203258 -280.044144)
			)
		)
		(polygon
			(pts
				(xy 40.20312 -280.04389) (xy 38.196774 -280.04389) (xy 38.196774 -281.93619) (xy 40.203374 -281.93619)
				(xy 40.203374 -280.044144)
			)
		)
		(polygon
			(pts
				(arc
					(start 5.59054 -280.335228)
					(mid 5.079873 -279.824942)
					(end 4.56946 -280.335482)
				)
				(arc
					(start 4.56946 -281.148282)
					(mid 5.08 -281.658822)
					(end 5.59054 -281.148282)
				)
			)
		)
		(polygon
			(pts
				(arc
					(start 222.339154 -280.430986)
					(mid 221.726887 -279.8191)
					(end 221.114874 -280.43124)
				)
				(arc
					(start 221.114874 -281.54884)
					(mid 221.727014 -282.16098)
					(end 222.339154 -281.54884)
				)
			)
		)
		(polygon
			(pts
				(arc
					(start 37.33927 -280.430986)
					(mid 36.727003 -279.8191)
					(end 36.11499 -280.43124)
				)
				(arc
					(start 36.11499 -281.54884)
					(mid 36.72713 -282.16098)
					(end 37.33927 -281.54884)
				)
			)
		)
		(polygon
			(pts
				(xy 3.494532 -278.48814) (xy 1.005332 -278.48814) (xy 1.005332 -279.795986) (xy 3.494532 -279.795986)
			)
		)
		(polygon
			(pts
				(arc
					(start 7.502906 -278.786336)
					(mid 6.992239 -278.27605)
					(end 6.481826 -278.78659)
				)
				(arc
					(start 6.481826 -279.59939)
					(mid 6.992366 -280.10993)
					(end 7.502906 -279.59939)
				)
			)
		)
		(polygon
			(pts
				(arc
					(start 220.840554 -278.18334)
					(mid 220.329887 -277.673054)
					(end 219.819474 -278.183594)
				)
				(arc
					(start 219.819474 -278.996394)
					(mid 220.330014 -279.506934)
					(end 220.840554 -278.996394)
				)
			)
		)
		(polygon
			(pts
				(arc
					(start 35.84067 -278.18334)
					(mid 35.330003 -277.673054)
					(end 34.81959 -278.183594)
				)
				(arc
					(start 34.81959 -278.996394)
					(mid 35.33013 -279.506934)
					(end 35.84067 -278.996394)
				)
			)
		)
		(polygon
			(pts
				(xy 225.203004 -277.643844) (xy 223.196658 -277.643844) (xy 223.196658 -279.536144) (xy 225.203258 -279.536144)
				(xy 225.203258 -277.644098)
			)
		)
		(polygon
			(pts
				(xy 40.20312 -277.643844) (xy 38.196774 -277.643844) (xy 38.196774 -279.536144) (xy 40.203374 -279.536144)
				(xy 40.203374 -277.644098)
			)
		)
		(polygon
			(pts
				(xy 225.203004 -275.243798) (xy 223.196658 -275.243798) (xy 223.196658 -277.136098) (xy 225.203258 -277.136098)
				(xy 225.203258 -275.244052)
			)
		)
		(polygon
			(pts
				(xy 40.20312 -275.243798) (xy 38.196774 -275.243798) (xy 38.196774 -277.136098) (xy 40.203374 -277.136098)
				(xy 40.203374 -275.244052)
			)
		)
		(polygon
			(pts
				(arc
					(start 222.339154 -275.630894)
					(mid 221.726887 -275.019008)
					(end 221.114874 -275.631148)
				)
				(arc
					(start 221.114874 -276.748748)
					(mid 221.727014 -277.360888)
					(end 222.339154 -276.748748)
				)
			)
		)
		(polygon
			(pts
				(arc
					(start 37.33927 -275.630894)
					(mid 36.727003 -275.019008)
					(end 36.11499 -275.631148)
				)
				(arc
					(start 36.11499 -276.748748)
					(mid 36.72713 -277.360888)
					(end 37.33927 -276.748748)
				)
			)
		)
		(polygon
			(pts
				(arc
					(start 220.840554 -273.383502)
					(mid 220.329887 -272.873216)
					(end 219.819474 -273.383756)
				)
				(arc
					(start 219.819474 -274.196556)
					(mid 220.330014 -274.707096)
					(end 220.840554 -274.196556)
				)
			)
		)
		(polygon
			(pts
				(arc
					(start 35.84067 -273.383502)
					(mid 35.330003 -272.873216)
					(end 34.81959 -273.383756)
				)
				(arc
					(start 34.81959 -274.196556)
					(mid 35.33013 -274.707096)
					(end 35.84067 -274.196556)
				)
			)
		)
		(polygon
			(pts
				(xy 225.203004 -272.844006) (xy 223.196658 -272.844006) (xy 223.196658 -274.736052) (xy 225.203258 -274.736052)
				(xy 225.203258 -272.84426)
			)
		)
		(polygon
			(pts
				(xy 40.20312 -272.844006) (xy 38.196774 -272.844006) (xy 38.196774 -274.736052) (xy 40.203374 -274.736052)
				(xy 40.203374 -272.84426)
			)
		)
		(polygon
			(pts
				(arc
					(start 233.897424 -266.57935)
					(mid 233.386884 -266.06881)
					(end 232.876344 -266.57935)
				)
				(arc
					(start 232.876344 -267.392404)
					(mid 233.387011 -267.90269)
					(end 233.897424 -267.39215)
				)
			)
		)
		(polygon
			(pts
				(arc
					(start 48.89754 -266.579096)
					(mid 48.386873 -266.06881)
					(end 47.87646 -266.57935)
				)
				(arc
					(start 47.87646 -267.39215)
					(mid 48.387 -267.90269)
					(end 48.89754 -267.39215)
				)
			)
		)
		(polygon
			(pts
				(xy 228.39299 -266.043918) (xy 226.386644 -266.043918) (xy 226.386644 -267.936218) (xy 228.393244 -267.936218)
				(xy 228.393244 -266.044172)
			)
		)
		(polygon
			(pts
				(xy 43.393106 -266.043918) (xy 41.38676 -266.043918) (xy 41.38676 -267.936218) (xy 43.39336 -267.936218)
				(xy 43.39336 -266.044172)
			)
		)
		(polygon
			(pts
				(arc
					(start 230.720138 -266.300712)
					(mid 231.230424 -265.790045)
					(end 230.719884 -265.279632)
				)
				(arc
					(start 229.907084 -265.279632)
					(mid 229.396544 -265.790172)
					(end 229.907084 -266.300712)
				)
			)
		)
		(polygon
			(pts
				(arc
					(start 45.72 -266.300712)
					(mid 46.23054 -265.790172)
					(end 45.72 -265.279632)
				)
				(arc
					(start 44.906946 -265.279632)
					(mid 44.39666 -265.790299)
					(end 44.9072 -266.300712)
				)
			)
		)
		(polygon
			(pts
				(xy 225.203258 -262.443976) (xy 223.196658 -262.443976) (xy 223.196658 -264.335768) (xy 223.196912 -264.336022)
				(xy 225.203258 -264.336022)
			)
		)
		(polygon
			(pts
				(xy 40.203374 -262.443976) (xy 38.196774 -262.443976) (xy 38.196774 -264.335768) (xy 38.197028 -264.336022)
				(xy 40.203374 -264.336022)
			)
		)
		(polygon
			(pts
				(arc
					(start 222.339154 -262.831072)
					(mid 221.726887 -262.219186)
					(end 221.114874 -262.831326)
				)
				(arc
					(start 221.114874 -263.948926)
					(mid 221.727014 -264.561066)
					(end 222.339154 -263.948926)
				)
			)
		)
		(polygon
			(pts
				(arc
					(start 37.33927 -262.831072)
					(mid 36.727003 -262.219186)
					(end 36.11499 -262.831326)
				)
				(arc
					(start 36.11499 -263.948926)
					(mid 36.72713 -264.561066)
					(end 37.33927 -263.948926)
				)
			)
		)
		(polygon
			(pts
				(arc
					(start 220.840554 -260.583426)
					(mid 220.329887 -260.07314)
					(end 219.819474 -260.58368)
				)
				(arc
					(start 219.819474 -261.39648)
					(mid 220.330014 -261.90702)
					(end 220.840554 -261.39648)
				)
			)
		)
		(polygon
			(pts
				(arc
					(start 35.84067 -260.583426)
					(mid 35.330003 -260.07314)
					(end 34.81959 -260.58368)
				)
				(arc
					(start 34.81959 -261.39648)
					(mid 35.33013 -261.90702)
					(end 35.84067 -261.39648)
				)
			)
		)
		(polygon
			(pts
				(xy 225.203004 -260.04393) (xy 223.196658 -260.04393) (xy 223.196658 -261.93623) (xy 225.203258 -261.93623)
				(xy 225.203258 -260.044184)
			)
		)
		(polygon
			(pts
				(xy 40.20312 -260.04393) (xy 38.196774 -260.04393) (xy 38.196774 -261.93623) (xy 40.203374 -261.93623)
				(xy 40.203374 -260.044184)
			)
		)
		(polygon
			(pts
				(xy 225.203004 -257.643884) (xy 223.196658 -257.643884) (xy 223.196658 -259.536184) (xy 225.203258 -259.536184)
				(xy 225.203258 -257.644138)
			)
		)
		(polygon
			(pts
				(xy 40.20312 -257.643884) (xy 38.196774 -257.643884) (xy 38.196774 -259.536184) (xy 40.203374 -259.536184)
				(xy 40.203374 -257.644138)
			)
		)
		(polygon
			(pts
				(xy 23.803356 -246.46382) (xy 21.796756 -246.46382) (xy 21.796756 -248.355866) (xy 21.79701 -248.35612)
				(xy 23.803356 -248.35612)
			)
		)
		(polygon
			(pts
				(arc
					(start 27.18054 -244.603524)
					(mid 26.67 -244.092984)
					(end 26.15946 -244.603524)
				)
				(arc
					(start 26.15946 -245.416578)
					(mid 26.670127 -245.926864)
					(end 27.18054 -245.416324)
				)
			)
		)
		(polygon
			(pts
				(xy 23.803356 -244.063774) (xy 21.796756 -244.063774) (xy 21.796756 -245.95582) (xy 21.79701 -245.956074)
				(xy 23.803356 -245.956074)
			)
		)
		(polygon
			(pts
				(xy 23.803356 -241.663982) (xy 21.796756 -241.663982) (xy 21.796756 -243.555774) (xy 21.79701 -243.556028)
				(xy 23.803356 -243.556028)
			)
		)
		(polygon
			(pts
				(arc
					(start 25.88514 -242.051078)
					(mid 25.273 -241.438938)
					(end 24.66086 -242.051078)
				)
				(arc
					(start 24.66086 -243.168932)
					(mid 25.273127 -243.780818)
					(end 25.88514 -243.168678)
				)
			)
		)
		(polygon
			(pts
				(arc
					(start 17.78254 -238.603282)
					(mid 17.272 -238.092742)
					(end 16.76146 -238.603282)
				)
				(arc
					(start 16.76146 -239.416336)
					(mid 17.272127 -239.926622)
					(end 17.78254 -239.416082)
				)
			)
		)
		(polygon
			(pts
				(arc
					(start 42.92854 -238.584232)
					(mid 42.417873 -238.073946)
					(end 41.90746 -238.584486)
				)
				(arc
					(start 41.90746 -239.397286)
					(mid 42.418 -239.907826)
					(end 42.92854 -239.397286)
				)
			)
		)
		(polygon
			(pts
				(xy 20.61337 -238.063786) (xy 18.60677 -238.063786) (xy 18.60677 -239.955832) (xy 18.607024 -239.956086)
				(xy 20.61337 -239.956086)
			)
		)
		(polygon
			(pts
				(arc
					(start 5.59054 -231.935274)
					(mid 5.079873 -231.424988)
					(end 4.56946 -231.935528)
				)
				(arc
					(start 4.56946 -232.748328)
					(mid 5.08 -233.258868)
					(end 5.59054 -232.748328)
				)
			)
		)
		(polygon
			(pts
				(arc
					(start 27.18054 -231.803448)
					(mid 26.67 -231.292908)
					(end 26.15946 -231.803448)
				)
				(arc
					(start 26.15946 -232.616502)
					(mid 26.670127 -233.126788)
					(end 27.18054 -232.616248)
				)
			)
		)
		(polygon
			(pts
				(xy 23.803356 -231.263952) (xy 21.796756 -231.263952) (xy 21.796756 -233.155744) (xy 21.79701 -233.155998)
				(xy 23.803356 -233.155998)
			)
		)
		(polygon
			(pts
				(xy 3.494532 -230.088186) (xy 1.005332 -230.088186) (xy 1.005332 -231.396032) (xy 3.494532 -231.396032)
			)
		)
		(polygon
			(pts
				(arc
					(start 7.502906 -230.335582)
					(mid 6.992239 -229.825296)
					(end 6.481826 -230.335836)
				)
				(arc
					(start 6.481826 -231.148636)
					(mid 6.992366 -231.659176)
					(end 7.502906 -231.148636)
				)
			)
		)
		(polygon
			(pts
				(xy 23.803356 -228.863906) (xy 21.796756 -228.863906) (xy 21.796756 -230.755952) (xy 21.79701 -230.756206)
				(xy 23.803356 -230.756206)
			)
		)
		(polygon
			(pts
				(arc
					(start 25.88514 -229.251256)
					(mid 25.273 -228.639116)
					(end 24.66086 -229.251256)
				)
				(arc
					(start 24.66086 -230.36911)
					(mid 25.273127 -230.980996)
					(end 25.88514 -230.368856)
				)
			)
		)
		(polygon
			(pts
				(arc
					(start 5.59054 -228.735128)
					(mid 5.079873 -228.224842)
					(end 4.56946 -228.735382)
				)
				(arc
					(start 4.56946 -229.548182)
					(mid 5.08 -230.058722)
					(end 5.59054 -229.548182)
				)
			)
		)
		(polygon
			(pts
				(xy 3.494532 -226.88804) (xy 1.005332 -226.88804) (xy 1.005332 -228.19614) (xy 3.494532 -228.19614)
			)
		)
		(polygon
			(pts
				(arc
					(start 7.502906 -227.13569)
					(mid 6.992239 -226.625404)
					(end 6.481826 -227.135944)
				)
				(arc
					(start 6.481826 -227.948744)
					(mid 6.992366 -228.459284)
					(end 7.502906 -227.948744)
				)
			)
		)
		(polygon
			(pts
				(arc
					(start 27.18054 -227.00361)
					(mid 26.67 -226.49307)
					(end 26.15946 -227.00361)
				)
				(arc
					(start 26.15946 -227.816664)
					(mid 26.670127 -228.32695)
					(end 27.18054 -227.81641)
				)
			)
		)
		(polygon
			(pts
				(xy 23.803356 -226.46386) (xy 21.796756 -226.46386) (xy 21.796756 -228.355906) (xy 21.79701 -228.35616)
				(xy 23.803356 -228.35616)
			)
		)
		(polygon
			(pts
				(xy 23.803356 -224.063814) (xy 21.796756 -224.063814) (xy 21.796756 -225.95586) (xy 21.79701 -225.956114)
				(xy 23.803356 -225.956114)
			)
		)
		(polygon
			(pts
				(arc
					(start 25.88514 -224.451164)
					(mid 25.273 -223.839024)
					(end 24.66086 -224.451164)
				)
				(arc
					(start 24.66086 -225.569018)
					(mid 25.273127 -226.180904)
					(end 25.88514 -225.568764)
				)
			)
		)
		(polygon
			(pts
				(xy 3.494532 -223.688148) (xy 1.005332 -223.688148) (xy 1.005332 -224.995994) (xy 3.494532 -224.995994)
			)
		)
		(polygon
			(pts
				(arc
					(start 7.502906 -223.897444)
					(mid 6.992239 -223.387158)
					(end 6.481826 -223.897698)
				)
				(arc
					(start 6.481826 -224.710498)
					(mid 6.992366 -225.221038)
					(end 7.502906 -224.710498)
				)
			)
		)
		(polygon
			(pts
				(arc
					(start 5.59054 -222.33509)
					(mid 5.079873 -221.824804)
					(end 4.56946 -222.335344)
				)
				(arc
					(start 4.56946 -223.148144)
					(mid 5.08 -223.658684)
					(end 5.59054 -223.148144)
				)
			)
		)
		(polygon
			(pts
				(arc
					(start 27.18054 -222.203518)
					(mid 26.67 -221.692978)
					(end 26.15946 -222.203518)
				)
				(arc
					(start 26.15946 -223.016572)
					(mid 26.670127 -223.526858)
					(end 27.18054 -223.016318)
				)
			)
		)
		(polygon
			(pts
				(xy 23.803356 -221.663768) (xy 21.796756 -221.663768) (xy 21.796756 -223.555814) (xy 21.79701 -223.556068)
				(xy 23.803356 -223.556068)
			)
		)
		(polygon
			(pts
				(xy 3.494532 -220.488002) (xy 1.005332 -220.488002) (xy 1.005332 -221.796102) (xy 3.494532 -221.796102)
			)
		)
		(polygon
			(pts
				(arc
					(start 7.502906 -220.685106)
					(mid 6.992366 -220.174566)
					(end 6.481826 -220.685106)
				)
				(arc
					(start 6.481826 -221.49816)
					(mid 6.992493 -222.008446)
					(end 7.502906 -221.497906)
				)
			)
		)
		(polygon
			(pts
				(xy 23.803356 -219.263722) (xy 21.796756 -219.263722) (xy 21.796756 -221.155768) (xy 21.79701 -221.156022)
				(xy 23.803356 -221.156022)
			)
		)
		(polygon
			(pts
				(arc
					(start 25.88514 -219.650818)
					(mid 25.272873 -219.038932)
					(end 24.66086 -219.651072)
				)
				(arc
					(start 24.66086 -220.768672)
					(mid 25.273 -221.380812)
					(end 25.88514 -220.768672)
				)
			)
		)
		(polygon
			(pts
				(arc
					(start 100.6094 -218.8464)
					(mid 100.579642 -218.774558)
					(end 100.5078 -218.7448)
				)
				(arc
					(start 99.1362 -218.7448)
					(mid 99.064358 -218.774558)
					(end 99.0346 -218.8464)
				)
				(arc
					(start 99.0346 -220.0656)
					(mid 99.064358 -220.137442)
					(end 99.1362 -220.1672)
				)
				(arc
					(start 100.5078 -220.1672)
					(mid 100.579642 -220.137442)
					(end 100.6094 -220.0656)
				)
			)
		)
		(polygon
			(pts
				(arc
					(start 96.7994 -218.8464)
					(mid 96.769642 -218.774558)
					(end 96.6978 -218.7448)
				)
				(arc
					(start 95.3262 -218.7448)
					(mid 95.254358 -218.774558)
					(end 95.2246 -218.8464)
				)
				(arc
					(start 95.2246 -220.0656)
					(mid 95.254358 -220.137442)
					(end 95.3262 -220.1672)
				)
				(arc
					(start 96.6978 -220.1672)
					(mid 96.769642 -220.137442)
					(end 96.7994 -220.0656)
				)
			)
		)
		(polygon
			(pts
				(arc
					(start 91.5924 -218.8464)
					(mid 91.562642 -218.774558)
					(end 91.4908 -218.7448)
				)
				(arc
					(start 90.1192 -218.7448)
					(mid 90.047358 -218.774558)
					(end 90.0176 -218.8464)
				)
				(arc
					(start 90.0176 -220.0656)
					(mid 90.047358 -220.137442)
					(end 90.1192 -220.1672)
				)
				(arc
					(start 91.4908 -220.1672)
					(mid 91.562642 -220.137442)
					(end 91.5924 -220.0656)
				)
			)
		)
		(polygon
			(pts
				(arc
					(start 87.7824 -218.8464)
					(mid 87.752642 -218.774558)
					(end 87.6808 -218.7448)
				)
				(arc
					(start 86.3092 -218.7448)
					(mid 86.237358 -218.774558)
					(end 86.2076 -218.8464)
				)
				(arc
					(start 86.2076 -220.0656)
					(mid 86.237358 -220.137442)
					(end 86.3092 -220.1672)
				)
				(arc
					(start 87.6808 -220.1672)
					(mid 87.752642 -220.137442)
					(end 87.7824 -220.0656)
				)
			)
		)
		(polygon
			(pts
				(arc
					(start 5.59054 -219.135198)
					(mid 5.079873 -218.624912)
					(end 4.56946 -219.135452)
				)
				(arc
					(start 4.56946 -219.948252)
					(mid 5.08 -220.458792)
					(end 5.59054 -219.948252)
				)
			)
		)
		(polygon
			(pts
				(xy 3.494532 -217.28811) (xy 1.005332 -217.28811) (xy 1.005332 -218.59621) (xy 3.494532 -218.59621)
			)
		)
		(polygon
			(pts
				(arc
					(start 7.502906 -217.48496)
					(mid 6.992239 -216.974674)
					(end 6.481826 -217.485214)
				)
				(arc
					(start 6.481826 -218.298014)
					(mid 6.992366 -218.808554)
					(end 7.502906 -218.298014)
				)
			)
		)
		(polygon
			(pts
				(arc
					(start 5.59054 -215.935052)
					(mid 5.079873 -215.424766)
					(end 4.56946 -215.935306)
				)
				(arc
					(start 4.56946 -216.748106)
					(mid 5.08 -217.258646)
					(end 5.59054 -216.748106)
				)
			)
		)
		(polygon
			(pts
				(xy 97.575878 -214.65921) (xy 96.383602 -214.65921) (xy 96.383602 -215.82761) (xy 97.575878 -215.82761)
			)
		)
		(polygon
			(pts
				(xy 95.576136 -214.65921) (xy 94.383352 -214.65921) (xy 94.383352 -215.82761) (xy 95.576136 -215.82761)
			)
		)
		(polygon
			(pts
				(xy 93.074236 -214.65921) (xy 91.882976 -214.65921) (xy 91.882976 -215.82761) (xy 93.074236 -215.82761)
			)
		)
		(polygon
			(pts
				(xy 91.076526 -214.65921) (xy 89.88933 -214.65921) (xy 89.88933 -215.82761) (xy 91.076526 -215.82761)
			)
		)
		(polygon
			(pts
				(xy 3.494532 -214.088218) (xy 1.005332 -214.088218) (xy 1.005332 -215.396064) (xy 3.494532 -215.396064)
			)
		)
		(polygon
			(pts
				(arc
					(start 7.502906 -214.284814)
					(mid 6.992239 -213.774528)
					(end 6.481826 -214.285068)
				)
				(arc
					(start 6.481826 -215.097868)
					(mid 6.992366 -215.608408)
					(end 7.502906 -215.097868)
				)
			)
		)
		(polygon
			(pts
				(arc
					(start 5.59054 -212.73516)
					(mid 5.079873 -212.224874)
					(end 4.56946 -212.735414)
				)
				(arc
					(start 4.56946 -213.548214)
					(mid 5.08 -214.058754)
					(end 5.59054 -213.548214)
				)
			)
		)
		(polygon
			(pts
				(xy 3.494532 -210.888072) (xy 1.005332 -210.888072) (xy 1.005332 -212.196172) (xy 3.494532 -212.196172)
			)
		)
		(polygon
			(pts
				(arc
					(start 7.502906 -211.135722)
					(mid 6.992239 -210.625436)
					(end 6.481826 -211.135976)
				)
				(arc
					(start 6.481826 -211.948776)
					(mid 6.992366 -212.459316)
					(end 7.502906 -211.948776)
				)
			)
		)
		(polygon
			(pts
				(arc
					(start 78.66634 -210.6676)
					(mid 78.635838 -210.593962)
					(end 78.5622 -210.56346)
				)
				(arc
					(start 78.2066 -210.56346)
					(mid 78.132962 -210.593962)
					(end 78.10246 -210.6676)
				)
				(arc
					(start 78.10246 -211.0232)
					(mid 78.132962 -211.096838)
					(end 78.2066 -211.12734)
				)
				(arc
					(start 78.5622 -211.12734)
					(mid 78.635838 -211.096838)
					(end 78.66634 -211.0232)
				)
			)
		)
		(polygon
			(pts
				(arc
					(start 77.62494 -210.6676)
					(mid 77.594438 -210.593962)
					(end 77.5208 -210.56346)
				)
				(arc
					(start 77.1652 -210.56346)
					(mid 77.091562 -210.593962)
					(end 77.06106 -210.6676)
				)
				(arc
					(start 77.06106 -211.0232)
					(mid 77.091562 -211.096838)
					(end 77.1652 -211.12734)
				)
				(arc
					(start 77.5208 -211.12734)
					(mid 77.594438 -211.096838)
					(end 77.62494 -211.0232)
				)
			)
		)
		(polygon
			(pts
				(arc
					(start 85.70214 -210.4771)
					(mid 85.686517 -210.439383)
					(end 85.6488 -210.42376)
				)
				(arc
					(start 85.4456 -210.42376)
					(mid 85.407883 -210.439383)
					(end 85.39226 -210.4771)
				)
				(arc
					(start 85.39226 -210.7311)
					(mid 85.407883 -210.768817)
					(end 85.4456 -210.78444)
				)
				(arc
					(start 85.6488 -210.78444)
					(mid 85.686517 -210.768817)
					(end 85.70214 -210.7311)
				)
			)
		)
		(polygon
			(pts
				(arc
					(start 85.70214 -209.9183)
					(mid 85.686517 -209.880583)
					(end 85.6488 -209.86496)
				)
				(arc
					(start 85.4456 -209.86496)
					(mid 85.407883 -209.880583)
					(end 85.39226 -209.9183)
				)
				(arc
					(start 85.39226 -210.1723)
					(mid 85.407883 -210.210017)
					(end 85.4456 -210.22564)
				)
				(arc
					(start 85.6488 -210.22564)
					(mid 85.686517 -210.210017)
					(end 85.70214 -210.1723)
				)
			)
		)
		(polygon
			(pts
				(xy 90.14079 -209.72399) (xy 88.97239 -209.72399) (xy 88.97239 -210.916266) (xy 90.14079 -210.916266)
			)
		)
		(polygon
			(pts
				(arc
					(start 78.66634 -209.6262)
					(mid 78.635838 -209.552562)
					(end 78.5622 -209.52206)
				)
				(arc
					(start 78.2066 -209.52206)
					(mid 78.132962 -209.552562)
					(end 78.10246 -209.6262)
				)
				(arc
					(start 78.10246 -209.9818)
					(mid 78.132962 -210.055438)
					(end 78.2066 -210.08594)
				)
				(arc
					(start 78.5622 -210.08594)
					(mid 78.635838 -210.055438)
					(end 78.66634 -209.9818)
				)
			)
		)
		(polygon
			(pts
				(arc
					(start 77.62494 -209.6262)
					(mid 77.594438 -209.552562)
					(end 77.5208 -209.52206)
				)
				(arc
					(start 77.1652 -209.52206)
					(mid 77.091562 -209.552562)
					(end 77.06106 -209.6262)
				)
				(arc
					(start 77.06106 -209.9818)
					(mid 77.091562 -210.055438)
					(end 77.1652 -210.08594)
				)
				(arc
					(start 77.5208 -210.08594)
					(mid 77.594438 -210.055438)
					(end 77.62494 -209.9818)
				)
			)
		)
		(polygon
			(pts
				(xy 98.98761 -209.222594) (xy 97.81921 -209.222594) (xy 97.81921 -210.416648) (xy 98.98761 -210.416648)
			)
		)
		(polygon
			(pts
				(arc
					(start 5.59054 -209.535268)
					(mid 5.079873 -209.024982)
					(end 4.56946 -209.535522)
				)
				(arc
					(start 4.56946 -210.348322)
					(mid 5.08 -210.858862)
					(end 5.59054 -210.348322)
				)
			)
		)
		(polygon
			(pts
				(arc
					(start 103.3272 -208.1022)
					(mid 103.297442 -208.030358)
					(end 103.2256 -208.0006)
				)
				(arc
					(start 102.0064 -208.0006)
					(mid 101.934558 -208.030358)
					(end 101.9048 -208.1022)
				)
				(arc
					(start 101.9048 -209.4738)
					(mid 101.934558 -209.545642)
					(end 102.0064 -209.5754)
				)
				(arc
					(start 103.2256 -209.5754)
					(mid 103.297442 -209.545642)
					(end 103.3272 -209.4738)
				)
			)
		)
		(polygon
			(pts
				(xy 3.494532 -207.68818) (xy 1.005332 -207.68818) (xy 1.005332 -208.996026) (xy 3.494532 -208.996026)
			)
		)
		(polygon
			(pts
				(arc
					(start 7.502906 -207.935576)
					(mid 6.992239 -207.42529)
					(end 6.481826 -207.93583)
				)
				(arc
					(start 6.481826 -208.74863)
					(mid 6.992366 -209.25917)
					(end 7.502906 -208.74863)
				)
			)
		)
		(polygon
			(pts
				(xy 98.98761 -207.223106) (xy 97.81921 -207.223106) (xy 97.81921 -208.416398) (xy 98.98761 -208.416398)
			)
		)
		(polygon
			(pts
				(arc
					(start 5.59054 -206.335122)
					(mid 5.079873 -205.824836)
					(end 4.56946 -206.335376)
				)
				(arc
					(start 4.56946 -207.148176)
					(mid 5.08 -207.658716)
					(end 5.59054 -207.148176)
				)
			)
		)
		(polygon
			(pts
				(xy 97.577148 -205.81239) (xy 96.383348 -205.81239) (xy 96.383348 -206.98079) (xy 97.577148 -206.98079)
			)
		)
		(polygon
			(pts
				(xy 95.577406 -205.81239) (xy 94.382844 -205.81239) (xy 94.382844 -206.98079) (xy 95.577406 -206.98079)
			)
		)
		(polygon
			(pts
				(xy 3.494532 -204.488034) (xy 1.005332 -204.488034) (xy 1.005332 -205.796134) (xy 3.494532 -205.796134)
			)
		)
		(polygon
			(pts
				(arc
					(start 7.502906 -204.735684)
					(mid 6.992239 -204.225398)
					(end 6.481826 -204.735938)
				)
				(arc
					(start 6.481826 -205.548738)
					(mid 6.992366 -206.059278)
					(end 7.502906 -205.548738)
				)
			)
		)
		(polygon
			(pts
				(arc
					(start 103.3272 -204.2922)
					(mid 103.297442 -204.220358)
					(end 103.2256 -204.1906)
				)
				(arc
					(start 102.0064 -204.1906)
					(mid 101.934558 -204.220358)
					(end 101.9048 -204.2922)
				)
				(arc
					(start 101.9048 -205.6638)
					(mid 101.934558 -205.735642)
					(end 102.0064 -205.7654)
				)
				(arc
					(start 103.2256 -205.7654)
					(mid 103.297442 -205.735642)
					(end 103.3272 -205.6638)
				)
			)
		)
		(polygon
			(pts
				(arc
					(start 5.59054 -203.13523)
					(mid 5.079873 -202.624944)
					(end 4.56946 -203.135484)
				)
				(arc
					(start 4.56946 -203.948284)
					(mid 5.08 -204.458824)
					(end 5.59054 -203.948284)
				)
			)
		)
		(polygon
			(pts
				(arc
					(start 98.9584 -201.5744)
					(mid 98.928642 -201.502558)
					(end 98.8568 -201.4728)
				)
				(arc
					(start 97.4852 -201.4728)
					(mid 97.413358 -201.502558)
					(end 97.3836 -201.5744)
				)
				(arc
					(start 97.3836 -202.7936)
					(mid 97.413358 -202.865442)
					(end 97.4852 -202.8952)
				)
				(arc
					(start 98.8568 -202.8952)
					(mid 98.928642 -202.865442)
					(end 98.9584 -202.7936)
				)
			)
		)
		(polygon
			(pts
				(arc
					(start 95.1484 -201.5744)
					(mid 95.118642 -201.502558)
					(end 95.0468 -201.4728)
				)
				(arc
					(start 93.6752 -201.4728)
					(mid 93.603358 -201.502558)
					(end 93.5736 -201.5744)
				)
				(arc
					(start 93.5736 -202.7936)
					(mid 93.603358 -202.865442)
					(end 93.6752 -202.8952)
				)
				(arc
					(start 95.0468 -202.8952)
					(mid 95.118642 -202.865442)
					(end 95.1484 -202.7936)
				)
			)
		)
		(polygon
			(pts
				(xy 3.494532 -201.288142) (xy 1.005332 -201.288142) (xy 1.005332 -202.595988) (xy 3.494532 -202.595988)
			)
		)
		(polygon
			(pts
				(arc
					(start 7.502906 -201.535538)
					(mid 6.992239 -201.025252)
					(end 6.481826 -201.535792)
				)
				(arc
					(start 6.481826 -202.348592)
					(mid 6.992366 -202.859132)
					(end 7.502906 -202.348592)
				)
			)
		)
		(polygon
			(pts
				(arc
					(start 5.59054 -199.935084)
					(mid 5.079873 -199.424798)
					(end 4.56946 -199.935338)
				)
				(arc
					(start 4.56946 -200.748138)
					(mid 5.08 -201.258678)
					(end 5.59054 -200.748138)
				)
			)
		)
		(polygon
			(pts
				(xy 3.494532 -195.688204) (xy 1.005332 -195.688204) (xy 1.005332 -196.99605) (xy 3.494532 -196.99605)
			)
		)
		(polygon
			(pts
				(arc
					(start 7.502906 -195.9356)
					(mid 6.992239 -195.425314)
					(end 6.481826 -195.935854)
				)
				(arc
					(start 6.481826 -196.748654)
					(mid 6.992366 -197.259194)
					(end 7.502906 -196.748654)
				)
			)
		)
		(polygon
			(pts
				(arc
					(start 5.59054 -194.335146)
					(mid 5.079873 -193.82486)
					(end 4.56946 -194.3354)
				)
				(arc
					(start 4.56946 -195.1482)
					(mid 5.08 -195.65874)
					(end 5.59054 -195.1482)
				)
			)
		)
		(polygon
			(pts
				(xy 3.494532 -192.488058) (xy 1.005332 -192.488058) (xy 1.005332 -193.796158) (xy 3.494532 -193.796158)
			)
		)
		(polygon
			(pts
				(arc
					(start 7.502906 -192.735708)
					(mid 6.992239 -192.225422)
					(end 6.481826 -192.735962)
				)
				(arc
					(start 6.481826 -193.548762)
					(mid 6.992366 -194.059302)
					(end 7.502906 -193.548762)
				)
			)
		)
		(polygon
			(pts
				(arc
					(start 5.59054 -191.135254)
					(mid 5.079873 -190.624968)
					(end 4.56946 -191.135508)
				)
				(arc
					(start 4.56946 -191.948308)
					(mid 5.08 -192.458848)
					(end 5.59054 -191.948308)
				)
			)
		)
		(polygon
			(pts
				(xy 3.494532 -184.488074) (xy 1.005332 -184.488074) (xy 1.005332 -185.796174) (xy 3.494532 -185.796174)
			)
		)
		(polygon
			(pts
				(arc
					(start 7.502906 -184.735724)
					(mid 6.992239 -184.225438)
					(end 6.481826 -184.735978)
				)
				(arc
					(start 6.481826 -185.548778)
					(mid 6.992366 -186.059318)
					(end 7.502906 -185.548778)
				)
			)
		)
		(polygon
			(pts
				(arc
					(start 5.59054 -183.13527)
					(mid 5.079873 -182.624984)
					(end 4.56946 -183.135524)
				)
				(arc
					(start 4.56946 -183.948324)
					(mid 5.08 -184.458864)
					(end 5.59054 -183.948324)
				)
			)
		)
		(polygon
			(pts
				(xy 225.203004 -181.843934) (xy 223.196658 -181.843934) (xy 223.196658 -183.73598) (xy 225.203258 -183.73598)
				(xy 225.203258 -181.844188)
			)
		)
		(polygon
			(pts
				(xy 40.20312 -181.843934) (xy 38.196774 -181.843934) (xy 38.196774 -183.73598) (xy 40.203374 -183.73598)
				(xy 40.203374 -181.844188)
			)
		)
		(polygon
			(pts
				(arc
					(start 222.339154 -182.23103)
					(mid 221.726887 -181.619144)
					(end 221.114874 -182.231284)
				)
				(arc
					(start 221.114874 -183.348884)
					(mid 221.727014 -183.961024)
					(end 222.339154 -183.348884)
				)
			)
		)
		(polygon
			(pts
				(arc
					(start 37.33927 -182.23103)
					(mid 36.727003 -181.619144)
					(end 36.11499 -182.231284)
				)
				(arc
					(start 36.11499 -183.348884)
					(mid 36.72713 -183.961024)
					(end 37.33927 -183.348884)
				)
			)
		)
		(polygon
			(pts
				(xy 3.494532 -181.288182) (xy 1.005332 -181.288182) (xy 1.005332 -182.596028) (xy 3.494532 -182.596028)
			)
		)
		(polygon
			(pts
				(arc
					(start 7.502906 -181.535578)
					(mid 6.992239 -181.025292)
					(end 6.481826 -181.535832)
				)
				(arc
					(start 6.481826 -182.348632)
					(mid 6.992366 -182.859172)
					(end 7.502906 -182.348632)
				)
			)
		)
		(polygon
			(pts
				(arc
					(start 220.840554 -179.983384)
					(mid 220.329887 -179.473098)
					(end 219.819474 -179.983638)
				)
				(arc
					(start 219.819474 -180.796438)
					(mid 220.330014 -181.306978)
					(end 220.840554 -180.796438)
				)
			)
		)
		(polygon
			(pts
				(arc
					(start 35.84067 -179.983384)
					(mid 35.330003 -179.473098)
					(end 34.81959 -179.983638)
				)
				(arc
					(start 34.81959 -180.796438)
					(mid 35.33013 -181.306978)
					(end 35.84067 -180.796438)
				)
			)
		)
		(polygon
			(pts
				(xy 225.203004 -179.443888) (xy 223.196658 -179.443888) (xy 223.196658 -181.336188) (xy 225.203258 -181.336188)
				(xy 225.203258 -179.444142)
			)
		)
		(polygon
			(pts
				(xy 40.20312 -179.443888) (xy 38.196774 -179.443888) (xy 38.196774 -181.336188) (xy 40.203374 -181.336188)
				(xy 40.203374 -179.444142)
			)
		)
		(polygon
			(pts
				(arc
					(start 5.59054 -179.935124)
					(mid 5.079873 -179.424838)
					(end 4.56946 -179.935378)
				)
				(arc
					(start 4.56946 -180.748178)
					(mid 5.08 -181.258718)
					(end 5.59054 -180.748178)
				)
			)
		)
		(polygon
			(pts
				(xy 3.494532 -178.088036) (xy 1.005332 -178.088036) (xy 1.005332 -179.396136) (xy 3.494532 -179.396136)
			)
		)
		(polygon
			(pts
				(arc
					(start 7.502906 -178.386486)
					(mid 6.992239 -177.8762)
					(end 6.481826 -178.38674)
				)
				(arc
					(start 6.481826 -179.19954)
					(mid 6.992366 -179.71008)
					(end 7.502906 -179.19954)
				)
			)
		)
		(polygon
			(pts
				(xy 225.203004 -177.043842) (xy 223.196658 -177.043842) (xy 223.196658 -178.936142) (xy 225.203258 -178.936142)
				(xy 225.203258 -177.044096)
			)
		)
		(polygon
			(pts
				(xy 40.20312 -177.043842) (xy 38.196774 -177.043842) (xy 38.196774 -178.936142) (xy 40.203374 -178.936142)
				(xy 40.203374 -177.044096)
			)
		)
		(polygon
			(pts
				(arc
					(start 222.339154 -177.430938)
					(mid 221.726887 -176.819052)
					(end 221.114874 -177.431192)
				)
				(arc
					(start 221.114874 -178.548792)
					(mid 221.727014 -179.160932)
					(end 222.339154 -178.548792)
				)
			)
		)
		(polygon
			(pts
				(arc
					(start 37.33927 -177.430938)
					(mid 36.727003 -176.819052)
					(end 36.11499 -177.431192)
				)
				(arc
					(start 36.11499 -178.548792)
					(mid 36.72713 -179.160932)
					(end 37.33927 -178.548792)
				)
			)
		)
		(polygon
			(pts
				(arc
					(start 5.59054 -176.735232)
					(mid 5.079873 -176.224946)
					(end 4.56946 -176.735486)
				)
				(arc
					(start 4.56946 -177.548286)
					(mid 5.08 -178.058826)
					(end 5.59054 -177.548286)
				)
			)
		)
		(polygon
			(pts
				(xy 3.494532 -174.888144) (xy 1.005332 -174.888144) (xy 1.005332 -176.19599) (xy 3.494532 -176.19599)
			)
		)
		(polygon
			(pts
				(arc
					(start 7.502906 -175.18634)
					(mid 6.992239 -174.676054)
					(end 6.481826 -175.186594)
				)
				(arc
					(start 6.481826 -175.999394)
					(mid 6.992366 -176.509934)
					(end 7.502906 -175.999394)
				)
			)
		)
		(polygon
			(pts
				(arc
					(start 220.840554 -175.183292)
					(mid 220.329887 -174.673006)
					(end 219.819474 -175.183546)
				)
				(arc
					(start 219.819474 -175.996346)
					(mid 220.330014 -176.506886)
					(end 220.840554 -175.996346)
				)
			)
		)
		(polygon
			(pts
				(arc
					(start 35.84067 -175.183292)
					(mid 35.330003 -174.673006)
					(end 34.81959 -175.183546)
				)
				(arc
					(start 34.81959 -175.996346)
					(mid 35.33013 -176.506886)
					(end 35.84067 -175.996346)
				)
			)
		)
		(polygon
			(pts
				(xy 225.203004 -174.643796) (xy 223.196658 -174.643796) (xy 223.196658 -176.536096) (xy 225.203258 -176.536096)
				(xy 225.203258 -174.64405)
			)
		)
		(polygon
			(pts
				(xy 40.20312 -174.643796) (xy 38.196774 -174.643796) (xy 38.196774 -176.536096) (xy 40.203374 -176.536096)
				(xy 40.203374 -174.64405)
			)
		)
		(polygon
			(pts
				(arc
					(start 5.59054 -173.535086)
					(mid 5.079873 -173.0248)
					(end 4.56946 -173.53534)
				)
				(arc
					(start 4.56946 -174.34814)
					(mid 5.08 -174.85868)
					(end 5.59054 -174.34814)
				)
			)
		)
		(polygon
			(pts
				(xy 225.203004 -172.24375) (xy 223.196658 -172.24375) (xy 223.196658 -174.13605) (xy 225.203258 -174.13605)
				(xy 225.203258 -172.244004)
			)
		)
		(polygon
			(pts
				(xy 40.20312 -172.24375) (xy 38.196774 -172.24375) (xy 38.196774 -174.13605) (xy 40.203374 -174.13605)
				(xy 40.203374 -172.244004)
			)
		)
		(polygon
			(pts
				(arc
					(start 222.339154 -172.630846)
					(mid 221.726887 -172.01896)
					(end 221.114874 -172.6311)
				)
				(arc
					(start 221.114874 -173.7487)
					(mid 221.727014 -174.36084)
					(end 222.339154 -173.7487)
				)
			)
		)
		(polygon
			(pts
				(arc
					(start 37.33927 -172.630846)
					(mid 36.727003 -172.01896)
					(end 36.11499 -172.6311)
				)
				(arc
					(start 36.11499 -173.7487)
					(mid 36.72713 -174.36084)
					(end 37.33927 -173.7487)
				)
			)
		)
		(polygon
			(pts
				(xy 3.494532 -171.687998) (xy 1.005332 -171.687998) (xy 1.005332 -172.996098) (xy 3.494532 -172.996098)
			)
		)
		(polygon
			(pts
				(arc
					(start 7.502906 -171.986448)
					(mid 6.992239 -171.476162)
					(end 6.481826 -171.986702)
				)
				(arc
					(start 6.481826 -172.799502)
					(mid 6.992366 -173.310042)
					(end 7.502906 -172.799502)
				)
			)
		)
		(polygon
			(pts
				(arc
					(start 220.840554 -170.383454)
					(mid 220.329887 -169.873168)
					(end 219.819474 -170.383708)
				)
				(arc
					(start 219.819474 -171.196508)
					(mid 220.330014 -171.707048)
					(end 220.840554 -171.196508)
				)
			)
		)
		(polygon
			(pts
				(arc
					(start 35.84067 -170.383454)
					(mid 35.330003 -169.873168)
					(end 34.81959 -170.383708)
				)
				(arc
					(start 34.81959 -171.196508)
					(mid 35.33013 -171.707048)
					(end 35.84067 -171.196508)
				)
			)
		)
		(polygon
			(pts
				(xy 225.203004 -169.843958) (xy 223.196658 -169.843958) (xy 223.196658 -171.736004) (xy 225.203258 -171.736004)
				(xy 225.203258 -169.844212)
			)
		)
		(polygon
			(pts
				(xy 40.20312 -169.843958) (xy 38.196774 -169.843958) (xy 38.196774 -171.736004) (xy 40.203374 -171.736004)
				(xy 40.203374 -169.844212)
			)
		)
		(polygon
			(pts
				(arc
					(start 5.59054 -170.335194)
					(mid 5.079873 -169.824908)
					(end 4.56946 -170.335448)
				)
				(arc
					(start 4.56946 -171.148248)
					(mid 5.08 -171.658788)
					(end 5.59054 -171.148248)
				)
			)
		)
		(polygon
			(pts
				(xy 3.494532 -168.488106) (xy 1.005332 -168.488106) (xy 1.005332 -169.796206) (xy 3.494532 -169.796206)
			)
		)
		(polygon
			(pts
				(arc
					(start 7.502906 -168.786556)
					(mid 6.992239 -168.27627)
					(end 6.481826 -168.78681)
				)
				(arc
					(start 6.481826 -169.59961)
					(mid 6.992366 -170.11015)
					(end 7.502906 -169.59961)
				)
			)
		)
		(polygon
			(pts
				(arc
					(start 5.59054 -167.135048)
					(mid 5.079873 -166.624762)
					(end 4.56946 -167.135302)
				)
				(arc
					(start 4.56946 -167.948102)
					(mid 5.08 -168.458642)
					(end 5.59054 -167.948102)
				)
			)
		)
		(polygon
			(pts
				(arc
					(start 5.59054 -163.935156)
					(mid 5.079873 -163.42487)
					(end 4.56946 -163.93541)
				)
				(arc
					(start 4.56946 -164.74821)
					(mid 5.08 -165.25875)
					(end 5.59054 -164.74821)
				)
			)
		)
		(polygon
			(pts
				(arc
					(start 233.897424 -163.579302)
					(mid 233.386884 -163.068762)
					(end 232.876344 -163.579302)
				)
				(arc
					(start 232.876344 -164.392356)
					(mid 233.387011 -164.902642)
					(end 233.897424 -164.392102)
				)
			)
		)
		(polygon
			(pts
				(arc
					(start 48.89754 -163.579048)
					(mid 48.386873 -163.068762)
					(end 47.87646 -163.579302)
				)
				(arc
					(start 47.87646 -164.392102)
					(mid 48.387 -164.902642)
					(end 48.89754 -164.392102)
				)
			)
		)
		(polygon
			(pts
				(xy 228.39299 -163.04387) (xy 226.386644 -163.04387) (xy 226.386644 -164.93617) (xy 228.393244 -164.93617)
				(xy 228.393244 -163.044124)
			)
		)
		(polygon
			(pts
				(xy 43.393106 -163.04387) (xy 41.38676 -163.04387) (xy 41.38676 -164.93617) (xy 43.39336 -164.93617)
				(xy 43.39336 -163.044124)
			)
		)
		(polygon
			(pts
				(arc
					(start 230.720138 -163.300664)
					(mid 231.230424 -162.789997)
					(end 230.719884 -162.279584)
				)
				(arc
					(start 229.907084 -162.279584)
					(mid 229.396544 -162.790124)
					(end 229.907084 -163.300664)
				)
			)
		)
		(polygon
			(pts
				(arc
					(start 45.72 -163.300664)
					(mid 46.23054 -162.790124)
					(end 45.72 -162.279584)
				)
				(arc
					(start 44.906946 -162.279584)
					(mid 44.39666 -162.790251)
					(end 44.9072 -163.300664)
				)
			)
		)
		(polygon
			(pts
				(xy 3.494532 -162.088068) (xy 1.005332 -162.088068) (xy 1.005332 -163.396168) (xy 3.494532 -163.396168)
			)
		)
		(polygon
			(pts
				(arc
					(start 7.502906 -162.386518)
					(mid 6.992239 -161.876232)
					(end 6.481826 -162.386772)
				)
				(arc
					(start 6.481826 -163.199572)
					(mid 6.992366 -163.710112)
					(end 7.502906 -163.199572)
				)
			)
		)
		(polygon
			(pts
				(arc
					(start 5.59054 -160.735264)
					(mid 5.079873 -160.224978)
					(end 4.56946 -160.735518)
				)
				(arc
					(start 4.56946 -161.548318)
					(mid 5.08 -162.058858)
					(end 5.59054 -161.548318)
				)
			)
		)
		(polygon
			(pts
				(xy 225.203004 -159.443928) (xy 223.196658 -159.443928) (xy 223.196658 -161.335974) (xy 225.203258 -161.335974)
				(xy 225.203258 -159.444182)
			)
		)
		(polygon
			(pts
				(xy 40.20312 -159.443928) (xy 38.196774 -159.443928) (xy 38.196774 -161.335974) (xy 40.203374 -161.335974)
				(xy 40.203374 -159.444182)
			)
		)
		(polygon
			(pts
				(arc
					(start 222.339154 -159.831024)
					(mid 221.726887 -159.219138)
					(end 221.114874 -159.831278)
				)
				(arc
					(start 221.114874 -160.948878)
					(mid 221.727014 -161.561018)
					(end 222.339154 -160.948878)
				)
			)
		)
		(polygon
			(pts
				(arc
					(start 37.33927 -159.831024)
					(mid 36.727003 -159.219138)
					(end 36.11499 -159.831278)
				)
				(arc
					(start 36.11499 -160.948878)
					(mid 36.72713 -161.561018)
					(end 37.33927 -160.948878)
				)
			)
		)
		(polygon
			(pts
				(xy 3.494532 -158.888176) (xy 1.005332 -158.888176) (xy 1.005332 -160.196022) (xy 3.494532 -160.196022)
			)
		)
		(polygon
			(pts
				(arc
					(start 7.502906 -159.186372)
					(mid 6.992239 -158.676086)
					(end 6.481826 -159.186626)
				)
				(arc
					(start 6.481826 -159.999426)
					(mid 6.992366 -160.509966)
					(end 7.502906 -159.999426)
				)
			)
		)
		(polygon
			(pts
				(arc
					(start 220.840554 -157.583378)
					(mid 220.329887 -157.073092)
					(end 219.819474 -157.583632)
				)
				(arc
					(start 219.819474 -158.396432)
					(mid 220.330014 -158.906972)
					(end 220.840554 -158.396432)
				)
			)
		)
		(polygon
			(pts
				(arc
					(start 35.84067 -157.583378)
					(mid 35.330003 -157.073092)
					(end 34.81959 -157.583632)
				)
				(arc
					(start 34.81959 -158.396432)
					(mid 35.33013 -158.906972)
					(end 35.84067 -158.396432)
				)
			)
		)
		(polygon
			(pts
				(xy 225.203004 -157.043882) (xy 223.196658 -157.043882) (xy 223.196658 -158.936182) (xy 225.203258 -158.936182)
				(xy 225.203258 -157.044136)
			)
		)
		(polygon
			(pts
				(xy 40.20312 -157.043882) (xy 38.196774 -157.043882) (xy 38.196774 -158.936182) (xy 40.203374 -158.936182)
				(xy 40.203374 -157.044136)
			)
		)
		(polygon
			(pts
				(arc
					(start 5.59054 -157.535118)
					(mid 5.079873 -157.024832)
					(end 4.56946 -157.535372)
				)
				(arc
					(start 4.56946 -158.348172)
					(mid 5.08 -158.858712)
					(end 5.59054 -158.348172)
				)
			)
		)
		(polygon
			(pts
				(xy 3.494532 -155.68803) (xy 1.005332 -155.68803) (xy 1.005332 -156.99613) (xy 3.494532 -156.99613)
			)
		)
		(polygon
			(pts
				(arc
					(start 7.502906 -155.97378)
					(mid 6.992239 -155.463494)
					(end 6.481826 -155.974034)
				)
				(arc
					(start 6.481826 -156.786834)
					(mid 6.992366 -157.297374)
					(end 7.502906 -156.786834)
				)
			)
		)
		(polygon
			(pts
				(xy 225.203004 -154.643836) (xy 223.196658 -154.643836) (xy 223.196658 -156.536136) (xy 225.203258 -156.536136)
				(xy 225.203258 -154.64409)
			)
		)
		(polygon
			(pts
				(xy 40.20312 -154.643836) (xy 38.196774 -154.643836) (xy 38.196774 -156.536136) (xy 40.203374 -156.536136)
				(xy 40.203374 -154.64409)
			)
		)
		(polygon
			(pts
				(arc
					(start 5.59054 -154.335226)
					(mid 5.079873 -153.82494)
					(end 4.56946 -154.33548)
				)
				(arc
					(start 4.56946 -155.14828)
					(mid 5.08 -155.65882)
					(end 5.59054 -155.14828)
				)
			)
		)
		(polygon
			(pts
				(xy 3.494532 -152.488138) (xy 1.005332 -152.488138) (xy 1.005332 -153.795984) (xy 3.494532 -153.795984)
			)
		)
		(polygon
			(pts
				(arc
					(start 7.502906 -152.786334)
					(mid 6.992239 -152.276048)
					(end 6.481826 -152.786588)
				)
				(arc
					(start 6.481826 -153.599388)
					(mid 6.992366 -154.109928)
					(end 7.502906 -153.599388)
				)
			)
		)
		(polygon
			(pts
				(xy 23.803356 -143.463772) (xy 21.796756 -143.463772) (xy 21.796756 -145.355818) (xy 21.79701 -145.356072)
				(xy 23.803356 -145.356072)
			)
		)
		(polygon
			(pts
				(arc
					(start 27.18054 -141.603476)
					(mid 26.67 -141.092936)
					(end 26.15946 -141.603476)
				)
				(arc
					(start 26.15946 -142.41653)
					(mid 26.670127 -142.926816)
					(end 27.18054 -142.416276)
				)
			)
		)
		(polygon
			(pts
				(xy 23.803356 -141.063726) (xy 21.796756 -141.063726) (xy 21.796756 -142.955772) (xy 21.79701 -142.956026)
				(xy 23.803356 -142.956026)
			)
		)
		(polygon
			(pts
				(xy 23.803356 -138.66368) (xy 21.796756 -138.66368) (xy 21.796756 -140.555726) (xy 21.79701 -140.55598)
				(xy 23.803356 -140.55598)
			)
		)
		(polygon
			(pts
				(arc
					(start 25.88514 -139.050776)
					(mid 25.272873 -138.43889)
					(end 24.66086 -139.05103)
				)
				(arc
					(start 24.66086 -140.16863)
					(mid 25.273 -140.78077)
					(end 25.88514 -140.16863)
				)
			)
		)
		(polygon
			(pts
				(arc
					(start 32.00654 -135.603488)
					(mid 31.495873 -135.093202)
					(end 30.98546 -135.603742)
				)
				(arc
					(start 30.98546 -136.416542)
					(mid 31.496 -136.927082)
					(end 32.00654 -136.416542)
				)
			)
		)
		(polygon
			(pts
				(arc
					(start 17.78254 -135.603234)
					(mid 17.272 -135.092694)
					(end 16.76146 -135.603234)
				)
				(arc
					(start 16.76146 -136.416288)
					(mid 17.272127 -136.926574)
					(end 17.78254 -136.416034)
				)
			)
		)
		(polygon
			(pts
				(xy 20.61337 -135.063738) (xy 18.60677 -135.063738) (xy 18.60677 -136.955784) (xy 18.607024 -136.956038)
				(xy 20.61337 -136.956038)
			)
		)
		(polygon
			(pts
				(arc
					(start 27.18054 -128.8034)
					(mid 26.67 -128.29286)
					(end 26.15946 -128.8034)
				)
				(arc
					(start 26.15946 -129.616454)
					(mid 26.670127 -130.12674)
					(end 27.18054 -129.6162)
				)
			)
		)
		(polygon
			(pts
				(xy 23.803356 -128.263904) (xy 21.796756 -128.263904) (xy 21.796756 -130.155696) (xy 21.79701 -130.15595)
				(xy 23.803356 -130.15595)
			)
		)
		(polygon
			(pts
				(xy 23.803356 -125.863858) (xy 21.796756 -125.863858) (xy 21.796756 -127.755904) (xy 21.79701 -127.756158)
				(xy 23.803356 -127.756158)
			)
		)
		(polygon
			(pts
				(arc
					(start 25.88514 -126.251208)
					(mid 25.273 -125.639068)
					(end 24.66086 -126.251208)
				)
				(arc
					(start 24.66086 -127.369062)
					(mid 25.273127 -127.980948)
					(end 25.88514 -127.368808)
				)
			)
		)
		(polygon
			(pts
				(arc
					(start 27.18054 -124.003562)
					(mid 26.67 -123.493022)
					(end 26.15946 -124.003562)
				)
				(arc
					(start 26.15946 -124.816616)
					(mid 26.670127 -125.326902)
					(end 27.18054 -124.816362)
				)
			)
		)
		(polygon
			(pts
				(xy 23.803356 -123.463812) (xy 21.796756 -123.463812) (xy 21.796756 -125.355858) (xy 21.79701 -125.356112)
				(xy 23.803356 -125.356112)
			)
		)
		(polygon
			(pts
				(xy 23.803356 -121.063766) (xy 21.796756 -121.063766) (xy 21.796756 -122.955812) (xy 21.79701 -122.956066)
				(xy 23.803356 -122.956066)
			)
		)
		(polygon
			(pts
				(arc
					(start 25.88514 -121.451116)
					(mid 25.273 -120.838976)
					(end 24.66086 -121.451116)
				)
				(arc
					(start 24.66086 -122.56897)
					(mid 25.273127 -123.180856)
					(end 25.88514 -122.568716)
				)
			)
		)
		(polygon
			(pts
				(arc
					(start 27.18054 -119.20347)
					(mid 26.67 -118.69293)
					(end 26.15946 -119.20347)
				)
				(arc
					(start 26.15946 -120.016524)
					(mid 26.670127 -120.52681)
					(end 27.18054 -120.01627)
				)
			)
		)
		(polygon
			(pts
				(xy 23.803356 -118.66372) (xy 21.796756 -118.66372) (xy 21.796756 -120.555766) (xy 21.79701 -120.55602)
				(xy 23.803356 -120.55602)
			)
		)
		(polygon
			(pts
				(xy 23.803356 -116.263928) (xy 21.796756 -116.263928) (xy 21.796756 -118.15572) (xy 21.79701 -118.155974)
				(xy 23.803356 -118.155974)
			)
		)
		(polygon
			(pts
				(arc
					(start 25.88514 -116.65077)
					(mid 25.272873 -116.038884)
					(end 24.66086 -116.651024)
				)
				(arc
					(start 24.66086 -117.768624)
					(mid 25.273 -118.380764)
					(end 25.88514 -117.768624)
				)
			)
		)
		(polygon
			(pts
				(arc
					(start 100.6094 -109.6264)
					(mid 100.579642 -109.554558)
					(end 100.5078 -109.5248)
				)
				(arc
					(start 99.1362 -109.5248)
					(mid 99.064358 -109.554558)
					(end 99.0346 -109.6264)
				)
				(arc
					(start 99.0346 -110.8456)
					(mid 99.064358 -110.917442)
					(end 99.1362 -110.9472)
				)
				(arc
					(start 100.5078 -110.9472)
					(mid 100.579642 -110.917442)
					(end 100.6094 -110.8456)
				)
			)
		)
		(polygon
			(pts
				(arc
					(start 96.7994 -109.6264)
					(mid 96.769642 -109.554558)
					(end 96.6978 -109.5248)
				)
				(arc
					(start 95.3262 -109.5248)
					(mid 95.254358 -109.554558)
					(end 95.2246 -109.6264)
				)
				(arc
					(start 95.2246 -110.8456)
					(mid 95.254358 -110.917442)
					(end 95.3262 -110.9472)
				)
				(arc
					(start 96.6978 -110.9472)
					(mid 96.769642 -110.917442)
					(end 96.7994 -110.8456)
				)
			)
		)
		(polygon
			(pts
				(arc
					(start 91.5924 -109.6264)
					(mid 91.562642 -109.554558)
					(end 91.4908 -109.5248)
				)
				(arc
					(start 90.1192 -109.5248)
					(mid 90.047358 -109.554558)
					(end 90.0176 -109.6264)
				)
				(arc
					(start 90.0176 -110.8456)
					(mid 90.047358 -110.917442)
					(end 90.1192 -110.9472)
				)
				(arc
					(start 91.4908 -110.9472)
					(mid 91.562642 -110.917442)
					(end 91.5924 -110.8456)
				)
			)
		)
		(polygon
			(pts
				(arc
					(start 87.7824 -109.6264)
					(mid 87.752642 -109.554558)
					(end 87.6808 -109.5248)
				)
				(arc
					(start 86.3092 -109.5248)
					(mid 86.237358 -109.554558)
					(end 86.2076 -109.6264)
				)
				(arc
					(start 86.2076 -110.8456)
					(mid 86.237358 -110.917442)
					(end 86.3092 -110.9472)
				)
				(arc
					(start 87.6808 -110.9472)
					(mid 87.752642 -110.917442)
					(end 87.7824 -110.8456)
				)
			)
		)
		(polygon
			(pts
				(xy 97.577148 -105.43921) (xy 96.383348 -105.43921) (xy 96.383348 -106.60761) (xy 97.577148 -106.60761)
			)
		)
		(polygon
			(pts
				(xy 95.577152 -105.43921) (xy 94.383098 -105.43921) (xy 94.383098 -106.60761) (xy 95.577152 -106.60761)
			)
		)
		(polygon
			(pts
				(xy 93.074998 -105.43921) (xy 91.883484 -105.43921) (xy 91.883484 -106.60761) (xy 93.074998 -106.60761)
			)
		)
		(polygon
			(pts
				(xy 91.077288 -105.43921) (xy 89.88679 -105.43921) (xy 89.88679 -106.60761) (xy 91.077288 -106.60761)
			)
		)
		(polygon
			(pts
				(arc
					(start 78.84414 -101.5746)
					(mid 78.813638 -101.500962)
					(end 78.74 -101.47046)
				)
				(arc
					(start 78.3844 -101.47046)
					(mid 78.310762 -101.500962)
					(end 78.28026 -101.5746)
				)
				(arc
					(start 78.28026 -101.9302)
					(mid 78.310762 -102.003838)
					(end 78.3844 -102.03434)
				)
				(arc
					(start 78.74 -102.03434)
					(mid 78.813638 -102.003838)
					(end 78.84414 -101.9302)
				)
			)
		)
		(polygon
			(pts
				(arc
					(start 77.77734 -101.5746)
					(mid 77.746838 -101.500962)
					(end 77.6732 -101.47046)
				)
				(arc
					(start 77.3176 -101.47046)
					(mid 77.243962 -101.500962)
					(end 77.21346 -101.5746)
				)
				(arc
					(start 77.21346 -101.9302)
					(mid 77.243962 -102.003838)
					(end 77.3176 -102.03434)
				)
				(arc
					(start 77.6732 -102.03434)
					(mid 77.746838 -102.003838)
					(end 77.77734 -101.9302)
				)
			)
		)
		(polygon
			(pts
				(arc
					(start 85.95614 -101.3968)
					(mid 85.940517 -101.359083)
					(end 85.9028 -101.34346)
				)
				(arc
					(start 85.6996 -101.34346)
					(mid 85.661883 -101.359083)
					(end 85.64626 -101.3968)
				)
				(arc
					(start 85.64626 -101.6508)
					(mid 85.661883 -101.688517)
					(end 85.6996 -101.70414)
				)
				(arc
					(start 85.9028 -101.70414)
					(mid 85.940517 -101.688517)
					(end 85.95614 -101.6508)
				)
			)
		)
		(polygon
			(pts
				(arc
					(start 85.95614 -100.838)
					(mid 85.940517 -100.800283)
					(end 85.9028 -100.78466)
				)
				(arc
					(start 85.6996 -100.78466)
					(mid 85.661883 -100.800283)
					(end 85.64626 -100.838)
				)
				(arc
					(start 85.64626 -101.092)
					(mid 85.661883 -101.129717)
					(end 85.6996 -101.14534)
				)
				(arc
					(start 85.9028 -101.14534)
					(mid 85.940517 -101.129717)
					(end 85.95614 -101.092)
				)
			)
		)
		(polygon
			(pts
				(xy 90.14079 -100.504244) (xy 88.97239 -100.504244) (xy 88.97239 -101.696012) (xy 90.14079 -101.696012)
			)
		)
		(polygon
			(pts
				(arc
					(start 78.84414 -100.5332)
					(mid 78.813638 -100.459562)
					(end 78.74 -100.42906)
				)
				(arc
					(start 78.3844 -100.42906)
					(mid 78.310762 -100.459562)
					(end 78.28026 -100.5332)
				)
				(arc
					(start 78.28026 -100.8888)
					(mid 78.310762 -100.962438)
					(end 78.3844 -100.99294)
				)
				(arc
					(start 78.74 -100.99294)
					(mid 78.813638 -100.962438)
					(end 78.84414 -100.8888)
				)
			)
		)
		(polygon
			(pts
				(arc
					(start 77.77734 -100.5332)
					(mid 77.746838 -100.459562)
					(end 77.6732 -100.42906)
				)
				(arc
					(start 77.3176 -100.42906)
					(mid 77.243962 -100.459562)
					(end 77.21346 -100.5332)
				)
				(arc
					(start 77.21346 -100.8888)
					(mid 77.243962 -100.962438)
					(end 77.3176 -100.99294)
				)
				(arc
					(start 77.6732 -100.99294)
					(mid 77.746838 -100.962438)
					(end 77.77734 -100.8888)
				)
			)
		)
		(polygon
			(pts
				(xy 97.577148 -96.59239) (xy 96.383856 -96.59239) (xy 96.383856 -97.76079) (xy 97.577148 -97.76079)
			)
		)
		(polygon
			(pts
				(xy 95.577152 -96.59239) (xy 94.383098 -96.59239) (xy 94.383098 -97.76079) (xy 95.577152 -97.76079)
			)
		)
		(polygon
			(pts
				(xy 93.075252 -96.59239) (xy 91.882722 -96.59239) (xy 91.882722 -97.76079) (xy 93.075252 -97.76079)
			)
		)
		(polygon
			(pts
				(xy 91.07678 -96.59239) (xy 89.88806 -96.59239) (xy 89.88806 -97.76079) (xy 91.07678 -97.76079)
			)
		)
		(polygon
			(pts
				(arc
					(start 100.6094 -92.3544)
					(mid 100.579642 -92.282558)
					(end 100.5078 -92.2528)
				)
				(arc
					(start 99.1362 -92.2528)
					(mid 99.064358 -92.282558)
					(end 99.0346 -92.3544)
				)
				(arc
					(start 99.0346 -93.5736)
					(mid 99.064358 -93.645442)
					(end 99.1362 -93.6752)
				)
				(arc
					(start 100.5078 -93.6752)
					(mid 100.579642 -93.645442)
					(end 100.6094 -93.5736)
				)
			)
		)
		(polygon
			(pts
				(arc
					(start 96.7994 -92.3544)
					(mid 96.769642 -92.282558)
					(end 96.6978 -92.2528)
				)
				(arc
					(start 95.3262 -92.2528)
					(mid 95.254358 -92.282558)
					(end 95.2246 -92.3544)
				)
				(arc
					(start 95.2246 -93.5736)
					(mid 95.254358 -93.645442)
					(end 95.3262 -93.6752)
				)
				(arc
					(start 96.6978 -93.6752)
					(mid 96.769642 -93.645442)
					(end 96.7994 -93.5736)
				)
			)
		)
		(polygon
			(pts
				(arc
					(start 91.5924 -92.3544)
					(mid 91.562642 -92.282558)
					(end 91.4908 -92.2528)
				)
				(arc
					(start 90.1192 -92.2528)
					(mid 90.047358 -92.282558)
					(end 90.0176 -92.3544)
				)
				(arc
					(start 90.0176 -93.5736)
					(mid 90.047358 -93.645442)
					(end 90.1192 -93.6752)
				)
				(arc
					(start 91.4908 -93.6752)
					(mid 91.562642 -93.645442)
					(end 91.5924 -93.5736)
				)
			)
		)
		(polygon
			(pts
				(arc
					(start 87.7824 -92.3544)
					(mid 87.752642 -92.282558)
					(end 87.6808 -92.2528)
				)
				(arc
					(start 86.3092 -92.2528)
					(mid 86.237358 -92.282558)
					(end 86.2076 -92.3544)
				)
				(arc
					(start 86.2076 -93.5736)
					(mid 86.237358 -93.645442)
					(end 86.3092 -93.6752)
				)
				(arc
					(start 87.6808 -93.6752)
					(mid 87.752642 -93.645442)
					(end 87.7824 -93.5736)
				)
			)
		)
		(polygon
			(pts
				(xy 225.203004 -78.843886) (xy 223.196658 -78.843886) (xy 223.196658 -80.735932) (xy 225.203258 -80.735932)
				(xy 225.203258 -78.84414)
			)
		)
		(polygon
			(pts
				(xy 40.20312 -78.843886) (xy 38.196774 -78.843886) (xy 38.196774 -80.735932) (xy 40.203374 -80.735932)
				(xy 40.203374 -78.84414)
			)
		)
		(polygon
			(pts
				(arc
					(start 222.339154 -79.230982)
					(mid 221.726887 -78.619096)
					(end 221.114874 -79.231236)
				)
				(arc
					(start 221.114874 -80.348836)
					(mid 221.727014 -80.960976)
					(end 222.339154 -80.348836)
				)
			)
		)
		(polygon
			(pts
				(arc
					(start 37.33927 -79.230982)
					(mid 36.727003 -78.619096)
					(end 36.11499 -79.231236)
				)
				(arc
					(start 36.11499 -80.348836)
					(mid 36.72713 -80.960976)
					(end 37.33927 -80.348836)
				)
			)
		)
		(polygon
			(pts
				(arc
					(start 220.840554 -76.983336)
					(mid 220.329887 -76.47305)
					(end 219.819474 -76.98359)
				)
				(arc
					(start 219.819474 -77.79639)
					(mid 220.330014 -78.30693)
					(end 220.840554 -77.79639)
				)
			)
		)
		(polygon
			(pts
				(arc
					(start 35.84067 -76.983336)
					(mid 35.330003 -76.47305)
					(end 34.81959 -76.98359)
				)
				(arc
					(start 34.81959 -77.79639)
					(mid 35.33013 -78.30693)
					(end 35.84067 -77.79639)
				)
			)
		)
		(polygon
			(pts
				(xy 225.203004 -76.44384) (xy 223.196658 -76.44384) (xy 223.196658 -78.33614) (xy 225.203258 -78.33614)
				(xy 225.203258 -76.444094)
			)
		)
		(polygon
			(pts
				(xy 40.20312 -76.44384) (xy 38.196774 -76.44384) (xy 38.196774 -78.33614) (xy 40.203374 -78.33614)
				(xy 40.203374 -76.444094)
			)
		)
		(polygon
			(pts
				(xy 225.203004 -74.043794) (xy 223.196658 -74.043794) (xy 223.196658 -75.936094) (xy 225.203258 -75.936094)
				(xy 225.203258 -74.044048)
			)
		)
		(polygon
			(pts
				(xy 40.20312 -74.043794) (xy 38.196774 -74.043794) (xy 38.196774 -75.936094) (xy 40.203374 -75.936094)
				(xy 40.203374 -74.044048)
			)
		)
		(polygon
			(pts
				(arc
					(start 222.339154 -74.43089)
					(mid 221.726887 -73.819004)
					(end 221.114874 -74.431144)
				)
				(arc
					(start 221.114874 -75.548744)
					(mid 221.727014 -76.160884)
					(end 222.339154 -75.548744)
				)
			)
		)
		(polygon
			(pts
				(arc
					(start 37.33927 -74.43089)
					(mid 36.727003 -73.819004)
					(end 36.11499 -74.431144)
				)
				(arc
					(start 36.11499 -75.548744)
					(mid 36.72713 -76.160884)
					(end 37.33927 -75.548744)
				)
			)
		)
		(polygon
			(pts
				(arc
					(start 220.840554 -72.183244)
					(mid 220.329887 -71.672958)
					(end 219.819474 -72.183498)
				)
				(arc
					(start 219.819474 -72.996298)
					(mid 220.330014 -73.506838)
					(end 220.840554 -72.996298)
				)
			)
		)
		(polygon
			(pts
				(arc
					(start 35.84067 -72.183244)
					(mid 35.330003 -71.672958)
					(end 34.81959 -72.183498)
				)
				(arc
					(start 34.81959 -72.996298)
					(mid 35.33013 -73.506838)
					(end 35.84067 -72.996298)
				)
			)
		)
		(polygon
			(pts
				(xy 225.203004 -71.643748) (xy 223.196658 -71.643748) (xy 223.196658 -73.536048) (xy 225.203258 -73.536048)
				(xy 225.203258 -71.644002)
			)
		)
		(polygon
			(pts
				(xy 40.20312 -71.643748) (xy 38.196774 -71.643748) (xy 38.196774 -73.536048) (xy 40.203374 -73.536048)
				(xy 40.203374 -71.644002)
			)
		)
		(polygon
			(pts
				(xy 225.203004 -69.243702) (xy 223.196658 -69.243702) (xy 223.196658 -71.136002) (xy 225.203258 -71.136002)
				(xy 225.203258 -69.243956)
			)
		)
		(polygon
			(pts
				(xy 40.20312 -69.243702) (xy 38.196774 -69.243702) (xy 38.196774 -71.136002) (xy 40.203374 -71.136002)
				(xy 40.203374 -69.243956)
			)
		)
		(polygon
			(pts
				(arc
					(start 222.339154 -69.630798)
					(mid 221.726887 -69.018912)
					(end 221.114874 -69.631052)
				)
				(arc
					(start 221.114874 -70.748652)
					(mid 221.727014 -71.360792)
					(end 222.339154 -70.748652)
				)
			)
		)
		(polygon
			(pts
				(arc
					(start 37.33927 -69.630798)
					(mid 36.727003 -69.018912)
					(end 36.11499 -69.631052)
				)
				(arc
					(start 36.11499 -70.748652)
					(mid 36.72713 -71.360792)
					(end 37.33927 -70.748652)
				)
			)
		)
		(polygon
			(pts
				(arc
					(start 220.840554 -67.383406)
					(mid 220.329887 -66.87312)
					(end 219.819474 -67.38366)
				)
				(arc
					(start 219.819474 -68.19646)
					(mid 220.330014 -68.707)
					(end 220.840554 -68.19646)
				)
			)
		)
		(polygon
			(pts
				(arc
					(start 35.84067 -67.383406)
					(mid 35.330003 -66.87312)
					(end 34.81959 -67.38366)
				)
				(arc
					(start 34.81959 -68.19646)
					(mid 35.33013 -68.707)
					(end 35.84067 -68.19646)
				)
			)
		)
		(polygon
			(pts
				(xy 225.203004 -66.84391) (xy 223.196658 -66.84391) (xy 223.196658 -68.735956) (xy 225.203258 -68.735956)
				(xy 225.203258 -66.844164)
			)
		)
		(polygon
			(pts
				(xy 40.20312 -66.84391) (xy 38.196774 -66.84391) (xy 38.196774 -68.735956) (xy 40.203374 -68.735956)
				(xy 40.203374 -66.844164)
			)
		)
		(polygon
			(pts
				(arc
					(start 233.897424 -60.579254)
					(mid 233.386884 -60.068714)
					(end 232.876344 -60.579254)
				)
				(arc
					(start 232.876344 -61.392308)
					(mid 233.387011 -61.902594)
					(end 233.897424 -61.392054)
				)
			)
		)
		(polygon
			(pts
				(arc
					(start 48.89754 -60.579)
					(mid 48.386873 -60.068714)
					(end 47.87646 -60.579254)
				)
				(arc
					(start 47.87646 -61.392054)
					(mid 48.387 -61.902594)
					(end 48.89754 -61.392054)
				)
			)
		)
		(polygon
			(pts
				(xy 228.393244 -60.043822) (xy 226.386644 -60.043822) (xy 226.386644 -61.935868) (xy 226.386898 -61.936122)
				(xy 228.393244 -61.936122)
			)
		)
		(polygon
			(pts
				(xy 43.393106 -60.043822) (xy 41.38676 -60.043822) (xy 41.38676 -61.936122) (xy 43.39336 -61.936122)
				(xy 43.39336 -60.044076)
			)
		)
		(polygon
			(pts
				(arc
					(start 230.720138 -60.300616)
					(mid 231.230424 -59.789949)
					(end 230.719884 -59.279536)
				)
				(arc
					(start 229.907084 -59.279536)
					(mid 229.396544 -59.790076)
					(end 229.907084 -60.300616)
				)
			)
		)
		(polygon
			(pts
				(arc
					(start 45.72 -60.300616)
					(mid 46.23054 -59.790076)
					(end 45.72 -59.279536)
				)
				(arc
					(start 44.906946 -59.279536)
					(mid 44.39666 -59.790203)
					(end 44.9072 -60.300616)
				)
			)
		)
		(polygon
			(pts
				(xy 225.203004 -56.44388) (xy 223.196658 -56.44388) (xy 223.196658 -58.335926) (xy 225.203258 -58.335926)
				(xy 225.203258 -56.444134)
			)
		)
		(polygon
			(pts
				(xy 40.20312 -56.44388) (xy 38.196774 -56.44388) (xy 38.196774 -58.335926) (xy 40.203374 -58.335926)
				(xy 40.203374 -56.444134)
			)
		)
		(polygon
			(pts
				(arc
					(start 222.339154 -56.830976)
					(mid 221.726887 -56.21909)
					(end 221.114874 -56.83123)
				)
				(arc
					(start 221.114874 -57.94883)
					(mid 221.727014 -58.56097)
					(end 222.339154 -57.94883)
				)
			)
		)
		(polygon
			(pts
				(arc
					(start 37.33927 -56.830976)
					(mid 36.727003 -56.21909)
					(end 36.11499 -56.83123)
				)
				(arc
					(start 36.11499 -57.94883)
					(mid 36.72713 -58.56097)
					(end 37.33927 -57.94883)
				)
			)
		)
		(polygon
			(pts
				(arc
					(start 220.840554 -54.58333)
					(mid 220.329887 -54.073044)
					(end 219.819474 -54.583584)
				)
				(arc
					(start 219.819474 -55.396384)
					(mid 220.330014 -55.906924)
					(end 220.840554 -55.396384)
				)
			)
		)
		(polygon
			(pts
				(arc
					(start 35.84067 -54.58333)
					(mid 35.330003 -54.073044)
					(end 34.81959 -54.583584)
				)
				(arc
					(start 34.81959 -55.396384)
					(mid 35.33013 -55.906924)
					(end 35.84067 -55.396384)
				)
			)
		)
		(polygon
			(pts
				(xy 225.203004 -54.043834) (xy 223.196658 -54.043834) (xy 223.196658 -55.936134) (xy 225.203258 -55.936134)
				(xy 225.203258 -54.044088)
			)
		)
		(polygon
			(pts
				(xy 40.20312 -54.043834) (xy 38.196774 -54.043834) (xy 38.196774 -55.936134) (xy 40.203374 -55.936134)
				(xy 40.203374 -54.044088)
			)
		)
		(polygon
			(pts
				(xy 225.203004 -51.643788) (xy 223.196658 -51.643788) (xy 223.196658 -53.536088) (xy 225.203258 -53.536088)
				(xy 225.203258 -51.644042)
			)
		)
		(polygon
			(pts
				(xy 40.20312 -51.643788) (xy 38.196774 -51.643788) (xy 38.196774 -53.536088) (xy 40.203374 -53.536088)
				(xy 40.203374 -51.644042)
			)
		)
		(polygon
			(pts
				(xy 23.803356 -40.463724) (xy 21.796756 -40.463724) (xy 21.796756 -42.35577) (xy 21.79701 -42.356024)
				(xy 23.803356 -42.356024)
			)
		)
		(polygon
			(pts
				(arc
					(start 27.18054 -38.603428)
					(mid 26.67 -38.092888)
					(end 26.15946 -38.603428)
				)
				(arc
					(start 26.15946 -39.416482)
					(mid 26.670127 -39.926768)
					(end 27.18054 -39.416228)
				)
			)
		)
		(polygon
			(pts
				(xy 23.803356 -38.063678) (xy 21.796756 -38.063678) (xy 21.796756 -39.955724) (xy 21.79701 -39.955978)
				(xy 23.803356 -39.955978)
			)
		)
		(polygon
			(pts
				(xy 23.803356 -35.663886) (xy 21.796756 -35.663886) (xy 21.796756 -37.555678) (xy 21.79701 -37.555932)
				(xy 23.803356 -37.555932)
			)
		)
		(polygon
			(pts
				(arc
					(start 25.88514 -36.050982)
					(mid 25.273 -35.438842)
					(end 24.66086 -36.050982)
				)
				(arc
					(start 24.66086 -37.168836)
					(mid 25.273127 -37.780722)
					(end 25.88514 -37.168582)
				)
			)
		)
		(polygon
			(pts
				(arc
					(start 32.00654 -32.602932)
					(mid 31.495873 -32.092646)
					(end 30.98546 -32.603186)
				)
				(arc
					(start 30.98546 -33.415986)
					(mid 31.496 -33.926526)
					(end 32.00654 -33.415986)
				)
			)
		)
		(polygon
			(pts
				(arc
					(start 17.78254 -32.602932)
					(mid 17.271873 -32.092646)
					(end 16.76146 -32.603186)
				)
				(arc
					(start 16.76146 -33.415986)
					(mid 17.272 -33.926526)
					(end 17.78254 -33.415986)
				)
			)
		)
		(polygon
			(pts
				(xy 20.61337 -32.06369) (xy 18.60677 -32.06369) (xy 18.60677 -33.955736) (xy 18.607024 -33.95599)
				(xy 20.61337 -33.95599)
			)
		)
		(polygon
			(pts
				(arc
					(start 27.18054 -25.803352)
					(mid 26.67 -25.292812)
					(end 26.15946 -25.803352)
				)
				(arc
					(start 26.15946 -26.616406)
					(mid 26.670127 -27.126692)
					(end 27.18054 -26.616152)
				)
			)
		)
		(polygon
			(pts
				(xy 23.803356 -25.263856) (xy 21.796756 -25.263856) (xy 21.796756 -27.155648) (xy 21.79701 -27.155902)
				(xy 23.803356 -27.155902)
			)
		)
		(polygon
			(pts
				(xy 23.803356 -22.86381) (xy 21.796756 -22.86381) (xy 21.796756 -24.755856) (xy 21.79701 -24.75611)
				(xy 23.803356 -24.75611)
			)
		)
		(polygon
			(pts
				(arc
					(start 25.88514 -23.25116)
					(mid 25.273 -22.63902)
					(end 24.66086 -23.25116)
				)
				(arc
					(start 24.66086 -24.369014)
					(mid 25.273127 -24.9809)
					(end 25.88514 -24.36876)
				)
			)
		)
		(polygon
			(pts
				(arc
					(start 27.18054 -21.003514)
					(mid 26.67 -20.492974)
					(end 26.15946 -21.003514)
				)
				(arc
					(start 26.15946 -21.816568)
					(mid 26.670127 -22.326854)
					(end 27.18054 -21.816314)
				)
			)
		)
		(polygon
			(pts
				(xy 23.803356 -20.463764) (xy 21.796756 -20.463764) (xy 21.796756 -22.35581) (xy 21.79701 -22.356064)
				(xy 23.803356 -22.356064)
			)
		)
		(polygon
			(pts
				(xy 23.803356 -18.063718) (xy 21.796756 -18.063718) (xy 21.796756 -19.955764) (xy 21.79701 -19.956018)
				(xy 23.803356 -19.956018)
			)
		)
		(polygon
			(pts
				(arc
					(start 25.88514 -18.451068)
					(mid 25.273 -17.838928)
					(end 24.66086 -18.451068)
				)
				(arc
					(start 24.66086 -19.568922)
					(mid 25.273127 -20.180808)
					(end 25.88514 -19.568668)
				)
			)
		)
		(polygon
			(pts
				(arc
					(start 27.18054 -16.203422)
					(mid 26.67 -15.692882)
					(end 26.15946 -16.203422)
				)
				(arc
					(start 26.15946 -17.016476)
					(mid 26.670127 -17.526762)
					(end 27.18054 -17.016222)
				)
			)
		)
		(polygon
			(pts
				(xy 23.803356 -15.663672) (xy 21.796756 -15.663672) (xy 21.796756 -17.555718) (xy 21.79701 -17.555972)
				(xy 23.803356 -17.555972)
			)
		)
		(polygon
			(pts
				(xy 23.803356 -13.26388) (xy 21.796756 -13.26388) (xy 21.796756 -15.155672) (xy 21.79701 -15.155926)
				(xy 23.803356 -15.155926)
			)
		)
		(polygon
			(pts
				(arc
					(start 25.88514 -13.676122)
					(mid 25.272873 -13.064236)
					(end 24.66086 -13.676376)
				)
				(arc
					(start 24.66086 -14.793976)
					(mid 25.273 -15.406116)
					(end 25.88514 -14.793976)
				)
			)
		)
	)
	(zone
		(layer "In1.Cu")
		(hatch none 0.5)
		(connect_pads
			(clearance 0)
		)
		(min_thickness 0.25)
		(keepout
			(tracks not_allowed)
			(vias allowed)
			(pads allowed)
			(copperpour not_allowed)
			(footprints allowed)
		)
		(placement
			(enabled no)
			(sheetname "")
		)
		(fill
			(thermal_gap 0.5)
			(thermal_bridge_width 0.5)
			(island_removal_mode 0)
		)
		(polygon
			(pts
				(xy 97.577148 -96.59239) (xy 96.383856 -96.59239) (xy 96.383856 -97.76079) (xy 97.577148 -97.76079)
			)
		)
	)
	(zone
		(layer "In1.Cu")
		(hatch none 0.5)
		(connect_pads
			(clearance 0)
		)
		(min_thickness 0.25)
		(keepout
			(tracks not_allowed)
			(vias allowed)
			(pads allowed)
			(copperpour not_allowed)
			(footprints allowed)
		)
		(placement
			(enabled no)
			(sheetname "")
		)
		(fill
			(thermal_gap 0.5)
			(thermal_bridge_width 0.5)
			(island_removal_mode 0)
		)
		(polygon
			(pts
				(arc
					(start 90.1192 -313.1058)
					(mid 90.047358 -313.135558)
					(end 90.0176 -313.2074)
				)
				(arc
					(start 90.0176 -314.4266)
					(mid 90.047358 -314.498442)
					(end 90.1192 -314.5282)
				)
				(arc
					(start 91.4908 -314.5282)
					(mid 91.562642 -314.498442)
					(end 91.5924 -314.4266)
				)
				(arc
					(start 91.5924 -313.2074)
					(mid 91.562642 -313.135558)
					(end 91.4908 -313.1058)
				)
			)
		)
	)
	(zone
		(layer "In1.Cu")
		(hatch none 0.5)
		(connect_pads
			(clearance 0)
		)
		(min_thickness 0.25)
		(keepout
			(tracks not_allowed)
			(vias allowed)
			(pads allowed)
			(copperpour not_allowed)
			(footprints allowed)
		)
		(placement
			(enabled no)
			(sheetname "")
		)
		(fill
			(thermal_gap 0.5)
			(thermal_bridge_width 0.5)
			(island_removal_mode 0)
		)
		(polygon
			(pts
				(xy 94.384876 -310.18861) (xy 95.575628 -310.18861) (xy 95.575628 -309.02021) (xy 94.384876 -309.02021)
			)
		)
	)
	(zone
		(layer "In1.Cu")
		(hatch none 0.5)
		(connect_pads
			(clearance 0)
		)
		(min_thickness 0.25)
		(keepout
			(tracks not_allowed)
			(vias allowed)
			(pads allowed)
			(copperpour not_allowed)
			(footprints allowed)
		)
		(placement
			(enabled no)
			(sheetname "")
		)
		(fill
			(thermal_gap 0.5)
			(thermal_bridge_width 0.5)
			(island_removal_mode 0)
		)
		(polygon
			(pts
				(arc
					(start 77.6986 -305.47564)
					(mid 77.772238 -305.445138)
					(end 77.80274 -305.3715)
				)
				(arc
					(start 77.80274 -305.0159)
					(mid 77.772238 -304.942262)
					(end 77.6986 -304.91176)
				)
				(arc
					(start 77.343 -304.91176)
					(mid 77.269362 -304.942262)
					(end 77.23886 -305.0159)
				)
				(arc
					(start 77.23886 -305.3715)
					(mid 77.269362 -305.445138)
					(end 77.343 -305.47564)
				)
			)
		)
	)
	(zone
		(layer "In1.Cu")
		(hatch none 0.5)
		(connect_pads
			(clearance 0)
		)
		(min_thickness 0.25)
		(keepout
			(tracks not_allowed)
			(vias allowed)
			(pads allowed)
			(copperpour not_allowed)
			(footprints allowed)
		)
		(placement
			(enabled no)
			(sheetname "")
		)
		(fill
			(thermal_gap 0.5)
			(thermal_bridge_width 0.5)
			(island_removal_mode 0)
		)
		(polygon
			(pts
				(arc
					(start 86.3092 -92.2528)
					(mid 86.237358 -92.282558)
					(end 86.2076 -92.3544)
				)
				(arc
					(start 86.2076 -93.5736)
					(mid 86.237358 -93.645442)
					(end 86.3092 -93.6752)
				)
				(arc
					(start 87.6808 -93.6752)
					(mid 87.752642 -93.645442)
					(end 87.7824 -93.5736)
				)
				(arc
					(start 87.7824 -92.3544)
					(mid 87.752642 -92.282558)
					(end 87.6808 -92.2528)
				)
			)
		)
	)
	(zone
		(layer "In1.Cu")
		(hatch none 0.5)
		(connect_pads
			(clearance 0)
		)
		(min_thickness 0.25)
		(keepout
			(tracks not_allowed)
			(vias allowed)
			(pads allowed)
			(copperpour not_allowed)
			(footprints allowed)
		)
		(placement
			(enabled no)
			(sheetname "")
		)
		(fill
			(thermal_gap 0.5)
			(thermal_bridge_width 0.5)
			(island_removal_mode 0)
		)
		(polygon
			(pts
				(arc
					(start 101.9048 -307.8988)
					(mid 101.934558 -307.970642)
					(end 102.0064 -308.0004)
				)
				(arc
					(start 103.2256 -308.0004)
					(mid 103.297442 -307.970642)
					(end 103.3272 -307.8988)
				)
				(arc
					(start 103.3272 -306.5272)
					(mid 103.297442 -306.455358)
					(end 103.2256 -306.4256)
				)
				(arc
					(start 102.0064 -306.4256)
					(mid 101.934558 -306.455358)
					(end 101.9048 -306.5272)
				)
			)
		)
	)
	(zone
		(layer "In1.Cu")
		(hatch none 0.5)
		(connect_pads
			(clearance 0)
		)
		(min_thickness 0.25)
		(keepout
			(tracks not_allowed)
			(vias allowed)
			(pads allowed)
			(copperpour not_allowed)
			(footprints allowed)
		)
		(placement
			(enabled no)
			(sheetname "")
		)
		(fill
			(thermal_gap 0.5)
			(thermal_bridge_width 0.5)
			(island_removal_mode 0)
		)
		(polygon
			(pts
				(xy 91.882976 -215.82761) (xy 93.074236 -215.82761) (xy 93.074236 -214.65921) (xy 91.882976 -214.65921)
			)
		)
	)
	(zone
		(layer "In1.Cu")
		(hatch none 0.5)
		(connect_pads
			(clearance 0)
		)
		(min_thickness 0.25)
		(keepout
			(tracks not_allowed)
			(vias allowed)
			(pads allowed)
			(copperpour not_allowed)
			(footprints allowed)
		)
		(placement
			(enabled no)
			(sheetname "")
		)
		(fill
			(thermal_gap 0.5)
			(thermal_bridge_width 0.5)
			(island_removal_mode 0)
		)
		(polygon
			(pts
				(xy 98.98761 -308.777894) (xy 98.98761 -307.58638) (xy 97.81921 -307.58638) (xy 97.81921 -308.777894)
			)
		)
	)
	(zone
		(layer "In1.Cu")
		(hatch none 0.5)
		(connect_pads
			(clearance 0)
		)
		(min_thickness 0.25)
		(keepout
			(tracks not_allowed)
			(vias allowed)
			(pads allowed)
			(copperpour not_allowed)
			(footprints allowed)
		)
		(placement
			(enabled no)
			(sheetname "")
		)
		(fill
			(thermal_gap 0.5)
			(thermal_bridge_width 0.5)
			(island_removal_mode 0)
		)
		(polygon
			(pts
				(arc
					(start 99.1362 -313.1058)
					(mid 99.064358 -313.135558)
					(end 99.0346 -313.2074)
				)
				(arc
					(start 99.0346 -314.4266)
					(mid 99.064358 -314.498442)
					(end 99.1362 -314.5282)
				)
				(arc
					(start 100.5078 -314.5282)
					(mid 100.579642 -314.498442)
					(end 100.6094 -314.4266)
				)
				(arc
					(start 100.6094 -313.2074)
					(mid 100.579642 -313.135558)
					(end 100.5078 -313.1058)
				)
			)
		)
	)
	(zone
		(layer "In1.Cu")
		(hatch none 0.5)
		(connect_pads
			(clearance 0)
		)
		(min_thickness 0.25)
		(keepout
			(tracks not_allowed)
			(vias allowed)
			(pads allowed)
			(copperpour not_allowed)
			(footprints allowed)
		)
		(placement
			(enabled no)
			(sheetname "")
		)
		(fill
			(thermal_gap 0.5)
			(thermal_bridge_width 0.5)
			(island_removal_mode 0)
		)
		(polygon
			(pts
				(arc
					(start 90.1192 -422.4528)
					(mid 90.047358 -422.482558)
					(end 90.0176 -422.5544)
				)
				(arc
					(start 90.0176 -423.7736)
					(mid 90.047358 -423.845442)
					(end 90.1192 -423.8752)
				)
				(arc
					(start 91.4908 -423.8752)
					(mid 91.562642 -423.845442)
					(end 91.5924 -423.7736)
				)
				(arc
					(start 91.5924 -422.5544)
					(mid 91.562642 -422.482558)
					(end 91.4908 -422.4528)
				)
			)
		)
	)
	(zone
		(layer "In1.Cu")
		(hatch none 0.5)
		(connect_pads
			(clearance 0)
		)
		(min_thickness 0.25)
		(keepout
			(tracks not_allowed)
			(vias allowed)
			(pads allowed)
			(copperpour not_allowed)
			(footprints allowed)
		)
		(placement
			(enabled no)
			(sheetname "")
		)
		(fill
			(thermal_gap 0.5)
			(thermal_bridge_width 0.5)
			(island_removal_mode 0)
		)
		(polygon
			(pts
				(arc
					(start 6.5532 -377.7234)
					(mid 6.481358 -377.753158)
					(end 6.4516 -377.825)
				)
				(arc
					(start 6.4516 -379.1458)
					(mid 6.481358 -379.217642)
					(end 6.5532 -379.2474)
				)
				(arc
					(start 7.874 -379.2474)
					(mid 7.945842 -379.217642)
					(end 7.9756 -379.1458)
				)
				(arc
					(start 7.9756 -377.825)
					(mid 7.945842 -377.753158)
					(end 7.874 -377.7234)
				)
			)
		)
	)
	(zone
		(layer "In1.Cu")
		(hatch none 0.5)
		(connect_pads
			(clearance 0)
		)
		(min_thickness 0.25)
		(keepout
			(tracks not_allowed)
			(vias allowed)
			(pads allowed)
			(copperpour not_allowed)
			(footprints allowed)
		)
		(placement
			(enabled no)
			(sheetname "")
		)
		(fill
			(thermal_gap 0.5)
			(thermal_bridge_width 0.5)
			(island_removal_mode 0)
		)
		(polygon
			(pts
				(arc
					(start 85.95614 -100.838)
					(mid 85.940517 -100.800283)
					(end 85.9028 -100.78466)
				)
				(arc
					(start 85.6996 -100.78466)
					(mid 85.661883 -100.800283)
					(end 85.64626 -100.838)
				)
				(arc
					(start 85.64626 -101.092)
					(mid 85.661883 -101.129717)
					(end 85.6996 -101.14534)
				)
				(arc
					(start 85.9028 -101.14534)
					(mid 85.940517 -101.129717)
					(end 85.95614 -101.092)
				)
			)
		)
	)
	(zone
		(layer "In1.Cu")
		(hatch none 0.5)
		(connect_pads
			(clearance 0)
		)
		(min_thickness 0.25)
		(keepout
			(tracks not_allowed)
			(vias allowed)
			(pads allowed)
			(copperpour not_allowed)
			(footprints allowed)
		)
		(placement
			(enabled no)
			(sheetname "")
		)
		(fill
			(thermal_gap 0.5)
			(thermal_bridge_width 0.5)
			(island_removal_mode 0)
		)
		(polygon
			(pts
				(xy 91.883992 -310.18861) (xy 93.073728 -310.18861) (xy 93.073728 -309.02021) (xy 91.883992 -309.02021)
			)
		)
	)
	(zone
		(layer "In1.Cu")
		(hatch none 0.5)
		(connect_pads
			(clearance 0)
		)
		(min_thickness 0.25)
		(keepout
			(tracks not_allowed)
			(vias allowed)
			(pads allowed)
			(copperpour not_allowed)
			(footprints allowed)
		)
		(placement
			(enabled no)
			(sheetname "")
		)
		(fill
			(thermal_gap 0.5)
			(thermal_bridge_width 0.5)
			(island_removal_mode 0)
		)
		(polygon
			(pts
				(arc
					(start 101.9048 -311.7088)
					(mid 101.934558 -311.780642)
					(end 102.0064 -311.8104)
				)
				(arc
					(start 103.2256 -311.8104)
					(mid 103.297442 -311.780642)
					(end 103.3272 -311.7088)
				)
				(arc
					(start 103.3272 -310.3372)
					(mid 103.297442 -310.265358)
					(end 103.2256 -310.2356)
				)
				(arc
					(start 102.0064 -310.2356)
					(mid 101.934558 -310.265358)
					(end 101.9048 -310.3372)
				)
			)
		)
	)
	(zone
		(layer "In1.Cu")
		(hatch none 0.5)
		(connect_pads
			(clearance 0)
		)
		(min_thickness 0.25)
		(keepout
			(tracks not_allowed)
			(vias allowed)
			(pads allowed)
			(copperpour not_allowed)
			(footprints allowed)
		)
		(placement
			(enabled no)
			(sheetname "")
		)
		(fill
			(thermal_gap 0.5)
			(thermal_bridge_width 0.5)
			(island_removal_mode 0)
		)
		(polygon
			(pts
				(arc
					(start 85.87994 -304.8381)
					(mid 85.864317 -304.800383)
					(end 85.8266 -304.78476)
				)
				(arc
					(start 85.6234 -304.78476)
					(mid 85.585683 -304.800383)
					(end 85.57006 -304.8381)
				)
				(arc
					(start 85.57006 -305.0921)
					(mid 85.585683 -305.129817)
					(end 85.6234 -305.14544)
				)
				(arc
					(start 85.8266 -305.14544)
					(mid 85.864317 -305.129817)
					(end 85.87994 -305.0921)
				)
			)
		)
	)
	(zone
		(layer "In1.Cu")
		(hatch none 0.5)
		(connect_pads
			(clearance 0)
		)
		(min_thickness 0.25)
		(keepout
			(tracks not_allowed)
			(vias allowed)
			(pads allowed)
			(copperpour not_allowed)
			(footprints allowed)
		)
		(placement
			(enabled no)
			(sheetname "")
		)
		(fill
			(thermal_gap 0.5)
			(thermal_bridge_width 0.5)
			(island_removal_mode 0)
		)
		(polygon
			(pts
				(arc
					(start 86.3092 -109.5248)
					(mid 86.237358 -109.554558)
					(end 86.2076 -109.6264)
				)
				(arc
					(start 86.2076 -110.8456)
					(mid 86.237358 -110.917442)
					(end 86.3092 -110.9472)
				)
				(arc
					(start 87.6808 -110.9472)
					(mid 87.752642 -110.917442)
					(end 87.7824 -110.8456)
				)
				(arc
					(start 87.7824 -109.6264)
					(mid 87.752642 -109.554558)
					(end 87.6808 -109.5248)
				)
			)
		)
	)
	(zone
		(layer "In1.Cu")
		(hatch none 0.5)
		(connect_pads
			(clearance 0)
		)
		(min_thickness 0.25)
		(keepout
			(tracks not_allowed)
			(vias allowed)
			(pads allowed)
			(copperpour not_allowed)
			(footprints allowed)
		)
		(placement
			(enabled no)
			(sheetname "")
		)
		(fill
			(thermal_gap 0.5)
			(thermal_bridge_width 0.5)
			(island_removal_mode 0)
		)
		(polygon
			(pts
				(arc
					(start 86.3092 -313.1058)
					(mid 86.237358 -313.135558)
					(end 86.2076 -313.2074)
				)
				(arc
					(start 86.2076 -314.4266)
					(mid 86.237358 -314.498442)
					(end 86.3092 -314.5282)
				)
				(arc
					(start 87.6808 -314.5282)
					(mid 87.752642 -314.498442)
					(end 87.7824 -314.4266)
				)
				(arc
					(start 87.7824 -313.2074)
					(mid 87.752642 -313.135558)
					(end 87.6808 -313.1058)
				)
			)
		)
	)
	(zone
		(layer "In1.Cu")
		(hatch none 0.5)
		(connect_pads
			(clearance 0)
		)
		(min_thickness 0.25)
		(keepout
			(tracks not_allowed)
			(vias allowed)
			(pads allowed)
			(copperpour not_allowed)
			(footprints allowed)
		)
		(placement
			(enabled no)
			(sheetname "")
		)
		(fill
			(thermal_gap 0.5)
			(thermal_bridge_width 0.5)
			(island_removal_mode 0)
		)
		(polygon
			(pts
				(arc
					(start 77.1652 -209.52206)
					(mid 77.091562 -209.552562)
					(end 77.06106 -209.6262)
				)
				(arc
					(start 77.06106 -209.9818)
					(mid 77.091562 -210.055438)
					(end 77.1652 -210.08594)
				)
				(arc
					(start 77.5208 -210.08594)
					(mid 77.594438 -210.055438)
					(end 77.62494 -209.9818)
				)
				(arc
					(start 77.62494 -209.6262)
					(mid 77.594438 -209.552562)
					(end 77.5208 -209.52206)
				)
			)
		)
	)
	(zone
		(layer "In1.Cu")
		(hatch none 0.5)
		(connect_pads
			(clearance 0)
		)
		(min_thickness 0.25)
		(keepout
			(tracks not_allowed)
			(vias allowed)
			(pads allowed)
			(copperpour not_allowed)
			(footprints allowed)
		)
		(placement
			(enabled no)
			(sheetname "")
		)
		(fill
			(thermal_gap 0.5)
			(thermal_bridge_width 0.5)
			(island_removal_mode 0)
		)
		(polygon
			(pts
				(arc
					(start 97.4852 -201.4728)
					(mid 97.413358 -201.502558)
					(end 97.3836 -201.5744)
				)
				(arc
					(start 97.3836 -202.7936)
					(mid 97.413358 -202.865442)
					(end 97.4852 -202.8952)
				)
				(arc
					(start 98.8568 -202.8952)
					(mid 98.928642 -202.865442)
					(end 98.9584 -202.7936)
				)
				(arc
					(start 98.9584 -201.5744)
					(mid 98.928642 -201.502558)
					(end 98.8568 -201.4728)
				)
			)
		)
	)
	(zone
		(layer "In1.Cu")
		(hatch none 0.5)
		(connect_pads
			(clearance 0)
		)
		(min_thickness 0.25)
		(keepout
			(tracks not_allowed)
			(vias allowed)
			(pads allowed)
			(copperpour not_allowed)
			(footprints allowed)
		)
		(placement
			(enabled no)
			(sheetname "")
		)
		(fill
			(thermal_gap 0.5)
			(thermal_bridge_width 0.5)
			(island_removal_mode 0)
		)
		(polygon
			(pts
				(arc
					(start 86.3092 -439.7248)
					(mid 86.237358 -439.754558)
					(end 86.2076 -439.8264)
				)
				(arc
					(start 86.2076 -441.0456)
					(mid 86.237358 -441.117442)
					(end 86.3092 -441.1472)
				)
				(arc
					(start 87.6808 -441.1472)
					(mid 87.752642 -441.117442)
					(end 87.7824 -441.0456)
				)
				(arc
					(start 87.7824 -439.8264)
					(mid 87.752642 -439.754558)
					(end 87.6808 -439.7248)
				)
			)
		)
	)
	(zone
		(layer "In1.Cu")
		(hatch none 0.5)
		(connect_pads
			(clearance 0)
		)
		(min_thickness 0.25)
		(keepout
			(tracks not_allowed)
			(vias allowed)
			(pads allowed)
			(copperpour not_allowed)
			(footprints allowed)
		)
		(placement
			(enabled no)
			(sheetname "")
		)
		(fill
			(thermal_gap 0.5)
			(thermal_bridge_width 0.5)
			(island_removal_mode 0)
		)
		(polygon
			(pts
				(arc
					(start 83.61934 -431.4571)
					(mid 83.603717 -431.419383)
					(end 83.566 -431.40376)
				)
				(arc
					(start 83.3628 -431.40376)
					(mid 83.325083 -431.419383)
					(end 83.30946 -431.4571)
				)
				(arc
					(start 83.30946 -431.7111)
					(mid 83.325083 -431.748817)
					(end 83.3628 -431.76444)
				)
				(arc
					(start 83.566 -431.76444)
					(mid 83.603717 -431.748817)
					(end 83.61934 -431.7111)
				)
			)
		)
	)
	(zone
		(layer "In1.Cu")
		(hatch none 0.5)
		(connect_pads
			(clearance 0)
		)
		(min_thickness 0.25)
		(keepout
			(tracks not_allowed)
			(vias allowed)
			(pads allowed)
			(copperpour not_allowed)
			(footprints allowed)
		)
		(placement
			(enabled no)
			(sheetname "")
		)
		(fill
			(thermal_gap 0.5)
			(thermal_bridge_width 0.5)
			(island_removal_mode 0)
		)
		(polygon
			(pts
				(arc
					(start 77.9526 -432.09464)
					(mid 78.026238 -432.064138)
					(end 78.05674 -431.9905)
				)
				(arc
					(start 78.05674 -431.6349)
					(mid 78.026238 -431.561262)
					(end 77.9526 -431.53076)
				)
				(arc
					(start 77.597 -431.53076)
					(mid 77.523362 -431.561262)
					(end 77.49286 -431.6349)
				)
				(arc
					(start 77.49286 -431.9905)
					(mid 77.523362 -432.064138)
					(end 77.597 -432.09464)
				)
			)
		)
	)
	(zone
		(layer "In1.Cu")
		(hatch none 0.5)
		(connect_pads
			(clearance 0)
		)
		(min_thickness 0.25)
		(keepout
			(tracks not_allowed)
			(vias allowed)
			(pads allowed)
			(copperpour not_allowed)
			(footprints allowed)
		)
		(placement
			(enabled no)
			(sheetname "")
		)
		(fill
			(thermal_gap 0.5)
			(thermal_bridge_width 0.5)
			(island_removal_mode 0)
		)
		(polygon
			(pts
				(arc
					(start 95.3262 -109.5248)
					(mid 95.254358 -109.554558)
					(end 95.2246 -109.6264)
				)
				(arc
					(start 95.2246 -110.8456)
					(mid 95.254358 -110.917442)
					(end 95.3262 -110.9472)
				)
				(arc
					(start 96.6978 -110.9472)
					(mid 96.769642 -110.917442)
					(end 96.7994 -110.8456)
				)
				(arc
					(start 96.7994 -109.6264)
					(mid 96.769642 -109.554558)
					(end 96.6978 -109.5248)
				)
			)
		)
	)
	(zone
		(layer "In1.Cu")
		(hatch none 0.5)
		(connect_pads
			(clearance 0)
		)
		(min_thickness 0.25)
		(keepout
			(tracks not_allowed)
			(vias allowed)
			(pads allowed)
			(copperpour not_allowed)
			(footprints allowed)
		)
		(placement
			(enabled no)
			(sheetname "")
		)
		(fill
			(thermal_gap 0.5)
			(thermal_bridge_width 0.5)
			(island_removal_mode 0)
		)
		(polygon
			(pts
				(xy 95.576898 -300.17339) (xy 94.383098 -300.17339) (xy 94.383098 -301.34179) (xy 95.576898 -301.34179)
			)
		)
	)
	(zone
		(layer "In1.Cu")
		(hatch none 0.5)
		(connect_pads
			(clearance 0)
		)
		(min_thickness 0.25)
		(keepout
			(tracks not_allowed)
			(vias allowed)
			(pads allowed)
			(copperpour not_allowed)
			(footprints allowed)
		)
		(placement
			(enabled no)
			(sheetname "")
		)
		(fill
			(thermal_gap 0.5)
			(thermal_bridge_width 0.5)
			(island_removal_mode 0)
		)
		(polygon
			(pts
				(xy 89.91854 -310.18861) (xy 91.077288 -310.18861) (xy 91.077288 -309.02021) (xy 89.91854 -309.02021)
			)
		)
	)
	(zone
		(layer "In1.Cu")
		(hatch none 0.5)
		(connect_pads
			(clearance 0)
		)
		(min_thickness 0.25)
		(keepout
			(tracks not_allowed)
			(vias allowed)
			(pads allowed)
			(copperpour not_allowed)
			(footprints allowed)
		)
		(placement
			(enabled no)
			(sheetname "")
		)
		(fill
			(thermal_gap 0.5)
			(thermal_bridge_width 0.5)
			(island_removal_mode 0)
		)
		(polygon
			(pts
				(xy 88.97239 -430.703736) (xy 88.97239 -431.895504) (xy 90.14079 -431.895504) (xy 90.14079 -430.703736)
			)
		)
	)
	(zone
		(layer "In1.Cu")
		(hatch none 0.5)
		(connect_pads
			(clearance 0)
		)
		(min_thickness 0.25)
		(keepout
			(tracks not_allowed)
			(vias allowed)
			(pads allowed)
			(copperpour not_allowed)
			(footprints allowed)
		)
		(placement
			(enabled no)
			(sheetname "")
		)
		(fill
			(thermal_gap 0.5)
			(thermal_bridge_width 0.5)
			(island_removal_mode 0)
		)
		(polygon
			(pts
				(xy 96.384364 -310.18861) (xy 97.575624 -310.18861) (xy 97.575624 -309.02021) (xy 96.384364 -309.02021)
			)
		)
	)
	(zone
		(layer "In1.Cu")
		(hatch none 0.5)
		(connect_pads
			(clearance 0)
		)
		(min_thickness 0.25)
		(keepout
			(tracks not_allowed)
			(vias allowed)
			(pads allowed)
			(copperpour not_allowed)
			(footprints allowed)
		)
		(placement
			(enabled no)
			(sheetname "")
		)
		(fill
			(thermal_gap 0.5)
			(thermal_bridge_width 0.5)
			(island_removal_mode 0)
		)
		(polygon
			(pts
				(arc
					(start 99.1362 -218.7448)
					(mid 99.064358 -218.774558)
					(end 99.0346 -218.8464)
				)
				(arc
					(start 99.0346 -220.0656)
					(mid 99.064358 -220.137442)
					(end 99.1362 -220.1672)
				)
				(arc
					(start 100.5078 -220.1672)
					(mid 100.579642 -220.137442)
					(end 100.6094 -220.0656)
				)
				(arc
					(start 100.6094 -218.8464)
					(mid 100.579642 -218.774558)
					(end 100.5078 -218.7448)
				)
			)
		)
	)
	(zone
		(layer "In1.Cu")
		(hatch none 0.5)
		(connect_pads
			(clearance 0)
		)
		(min_thickness 0.25)
		(keepout
			(tracks not_allowed)
			(vias allowed)
			(pads allowed)
			(copperpour not_allowed)
			(footprints allowed)
		)
		(placement
			(enabled no)
			(sheetname "")
		)
		(fill
			(thermal_gap 0.5)
			(thermal_bridge_width 0.5)
			(island_removal_mode 0)
		)
		(polygon
			(pts
				(arc
					(start 90.1192 -439.7248)
					(mid 90.047358 -439.754558)
					(end 90.0176 -439.8264)
				)
				(arc
					(start 90.0176 -441.0456)
					(mid 90.047358 -441.117442)
					(end 90.1192 -441.1472)
				)
				(arc
					(start 91.4908 -441.1472)
					(mid 91.562642 -441.117442)
					(end 91.5924 -441.0456)
				)
				(arc
					(start 91.5924 -439.8264)
					(mid 91.562642 -439.754558)
					(end 91.4908 -439.7248)
				)
			)
		)
	)
	(zone
		(layer "In1.Cu")
		(hatch none 0.5)
		(connect_pads
			(clearance 0)
		)
		(min_thickness 0.25)
		(keepout
			(tracks not_allowed)
			(vias allowed)
			(pads allowed)
			(copperpour not_allowed)
			(footprints allowed)
		)
		(placement
			(enabled no)
			(sheetname "")
		)
		(fill
			(thermal_gap 0.5)
			(thermal_bridge_width 0.5)
			(island_removal_mode 0)
		)
		(polygon
			(pts
				(arc
					(start 77.5208 -211.12734)
					(mid 77.594438 -211.096838)
					(end 77.62494 -211.0232)
				)
				(arc
					(start 77.62494 -210.6676)
					(mid 77.594438 -210.593962)
					(end 77.5208 -210.56346)
				)
				(arc
					(start 77.1652 -210.56346)
					(mid 77.091562 -210.593962)
					(end 77.06106 -210.6676)
				)
				(arc
					(start 77.06106 -211.0232)
					(mid 77.091562 -211.096838)
					(end 77.1652 -211.12734)
				)
			)
		)
	)
	(zone
		(layer "In1.Cu")
		(hatch none 0.5)
		(connect_pads
			(clearance 0)
		)
		(min_thickness 0.25)
		(keepout
			(tracks not_allowed)
			(vias allowed)
			(pads allowed)
			(copperpour not_allowed)
			(footprints allowed)
		)
		(placement
			(enabled no)
			(sheetname "")
		)
		(fill
			(thermal_gap 0.5)
			(thermal_bridge_width 0.5)
			(island_removal_mode 0)
		)
		(polygon
			(pts
				(arc
					(start 85.87994 -304.2793)
					(mid 85.864317 -304.241583)
					(end 85.8266 -304.22596)
				)
				(arc
					(start 85.6234 -304.22596)
					(mid 85.585683 -304.241583)
					(end 85.57006 -304.2793)
				)
				(arc
					(start 85.57006 -304.5333)
					(mid 85.585683 -304.571017)
					(end 85.6234 -304.58664)
				)
				(arc
					(start 85.8266 -304.58664)
					(mid 85.864317 -304.571017)
					(end 85.87994 -304.5333)
				)
			)
		)
	)
	(zone
		(layer "In1.Cu")
		(hatch none 0.5)
		(connect_pads
			(clearance 0)
		)
		(min_thickness 0.25)
		(keepout
			(tracks not_allowed)
			(vias allowed)
			(pads allowed)
			(copperpour not_allowed)
			(footprints allowed)
		)
		(placement
			(enabled no)
			(sheetname "")
		)
		(fill
			(thermal_gap 0.5)
			(thermal_bridge_width 0.5)
			(island_removal_mode 0)
		)
		(polygon
			(pts
				(arc
					(start 77.3176 -100.42906)
					(mid 77.243962 -100.459562)
					(end 77.21346 -100.5332)
				)
				(arc
					(start 77.21346 -100.8888)
					(mid 77.243962 -100.962438)
					(end 77.3176 -100.99294)
				)
				(arc
					(start 77.6732 -100.99294)
					(mid 77.746838 -100.962438)
					(end 77.77734 -100.8888)
				)
				(arc
					(start 77.77734 -100.5332)
					(mid 77.746838 -100.459562)
					(end 77.6732 -100.42906)
				)
			)
		)
	)
	(zone
		(layer "In1.Cu")
		(hatch none 0.5)
		(connect_pads
			(clearance 0)
		)
		(min_thickness 0.25)
		(keepout
			(tracks not_allowed)
			(vias allowed)
			(pads allowed)
			(copperpour not_allowed)
			(footprints allowed)
		)
		(placement
			(enabled no)
			(sheetname "")
		)
		(fill
			(thermal_gap 0.5)
			(thermal_bridge_width 0.5)
			(island_removal_mode 0)
		)
		(polygon
			(pts
				(arc
					(start 78.74 -100.99294)
					(mid 78.813638 -100.962438)
					(end 78.84414 -100.8888)
				)
				(arc
					(start 78.84414 -100.5332)
					(mid 78.813638 -100.459562)
					(end 78.74 -100.42906)
				)
				(arc
					(start 78.3844 -100.42906)
					(mid 78.310762 -100.459562)
					(end 78.28026 -100.5332)
				)
				(arc
					(start 78.28026 -100.8888)
					(mid 78.310762 -100.962438)
					(end 78.3844 -100.99294)
				)
			)
		)
	)
	(zone
		(layer "In1.Cu")
		(hatch none 0.5)
		(connect_pads
			(clearance 0)
		)
		(min_thickness 0.25)
		(keepout
			(tracks not_allowed)
			(vias allowed)
			(pads allowed)
			(copperpour not_allowed)
			(footprints allowed)
		)
		(placement
			(enabled no)
			(sheetname "")
		)
		(fill
			(thermal_gap 0.5)
			(thermal_bridge_width 0.5)
			(island_removal_mode 0)
		)
		(polygon
			(pts
				(xy 98.98761 -306.777136) (xy 98.98761 -305.58486) (xy 97.81921 -305.58486) (xy 97.81921 -306.777136)
			)
		)
	)
	(zone
		(layer "In1.Cu")
		(hatch none 0.5)
		(connect_pads
			(clearance 0)
		)
		(min_thickness 0.25)
		(keepout
			(tracks not_allowed)
			(vias allowed)
			(pads allowed)
			(copperpour not_allowed)
			(footprints allowed)
		)
		(placement
			(enabled no)
			(sheetname "")
		)
		(fill
			(thermal_gap 0.5)
			(thermal_bridge_width 0.5)
			(island_removal_mode 0)
		)
		(polygon
			(pts
				(arc
					(start 86.3092 -218.7448)
					(mid 86.237358 -218.774558)
					(end 86.2076 -218.8464)
				)
				(arc
					(start 86.2076 -220.0656)
					(mid 86.237358 -220.137442)
					(end 86.3092 -220.1672)
				)
				(arc
					(start 87.6808 -220.1672)
					(mid 87.752642 -220.137442)
					(end 87.7824 -220.0656)
				)
				(arc
					(start 87.7824 -218.8464)
					(mid 87.752642 -218.774558)
					(end 87.6808 -218.7448)
				)
			)
		)
	)
	(zone
		(layer "In1.Cu")
		(hatch none 0.5)
		(connect_pads
			(clearance 0)
		)
		(min_thickness 0.25)
		(keepout
			(tracks not_allowed)
			(vias allowed)
			(pads allowed)
			(copperpour not_allowed)
			(footprints allowed)
		)
		(placement
			(enabled no)
			(sheetname "")
		)
		(fill
			(thermal_gap 0.5)
			(thermal_bridge_width 0.5)
			(island_removal_mode 0)
		)
		(polygon
			(pts
				(arc
					(start 86.3092 -422.4528)
					(mid 86.237358 -422.482558)
					(end 86.2076 -422.5544)
				)
				(arc
					(start 86.2076 -423.7736)
					(mid 86.237358 -423.845442)
					(end 86.3092 -423.8752)
				)
				(arc
					(start 87.6808 -423.8752)
					(mid 87.752642 -423.845442)
					(end 87.7824 -423.7736)
				)
				(arc
					(start 87.7824 -422.5544)
					(mid 87.752642 -422.482558)
					(end 87.6808 -422.4528)
				)
			)
		)
	)
	(zone
		(layer "In1.Cu")
		(hatch none 0.5)
		(connect_pads
			(clearance 0)
		)
		(min_thickness 0.25)
		(keepout
			(tracks not_allowed)
			(vias allowed)
			(pads allowed)
			(copperpour not_allowed)
			(footprints allowed)
		)
		(placement
			(enabled no)
			(sheetname "")
		)
		(fill
			(thermal_gap 0.5)
			(thermal_bridge_width 0.5)
			(island_removal_mode 0)
		)
		(polygon
			(pts
				(arc
					(start 78.3844 -101.47046)
					(mid 78.310762 -101.500962)
					(end 78.28026 -101.5746)
				)
				(arc
					(start 78.28026 -101.9302)
					(mid 78.310762 -102.003838)
					(end 78.3844 -102.03434)
				)
				(arc
					(start 78.74 -102.03434)
					(mid 78.813638 -102.003838)
					(end 78.84414 -101.9302)
				)
				(arc
					(start 78.84414 -101.5746)
					(mid 78.813638 -101.500962)
					(end 78.74 -101.47046)
				)
			)
		)
	)
	(zone
		(layer "In1.Cu")
		(hatch none 0.5)
		(connect_pads
			(clearance 0)
		)
		(min_thickness 0.25)
		(keepout
			(tracks not_allowed)
			(vias allowed)
			(pads allowed)
			(copperpour not_allowed)
			(footprints allowed)
		)
		(placement
			(enabled no)
			(sheetname "")
		)
		(fill
			(thermal_gap 0.5)
			(thermal_bridge_width 0.5)
			(island_removal_mode 0)
		)
		(polygon
			(pts
				(arc
					(start 90.1192 -109.5248)
					(mid 90.047358 -109.554558)
					(end 90.0176 -109.6264)
				)
				(arc
					(start 90.0176 -110.8456)
					(mid 90.047358 -110.917442)
					(end 90.1192 -110.9472)
				)
				(arc
					(start 91.4908 -110.9472)
					(mid 91.562642 -110.917442)
					(end 91.5924 -110.8456)
				)
				(arc
					(start 91.5924 -109.6264)
					(mid 91.562642 -109.554558)
					(end 91.4908 -109.5248)
				)
			)
		)
	)
	(zone
		(layers "In1.Cu" "In2.Cu")
		(hatch none 0.5)
		(connect_pads
			(clearance 0)
		)
		(min_thickness 0.25)
		(keepout
			(tracks not_allowed)
			(vias allowed)
			(pads allowed)
			(copperpour not_allowed)
			(footprints allowed)
		)
		(placement
			(enabled no)
			(sheetname "")
		)
		(fill yes
			(thermal_gap 0.5)
			(thermal_bridge_width 0.5)
			(island_removal_mode 0)
		)
		(polygon
			(pts
				(xy 23.803356 -336.156046) (xy 23.803356 -334.264) (xy 21.796756 -334.264) (xy 21.796756 -336.155792)
				(xy 21.79701 -336.156046)
			)
		)
	)
	(zone
		(layers "In1.Cu" "In2.Cu")
		(hatch none 0.5)
		(connect_pads
			(clearance 0)
		)
		(min_thickness 0.25)
		(keepout
			(tracks not_allowed)
			(vias allowed)
			(pads allowed)
			(copperpour not_allowed)
			(footprints allowed)
		)
		(placement
			(enabled no)
			(sheetname "")
		)
		(fill yes
			(thermal_gap 0.5)
			(thermal_bridge_width 0.5)
			(island_removal_mode 0)
		)
		(polygon
			(pts
				(xy 23.803356 -351.356168) (xy 23.803356 -349.463868) (xy 21.796756 -349.463868) (xy 21.796756 -351.355914)
				(xy 21.79701 -351.356168)
			)
		)
	)
	(zone
		(layers "In1.Cu" "In2.Cu")
		(hatch none 0.5)
		(connect_pads
			(clearance 0)
		)
		(min_thickness 0.25)
		(keepout
			(tracks not_allowed)
			(vias allowed)
			(pads allowed)
			(copperpour not_allowed)
			(footprints allowed)
		)
		(placement
			(enabled no)
			(sheetname "")
		)
		(fill yes
			(thermal_gap 0.5)
			(thermal_bridge_width 0.5)
			(island_removal_mode 0)
		)
		(polygon
			(pts
				(xy 223.196658 -260.04393) (xy 223.196658 -261.93623) (xy 225.203258 -261.93623) (xy 225.203258 -260.044184)
				(xy 225.203004 -260.04393)
			)
		)
	)
	(zone
		(layers "In1.Cu" "In2.Cu")
		(hatch none 0.5)
		(connect_pads
			(clearance 0)
		)
		(min_thickness 0.25)
		(keepout
			(tracks not_allowed)
			(vias allowed)
			(pads allowed)
			(copperpour not_allowed)
			(footprints allowed)
		)
		(placement
			(enabled no)
			(sheetname "")
		)
		(fill yes
			(thermal_gap 0.5)
			(thermal_bridge_width 0.5)
			(island_removal_mode 0)
		)
		(polygon
			(pts
				(xy 38.196774 -54.043834) (xy 38.196774 -55.936134) (xy 40.203374 -55.936134) (xy 40.203374 -54.044088)
				(xy 40.20312 -54.043834)
			)
		)
	)
	(zone
		(layers "In1.Cu" "In2.Cu")
		(hatch none 0.5)
		(connect_pads
			(clearance 0)
		)
		(min_thickness 0.25)
		(keepout
			(tracks not_allowed)
			(vias allowed)
			(pads allowed)
			(copperpour not_allowed)
			(footprints allowed)
		)
		(placement
			(enabled no)
			(sheetname "")
		)
		(fill yes
			(thermal_gap 0.5)
			(thermal_bridge_width 0.5)
			(island_removal_mode 0)
		)
		(polygon
			(pts
				(xy 223.196658 -486.043986) (xy 223.196658 -487.936286) (xy 225.203258 -487.936286) (xy 225.203258 -486.04424)
				(xy 225.203004 -486.043986)
			)
		)
	)
	(zone
		(layers "In1.Cu" "In2.Cu")
		(hatch none 0.5)
		(connect_pads
			(clearance 0)
		)
		(min_thickness 0.25)
		(keepout
			(tracks not_allowed)
			(vias allowed)
			(pads allowed)
			(copperpour not_allowed)
			(footprints allowed)
		)
		(placement
			(enabled no)
			(sheetname "")
		)
		(fill yes
			(thermal_gap 0.5)
			(thermal_bridge_width 0.5)
			(island_removal_mode 0)
		)
		(polygon
			(pts
				(xy 23.803356 -223.556068) (xy 23.803356 -221.663768) (xy 21.796756 -221.663768) (xy 21.796756 -223.555814)
				(xy 21.79701 -223.556068)
			)
		)
	)
	(zone
		(layers "In1.Cu" "In2.Cu")
		(hatch none 0.5)
		(connect_pads
			(clearance 0)
		)
		(min_thickness 0.25)
		(keepout
			(tracks not_allowed)
			(vias allowed)
			(pads allowed)
			(copperpour not_allowed)
			(footprints allowed)
		)
		(placement
			(enabled no)
			(sheetname "")
		)
		(fill yes
			(thermal_gap 0.5)
			(thermal_bridge_width 0.5)
			(island_removal_mode 0)
		)
		(polygon
			(pts
				(xy 223.196658 -280.04389) (xy 223.196658 -281.93619) (xy 225.203258 -281.93619) (xy 225.203258 -280.044144)
				(xy 225.203004 -280.04389)
			)
		)
	)
	(zone
		(layers "In1.Cu" "In2.Cu")
		(hatch none 0.5)
		(connect_pads
			(clearance 0)
		)
		(min_thickness 0.25)
		(keepout
			(tracks not_allowed)
			(vias allowed)
			(pads allowed)
			(copperpour not_allowed)
			(footprints allowed)
		)
		(placement
			(enabled no)
			(sheetname "")
		)
		(fill yes
			(thermal_gap 0.5)
			(thermal_bridge_width 0.5)
			(island_removal_mode 0)
		)
		(polygon
			(pts
				(xy 38.196774 -275.243798) (xy 38.196774 -277.136098) (xy 40.203374 -277.136098) (xy 40.203374 -275.244052)
				(xy 40.20312 -275.243798)
			)
		)
	)
	(zone
		(layers "In1.Cu" "In2.Cu")
		(hatch none 0.5)
		(connect_pads
			(clearance 0)
		)
		(min_thickness 0.25)
		(keepout
			(tracks not_allowed)
			(vias allowed)
			(pads allowed)
			(copperpour not_allowed)
			(footprints allowed)
		)
		(placement
			(enabled no)
			(sheetname "")
		)
		(fill yes
			(thermal_gap 0.5)
			(thermal_bridge_width 0.5)
			(island_removal_mode 0)
		)
		(polygon
			(pts
				(xy 226.386644 -163.04387) (xy 226.386644 -164.93617) (xy 228.393244 -164.93617) (xy 228.393244 -163.044124)
				(xy 228.39299 -163.04387)
			)
		)
	)
	(zone
		(layers "In1.Cu" "In2.Cu")
		(hatch none 0.5)
		(connect_pads
			(clearance 0)
		)
		(min_thickness 0.25)
		(keepout
			(tracks not_allowed)
			(vias allowed)
			(pads allowed)
			(copperpour not_allowed)
			(footprints allowed)
		)
		(placement
			(enabled no)
			(sheetname "")
		)
		(fill yes
			(thermal_gap 0.5)
			(thermal_bridge_width 0.5)
			(island_removal_mode 0)
		)
		(polygon
			(pts
				(xy 226.386644 -472.044014) (xy 226.386644 -473.936314) (xy 228.393244 -473.936314) (xy 228.393244 -472.044268)
				(xy 228.39299 -472.044014)
			)
		)
	)
	(zone
		(layers "In1.Cu" "In2.Cu")
		(hatch none 0.5)
		(connect_pads
			(clearance 0)
		)
		(min_thickness 0.25)
		(keepout
			(tracks not_allowed)
			(vias allowed)
			(pads allowed)
			(copperpour not_allowed)
			(footprints allowed)
		)
		(placement
			(enabled no)
			(sheetname "")
		)
		(fill yes
			(thermal_gap 0.5)
			(thermal_bridge_width 0.5)
			(island_removal_mode 0)
		)
		(polygon
			(pts
				(xy 223.196658 -488.444032) (xy 223.196658 -490.336332) (xy 225.203258 -490.336332) (xy 225.203258 -488.444286)
				(xy 225.203004 -488.444032)
			)
		)
	)
	(zone
		(layers "In1.Cu" "In2.Cu")
		(hatch none 0.5)
		(connect_pads
			(clearance 0)
		)
		(min_thickness 0.25)
		(keepout
			(tracks not_allowed)
			(vias allowed)
			(pads allowed)
			(copperpour not_allowed)
			(footprints allowed)
		)
		(placement
			(enabled no)
			(sheetname "")
		)
		(fill yes
			(thermal_gap 0.5)
			(thermal_bridge_width 0.5)
			(island_removal_mode 0)
		)
		(polygon
			(pts
				(xy 23.803356 -331.356208) (xy 23.803356 -329.463908) (xy 21.796756 -329.463908) (xy 21.796756 -331.355954)
				(xy 21.79701 -331.356208)
			)
		)
	)
	(zone
		(layers "In1.Cu" "In2.Cu")
		(hatch none 0.5)
		(connect_pads
			(clearance 0)
		)
		(min_thickness 0.25)
		(keepout
			(tracks not_allowed)
			(vias allowed)
			(pads allowed)
			(copperpour not_allowed)
			(footprints allowed)
		)
		(placement
			(enabled no)
			(sheetname "")
		)
		(fill yes
			(thermal_gap 0.5)
			(thermal_bridge_width 0.5)
			(island_removal_mode 0)
		)
		(polygon
			(pts
				(xy 23.803356 -130.15595) (xy 23.803356 -128.263904) (xy 21.796756 -128.263904) (xy 21.796756 -130.155696)
				(xy 21.79701 -130.15595)
			)
		)
	)
	(zone
		(layers "In1.Cu" "In2.Cu")
		(hatch none 0.5)
		(connect_pads
			(clearance 0)
		)
		(min_thickness 0.25)
		(keepout
			(tracks not_allowed)
			(vias allowed)
			(pads allowed)
			(copperpour not_allowed)
			(footprints allowed)
		)
		(placement
			(enabled no)
			(sheetname "")
		)
		(fill yes
			(thermal_gap 0.5)
			(thermal_bridge_width 0.5)
			(island_removal_mode 0)
		)
		(polygon
			(pts
				(xy 38.196774 -383.043938) (xy 38.196774 -384.936238) (xy 40.203374 -384.936238) (xy 40.203374 -383.044192)
				(xy 40.20312 -383.043938)
			)
		)
	)
	(zone
		(layers "In1.Cu" "In2.Cu")
		(hatch none 0.5)
		(connect_pads
			(clearance 0)
		)
		(min_thickness 0.25)
		(keepout
			(tracks not_allowed)
			(vias allowed)
			(pads allowed)
			(copperpour not_allowed)
			(footprints allowed)
		)
		(placement
			(enabled no)
			(sheetname "")
		)
		(fill yes
			(thermal_gap 0.5)
			(thermal_bridge_width 0.5)
			(island_removal_mode 0)
		)
		(polygon
			(pts
				(xy 20.61337 -342.956134) (xy 20.61337 -341.063834) (xy 18.60677 -341.063834) (xy 18.60677 -342.95588)
				(xy 18.607024 -342.956134)
			)
		)
	)
	(zone
		(layers "In1.Cu" "In2.Cu")
		(hatch none 0.5)
		(connect_pads
			(clearance 0)
		)
		(min_thickness 0.25)
		(keepout
			(tracks not_allowed)
			(vias allowed)
			(pads allowed)
			(copperpour not_allowed)
			(footprints allowed)
		)
		(placement
			(enabled no)
			(sheetname "")
		)
		(fill yes
			(thermal_gap 0.5)
			(thermal_bridge_width 0.5)
			(island_removal_mode 0)
		)
		(polygon
			(pts
				(xy 41.38676 -163.04387) (xy 41.38676 -164.93617) (xy 43.39336 -164.93617) (xy 43.39336 -163.044124)
				(xy 43.393106 -163.04387)
			)
		)
	)
	(zone
		(layers "In1.Cu" "In2.Cu")
		(hatch none 0.5)
		(connect_pads
			(clearance 0)
		)
		(min_thickness 0.25)
		(keepout
			(tracks not_allowed)
			(vias allowed)
			(pads allowed)
			(copperpour not_allowed)
			(footprints allowed)
		)
		(placement
			(enabled no)
			(sheetname "")
		)
		(fill yes
			(thermal_gap 0.5)
			(thermal_bridge_width 0.5)
			(island_removal_mode 0)
		)
		(polygon
			(pts
				(xy 20.61337 -239.956086) (xy 20.61337 -238.063786) (xy 18.60677 -238.063786) (xy 18.60677 -239.955832)
				(xy 18.607024 -239.956086)
			)
		)
	)
	(zone
		(layers "In1.Cu" "In2.Cu")
		(hatch none 0.5)
		(connect_pads
			(clearance 0)
		)
		(min_thickness 0.25)
		(keepout
			(tracks not_allowed)
			(vias allowed)
			(pads allowed)
			(copperpour not_allowed)
			(footprints allowed)
		)
		(placement
			(enabled no)
			(sheetname "")
		)
		(fill yes
			(thermal_gap 0.5)
			(thermal_bridge_width 0.5)
			(island_removal_mode 0)
		)
		(polygon
			(pts
				(xy 23.803356 -230.756206) (xy 23.803356 -228.863906) (xy 21.796756 -228.863906) (xy 21.796756 -230.755952)
				(xy 21.79701 -230.756206)
			)
		)
	)
	(zone
		(layers "In1.Cu" "In2.Cu")
		(hatch none 0.5)
		(connect_pads
			(clearance 0)
		)
		(min_thickness 0.25)
		(keepout
			(tracks not_allowed)
			(vias allowed)
			(pads allowed)
			(copperpour not_allowed)
			(footprints allowed)
		)
		(placement
			(enabled no)
			(sheetname "")
		)
		(fill yes
			(thermal_gap 0.5)
			(thermal_bridge_width 0.5)
			(island_removal_mode 0)
		)
		(polygon
			(pts
				(xy 41.38676 -472.044014) (xy 41.38676 -473.936314) (xy 43.39336 -473.936314) (xy 43.39336 -472.044268)
				(xy 43.393106 -472.044014)
			)
		)
	)
	(zone
		(layers "In1.Cu" "In2.Cu")
		(hatch none 0.5)
		(connect_pads
			(clearance 0)
		)
		(min_thickness 0.25)
		(keepout
			(tracks not_allowed)
			(vias allowed)
			(pads allowed)
			(copperpour not_allowed)
			(footprints allowed)
		)
		(placement
			(enabled no)
			(sheetname "")
		)
		(fill yes
			(thermal_gap 0.5)
			(thermal_bridge_width 0.5)
			(island_removal_mode 0)
		)
		(polygon
			(pts
				(xy 38.196774 -74.043794) (xy 38.196774 -75.936094) (xy 40.203374 -75.936094) (xy 40.203374 -74.044048)
				(xy 40.20312 -74.043794)
			)
		)
	)
	(zone
		(layers "In1.Cu" "In2.Cu")
		(hatch none 0.5)
		(connect_pads
			(clearance 0)
		)
		(min_thickness 0.25)
		(keepout
			(tracks not_allowed)
			(vias allowed)
			(pads allowed)
			(copperpour not_allowed)
			(footprints allowed)
		)
		(placement
			(enabled no)
			(sheetname "")
		)
		(fill yes
			(thermal_gap 0.5)
			(thermal_bridge_width 0.5)
			(island_removal_mode 0)
		)
		(polygon
			(pts
				(xy 228.393244 -61.936122) (xy 228.393244 -60.043822) (xy 226.386644 -60.043822) (xy 226.386644 -61.935868)
				(xy 226.386898 -61.936122)
			)
		)
	)
	(zone
		(layers "In1.Cu" "In2.Cu")
		(hatch none 0.5)
		(connect_pads
			(clearance 0)
		)
		(min_thickness 0.25)
		(keepout
			(tracks not_allowed)
			(vias allowed)
			(pads allowed)
			(copperpour not_allowed)
			(footprints allowed)
		)
		(placement
			(enabled no)
			(sheetname "")
		)
		(fill yes
			(thermal_gap 0.5)
			(thermal_bridge_width 0.5)
			(island_removal_mode 0)
		)
		(polygon
			(pts
				(xy 223.196658 -172.24375) (xy 223.196658 -174.13605) (xy 225.203258 -174.13605) (xy 225.203258 -172.244004)
				(xy 225.203004 -172.24375)
			)
		)
	)
	(zone
		(layers "In1.Cu" "In2.Cu")
		(hatch none 0.5)
		(connect_pads
			(clearance 0)
		)
		(min_thickness 0.25)
		(keepout
			(tracks not_allowed)
			(vias allowed)
			(pads allowed)
			(copperpour not_allowed)
			(footprints allowed)
		)
		(placement
			(enabled no)
			(sheetname "")
		)
		(fill yes
			(thermal_gap 0.5)
			(thermal_bridge_width 0.5)
			(island_removal_mode 0)
		)
		(polygon
			(pts
				(xy 23.803356 -436.756302) (xy 23.803356 -434.864002) (xy 21.796756 -434.864002) (xy 21.796756 -436.756048)
				(xy 21.79701 -436.756302)
			)
		)
	)
	(zone
		(layers "In1.Cu" "In2.Cu")
		(hatch none 0.5)
		(connect_pads
			(clearance 0)
		)
		(min_thickness 0.25)
		(keepout
			(tracks not_allowed)
			(vias allowed)
			(pads allowed)
			(copperpour not_allowed)
			(footprints allowed)
		)
		(placement
			(enabled no)
			(sheetname "")
		)
		(fill yes
			(thermal_gap 0.5)
			(thermal_bridge_width 0.5)
			(island_removal_mode 0)
		)
		(polygon
			(pts
				(xy 23.803356 -140.55598) (xy 23.803356 -138.66368) (xy 21.796756 -138.66368) (xy 21.796756 -140.555726)
				(xy 21.79701 -140.55598)
			)
		)
	)
	(zone
		(layers "In1.Cu" "In2.Cu")
		(hatch none 0.5)
		(connect_pads
			(clearance 0)
		)
		(min_thickness 0.25)
		(keepout
			(tracks not_allowed)
			(vias allowed)
			(pads allowed)
			(copperpour not_allowed)
			(footprints allowed)
		)
		(placement
			(enabled no)
			(sheetname "")
		)
		(fill yes
			(thermal_gap 0.5)
			(thermal_bridge_width 0.5)
			(island_removal_mode 0)
		)
		(polygon
			(pts
				(xy 23.803356 -427.156118) (xy 23.803356 -425.263818) (xy 21.796756 -425.263818) (xy 21.796756 -427.155864)
				(xy 21.79701 -427.156118)
			)
		)
	)
	(zone
		(layers "In1.Cu" "In2.Cu")
		(hatch none 0.5)
		(connect_pads
			(clearance 0)
		)
		(min_thickness 0.25)
		(keepout
			(tracks not_allowed)
			(vias allowed)
			(pads allowed)
			(copperpour not_allowed)
			(footprints allowed)
		)
		(placement
			(enabled no)
			(sheetname "")
		)
		(fill yes
			(thermal_gap 0.5)
			(thermal_bridge_width 0.5)
			(island_removal_mode 0)
		)
		(polygon
			(pts
				(xy 38.196774 -385.443984) (xy 38.196774 -387.336284) (xy 40.203374 -387.336284) (xy 40.203374 -385.444238)
				(xy 40.20312 -385.443984)
			)
		)
	)
	(zone
		(layers "In1.Cu" "In2.Cu")
		(hatch none 0.5)
		(connect_pads
			(clearance 0)
		)
		(min_thickness 0.25)
		(keepout
			(tracks not_allowed)
			(vias allowed)
			(pads allowed)
			(copperpour not_allowed)
			(footprints allowed)
		)
		(placement
			(enabled no)
			(sheetname "")
		)
		(fill yes
			(thermal_gap 0.5)
			(thermal_bridge_width 0.5)
			(island_removal_mode 0)
		)
		(polygon
			(pts
				(xy 223.196658 -69.243702) (xy 223.196658 -71.136002) (xy 225.203258 -71.136002) (xy 225.203258 -69.243956)
				(xy 225.203004 -69.243702)
			)
		)
	)
	(zone
		(layers "In1.Cu" "In2.Cu")
		(hatch none 0.5)
		(connect_pads
			(clearance 0)
		)
		(min_thickness 0.25)
		(keepout
			(tracks not_allowed)
			(vias allowed)
			(pads allowed)
			(copperpour not_allowed)
			(footprints allowed)
		)
		(placement
			(enabled no)
			(sheetname "")
		)
		(fill yes
			(thermal_gap 0.5)
			(thermal_bridge_width 0.5)
			(island_removal_mode 0)
		)
		(polygon
			(pts
				(xy 38.196774 -69.243702) (xy 38.196774 -71.136002) (xy 40.203374 -71.136002) (xy 40.203374 -69.243956)
				(xy 40.20312 -69.243702)
			)
		)
	)
	(zone
		(layers "In1.Cu" "In2.Cu")
		(hatch none 0.5)
		(connect_pads
			(clearance 0)
		)
		(min_thickness 0.25)
		(keepout
			(tracks not_allowed)
			(vias allowed)
			(pads allowed)
			(copperpour not_allowed)
			(footprints allowed)
		)
		(placement
			(enabled no)
			(sheetname "")
		)
		(fill yes
			(thermal_gap 0.5)
			(thermal_bridge_width 0.5)
			(island_removal_mode 0)
		)
		(polygon
			(pts
				(xy 38.196774 -282.443936) (xy 38.196774 -284.336236) (xy 40.203374 -284.336236) (xy 40.203374 -282.44419)
				(xy 40.20312 -282.443936)
			)
		)
	)
	(zone
		(layers "In1.Cu" "In2.Cu")
		(hatch none 0.5)
		(connect_pads
			(clearance 0)
		)
		(min_thickness 0.25)
		(keepout
			(tracks not_allowed)
			(vias allowed)
			(pads allowed)
			(copperpour not_allowed)
			(footprints allowed)
		)
		(placement
			(enabled no)
			(sheetname "")
		)
		(fill yes
			(thermal_gap 0.5)
			(thermal_bridge_width 0.5)
			(island_removal_mode 0)
		)
		(polygon
			(pts
				(xy 41.38676 -369.043966) (xy 41.38676 -370.936266) (xy 43.39336 -370.936266) (xy 43.39336 -369.04422)
				(xy 43.393106 -369.043966)
			)
		)
	)
	(zone
		(layers "In1.Cu" "In2.Cu")
		(hatch none 0.5)
		(connect_pads
			(clearance 0)
		)
		(min_thickness 0.25)
		(keepout
			(tracks not_allowed)
			(vias allowed)
			(pads allowed)
			(copperpour not_allowed)
			(footprints allowed)
		)
		(placement
			(enabled no)
			(sheetname "")
		)
		(fill yes
			(thermal_gap 0.5)
			(thermal_bridge_width 0.5)
			(island_removal_mode 0)
		)
		(polygon
			(pts
				(xy 23.803356 -118.155974) (xy 23.803356 -116.263928) (xy 21.796756 -116.263928) (xy 21.796756 -118.15572)
				(xy 21.79701 -118.155974)
			)
		)
	)
	(zone
		(layers "In1.Cu" "In2.Cu")
		(hatch none 0.5)
		(connect_pads
			(clearance 0)
		)
		(min_thickness 0.25)
		(keepout
			(tracks not_allowed)
			(vias allowed)
			(pads allowed)
			(copperpour not_allowed)
			(footprints allowed)
		)
		(placement
			(enabled no)
			(sheetname "")
		)
		(fill yes
			(thermal_gap 0.5)
			(thermal_bridge_width 0.5)
			(island_removal_mode 0)
		)
		(polygon
			(pts
				(xy 223.196658 -380.643892) (xy 223.196658 -382.536192) (xy 225.203258 -382.536192) (xy 225.203258 -380.644146)
				(xy 225.203004 -380.643892)
			)
		)
	)
	(zone
		(layers "In1.Cu" "In2.Cu")
		(hatch none 0.5)
		(connect_pads
			(clearance 0)
		)
		(min_thickness 0.25)
		(keepout
			(tracks not_allowed)
			(vias allowed)
			(pads allowed)
			(copperpour not_allowed)
			(footprints allowed)
		)
		(placement
			(enabled no)
			(sheetname "")
		)
		(fill yes
			(thermal_gap 0.5)
			(thermal_bridge_width 0.5)
			(island_removal_mode 0)
		)
		(polygon
			(pts
				(xy 223.196658 -385.443984) (xy 223.196658 -387.336284) (xy 225.203258 -387.336284) (xy 225.203258 -385.444238)
				(xy 225.203004 -385.443984)
			)
		)
	)
	(zone
		(layers "In1.Cu" "In2.Cu")
		(hatch none 0.5)
		(connect_pads
			(clearance 0)
		)
		(min_thickness 0.25)
		(keepout
			(tracks not_allowed)
			(vias allowed)
			(pads allowed)
			(copperpour not_allowed)
			(footprints allowed)
		)
		(placement
			(enabled no)
			(sheetname "")
		)
		(fill yes
			(thermal_gap 0.5)
			(thermal_bridge_width 0.5)
			(island_removal_mode 0)
		)
		(polygon
			(pts
				(xy 38.196774 -490.844078) (xy 38.196774 -492.736124) (xy 40.203374 -492.736124) (xy 40.203374 -490.844332)
				(xy 40.20312 -490.844078)
			)
		)
	)
	(zone
		(layers "In1.Cu" "In2.Cu")
		(hatch none 0.5)
		(connect_pads
			(clearance 0)
		)
		(min_thickness 0.25)
		(keepout
			(tracks not_allowed)
			(vias allowed)
			(pads allowed)
			(copperpour not_allowed)
			(footprints allowed)
		)
		(placement
			(enabled no)
			(sheetname "")
		)
		(fill yes
			(thermal_gap 0.5)
			(thermal_bridge_width 0.5)
			(island_removal_mode 0)
		)
		(polygon
			(pts
				(xy 23.803356 -346.556076) (xy 23.803356 -344.663776) (xy 21.796756 -344.663776) (xy 21.796756 -346.555822)
				(xy 21.79701 -346.556076)
			)
		)
	)
	(zone
		(layers "In1.Cu" "In2.Cu")
		(hatch none 0.5)
		(connect_pads
			(clearance 0)
		)
		(min_thickness 0.25)
		(keepout
			(tracks not_allowed)
			(vias allowed)
			(pads allowed)
			(copperpour not_allowed)
			(footprints allowed)
		)
		(placement
			(enabled no)
			(sheetname "")
		)
		(fill yes
			(thermal_gap 0.5)
			(thermal_bridge_width 0.5)
			(island_removal_mode 0)
		)
		(polygon
			(pts
				(xy 89.88933 -215.82761) (xy 91.076526 -215.82761) (xy 91.076526 -214.65921) (xy 89.88933 -214.65921)
			)
		)
	)
	(zone
		(layers "In1.Cu" "In2.Cu")
		(hatch none 0.5)
		(connect_pads
			(clearance 0)
		)
		(min_thickness 0.25)
		(keepout
			(tracks not_allowed)
			(vias allowed)
			(pads allowed)
			(copperpour not_allowed)
			(footprints allowed)
		)
		(placement
			(enabled no)
			(sheetname "")
		)
		(fill yes
			(thermal_gap 0.5)
			(thermal_bridge_width 0.5)
			(island_removal_mode 0)
		)
		(polygon
			(pts
				(xy 226.386644 -266.043918) (xy 226.386644 -267.936218) (xy 228.393244 -267.936218) (xy 228.393244 -266.044172)
				(xy 228.39299 -266.043918)
			)
		)
	)
	(zone
		(layers "In1.Cu" "In2.Cu")
		(hatch none 0.5)
		(connect_pads
			(clearance 0)
		)
		(min_thickness 0.25)
		(keepout
			(tracks not_allowed)
			(vias allowed)
			(pads allowed)
			(copperpour not_allowed)
			(footprints allowed)
		)
		(placement
			(enabled no)
			(sheetname "")
		)
		(fill yes
			(thermal_gap 0.5)
			(thermal_bridge_width 0.5)
			(island_removal_mode 0)
		)
		(polygon
			(pts
				(xy 223.196658 -468.444072) (xy 223.196658 -470.336118) (xy 225.203258 -470.336118) (xy 225.203258 -468.444326)
				(xy 225.203004 -468.444072)
			)
		)
	)
	(zone
		(layers "In1.Cu" "In2.Cu")
		(hatch none 0.5)
		(connect_pads
			(clearance 0)
		)
		(min_thickness 0.25)
		(keepout
			(tracks not_allowed)
			(vias allowed)
			(pads allowed)
			(copperpour not_allowed)
			(footprints allowed)
		)
		(placement
			(enabled no)
			(sheetname "")
		)
		(fill yes
			(thermal_gap 0.5)
			(thermal_bridge_width 0.5)
			(island_removal_mode 0)
		)
		(polygon
			(pts
				(xy 23.803356 -22.356064) (xy 23.803356 -20.463764) (xy 21.796756 -20.463764) (xy 21.796756 -22.35581)
				(xy 21.79701 -22.356064)
			)
		)
	)
	(zone
		(layers "In1.Cu" "In2.Cu")
		(hatch none 0.5)
		(connect_pads
			(clearance 0)
		)
		(min_thickness 0.25)
		(keepout
			(tracks not_allowed)
			(vias allowed)
			(pads allowed)
			(copperpour not_allowed)
			(footprints allowed)
		)
		(placement
			(enabled no)
			(sheetname "")
		)
		(fill yes
			(thermal_gap 0.5)
			(thermal_bridge_width 0.5)
			(island_removal_mode 0)
		)
		(polygon
			(pts
				(xy 41.38676 -266.043918) (xy 41.38676 -267.936218) (xy 43.39336 -267.936218) (xy 43.39336 -266.044172)
				(xy 43.393106 -266.043918)
			)
		)
	)
	(zone
		(layers "In1.Cu" "In2.Cu")
		(hatch none 0.5)
		(connect_pads
			(clearance 0)
		)
		(min_thickness 0.25)
		(keepout
			(tracks not_allowed)
			(vias allowed)
			(pads allowed)
			(copperpour not_allowed)
			(footprints allowed)
		)
		(placement
			(enabled no)
			(sheetname "")
		)
		(fill yes
			(thermal_gap 0.5)
			(thermal_bridge_width 0.5)
			(island_removal_mode 0)
		)
		(polygon
			(pts
				(xy 38.196774 -157.043882) (xy 38.196774 -158.936182) (xy 40.203374 -158.936182) (xy 40.203374 -157.044136)
				(xy 40.20312 -157.043882)
			)
		)
	)
	(zone
		(layers "In1.Cu" "In2.Cu")
		(hatch none 0.5)
		(connect_pads
			(clearance 0)
		)
		(min_thickness 0.25)
		(keepout
			(tracks not_allowed)
			(vias allowed)
			(pads allowed)
			(copperpour not_allowed)
			(footprints allowed)
		)
		(placement
			(enabled no)
			(sheetname "")
		)
		(fill yes
			(thermal_gap 0.5)
			(thermal_bridge_width 0.5)
			(island_removal_mode 0)
		)
		(polygon
			(pts
				(xy 23.803356 -324.15607) (xy 23.803356 -322.264024) (xy 21.796756 -322.264024) (xy 21.796756 -324.155816)
				(xy 21.79701 -324.15607)
			)
		)
	)
	(zone
		(layers "In1.Cu" "In2.Cu")
		(hatch none 0.5)
		(connect_pads
			(clearance 0)
		)
		(min_thickness 0.25)
		(keepout
			(tracks not_allowed)
			(vias allowed)
			(pads allowed)
			(copperpour not_allowed)
			(footprints allowed)
		)
		(placement
			(enabled no)
			(sheetname "")
		)
		(fill yes
			(thermal_gap 0.5)
			(thermal_bridge_width 0.5)
			(island_removal_mode 0)
		)
		(polygon
			(pts
				(xy 38.196774 -463.64398) (xy 38.196774 -465.53628) (xy 40.203374 -465.53628) (xy 40.203374 -463.644234)
				(xy 40.20312 -463.64398)
			)
		)
	)
	(zone
		(layers "In1.Cu" "In2.Cu")
		(hatch none 0.5)
		(connect_pads
			(clearance 0)
		)
		(min_thickness 0.25)
		(keepout
			(tracks not_allowed)
			(vias allowed)
			(pads allowed)
			(copperpour not_allowed)
			(footprints allowed)
		)
		(placement
			(enabled no)
			(sheetname "")
		)
		(fill yes
			(thermal_gap 0.5)
			(thermal_bridge_width 0.5)
			(island_removal_mode 0)
		)
		(polygon
			(pts
				(xy 38.196774 -478.844102) (xy 38.196774 -480.736148) (xy 40.203374 -480.736148) (xy 40.203374 -478.844356)
				(xy 40.20312 -478.844102)
			)
		)
	)
	(zone
		(layers "In1.Cu" "In2.Cu")
		(hatch none 0.5)
		(connect_pads
			(clearance 0)
		)
		(min_thickness 0.25)
		(keepout
			(tracks not_allowed)
			(vias allowed)
			(pads allowed)
			(copperpour not_allowed)
			(footprints allowed)
		)
		(placement
			(enabled no)
			(sheetname "")
		)
		(fill yes
			(thermal_gap 0.5)
			(thermal_bridge_width 0.5)
			(island_removal_mode 0)
		)
		(polygon
			(pts
				(xy 38.196774 -181.843934) (xy 38.196774 -183.73598) (xy 40.203374 -183.73598) (xy 40.203374 -181.844188)
				(xy 40.20312 -181.843934)
			)
		)
	)
	(zone
		(layers "In1.Cu" "In2.Cu")
		(hatch none 0.5)
		(connect_pads
			(clearance 0)
		)
		(min_thickness 0.25)
		(keepout
			(tracks not_allowed)
			(vias allowed)
			(pads allowed)
			(copperpour not_allowed)
			(footprints allowed)
		)
		(placement
			(enabled no)
			(sheetname "")
		)
		(fill yes
			(thermal_gap 0.5)
			(thermal_bridge_width 0.5)
			(island_removal_mode 0)
		)
		(polygon
			(pts
				(xy 38.196774 -272.844006) (xy 38.196774 -274.736052) (xy 40.203374 -274.736052) (xy 40.203374 -272.84426)
				(xy 40.20312 -272.844006)
			)
		)
	)
	(zone
		(layers "In1.Cu" "In2.Cu")
		(hatch none 0.5)
		(connect_pads
			(clearance 0)
		)
		(min_thickness 0.25)
		(keepout
			(tracks not_allowed)
			(vias allowed)
			(pads allowed)
			(copperpour not_allowed)
			(footprints allowed)
		)
		(placement
			(enabled no)
			(sheetname "")
		)
		(fill yes
			(thermal_gap 0.5)
			(thermal_bridge_width 0.5)
			(island_removal_mode 0)
		)
		(polygon
			(pts
				(xy 223.196658 -157.043882) (xy 223.196658 -158.936182) (xy 225.203258 -158.936182) (xy 225.203258 -157.044136)
				(xy 225.203004 -157.043882)
			)
		)
	)
	(zone
		(layers "In1.Cu" "In2.Cu")
		(hatch none 0.5)
		(connect_pads
			(clearance 0)
		)
		(min_thickness 0.25)
		(keepout
			(tracks not_allowed)
			(vias allowed)
			(pads allowed)
			(copperpour not_allowed)
			(footprints allowed)
		)
		(placement
			(enabled no)
			(sheetname "")
		)
		(fill yes
			(thermal_gap 0.5)
			(thermal_bridge_width 0.5)
			(island_removal_mode 0)
		)
		(polygon
			(pts
				(xy 40.203374 -264.336022) (xy 40.203374 -262.443976) (xy 38.196774 -262.443976) (xy 38.196774 -264.335768)
				(xy 38.197028 -264.336022)
			)
		)
	)
	(zone
		(layers "In1.Cu" "In2.Cu")
		(hatch none 0.5)
		(connect_pads
			(clearance 0)
		)
		(min_thickness 0.25)
		(keepout
			(tracks not_allowed)
			(vias allowed)
			(pads allowed)
			(copperpour not_allowed)
			(footprints allowed)
		)
		(placement
			(enabled no)
			(sheetname "")
		)
		(fill yes
			(thermal_gap 0.5)
			(thermal_bridge_width 0.5)
			(island_removal_mode 0)
		)
		(polygon
			(pts
				(xy 223.196658 -257.643884) (xy 223.196658 -259.536184) (xy 225.203258 -259.536184) (xy 225.203258 -257.644138)
				(xy 225.203004 -257.643884)
			)
		)
	)
	(zone
		(layers "In1.Cu" "In2.Cu")
		(hatch none 0.5)
		(connect_pads
			(clearance 0)
		)
		(min_thickness 0.25)
		(keepout
			(tracks not_allowed)
			(vias allowed)
			(pads allowed)
			(copperpour not_allowed)
			(footprints allowed)
		)
		(placement
			(enabled no)
			(sheetname "")
		)
		(fill yes
			(thermal_gap 0.5)
			(thermal_bridge_width 0.5)
			(island_removal_mode 0)
		)
		(polygon
			(pts
				(xy 41.38676 -60.043822) (xy 41.38676 -61.936122) (xy 43.39336 -61.936122) (xy 43.39336 -60.044076)
				(xy 43.393106 -60.043822)
			)
		)
	)
	(zone
		(layers "In1.Cu" "In2.Cu")
		(hatch none 0.5)
		(connect_pads
			(clearance 0)
		)
		(min_thickness 0.25)
		(keepout
			(tracks not_allowed)
			(vias allowed)
			(pads allowed)
			(copperpour not_allowed)
			(footprints allowed)
		)
		(placement
			(enabled no)
			(sheetname "")
		)
		(fill yes
			(thermal_gap 0.5)
			(thermal_bridge_width 0.5)
			(island_removal_mode 0)
		)
		(polygon
			(pts
				(xy 23.803356 -39.955978) (xy 23.803356 -38.063678) (xy 21.796756 -38.063678) (xy 21.796756 -39.955724)
				(xy 21.79701 -39.955978)
			)
		)
	)
	(zone
		(layers "In1.Cu" "In2.Cu")
		(hatch none 0.5)
		(connect_pads
			(clearance 0)
		)
		(min_thickness 0.25)
		(keepout
			(tracks not_allowed)
			(vias allowed)
			(pads allowed)
			(copperpour not_allowed)
			(footprints allowed)
		)
		(placement
			(enabled no)
			(sheetname "")
		)
		(fill yes
			(thermal_gap 0.5)
			(thermal_bridge_width 0.5)
			(island_removal_mode 0)
		)
		(polygon
			(pts
				(xy 89.88679 -106.60761) (xy 91.077288 -106.60761) (xy 91.077288 -105.43921) (xy 89.88679 -105.43921)
			)
		)
	)
	(zone
		(layers "In1.Cu" "In2.Cu")
		(hatch none 0.5)
		(connect_pads
			(clearance 0)
		)
		(min_thickness 0.25)
		(keepout
			(tracks not_allowed)
			(vias allowed)
			(pads allowed)
			(copperpour not_allowed)
			(footprints allowed)
		)
		(placement
			(enabled no)
			(sheetname "")
		)
		(fill yes
			(thermal_gap 0.5)
			(thermal_bridge_width 0.5)
			(island_removal_mode 0)
		)
		(polygon
			(pts
				(xy 38.196774 -488.444032) (xy 38.196774 -490.336332) (xy 40.203374 -490.336332) (xy 40.203374 -488.444286)
				(xy 40.20312 -488.444032)
			)
		)
	)
	(zone
		(layers "In1.Cu" "In2.Cu")
		(hatch none 0.5)
		(connect_pads
			(clearance 0)
		)
		(min_thickness 0.25)
		(keepout
			(tracks not_allowed)
			(vias allowed)
			(pads allowed)
			(copperpour not_allowed)
			(footprints allowed)
		)
		(placement
			(enabled no)
			(sheetname "")
		)
		(fill yes
			(thermal_gap 0.5)
			(thermal_bridge_width 0.5)
			(island_removal_mode 0)
		)
		(polygon
			(pts
				(xy 38.196774 -277.643844) (xy 38.196774 -279.536144) (xy 40.203374 -279.536144) (xy 40.203374 -277.644098)
				(xy 40.20312 -277.643844)
			)
		)
	)
	(zone
		(layers "In1.Cu" "In2.Cu")
		(hatch none 0.5)
		(connect_pads
			(clearance 0)
		)
		(min_thickness 0.25)
		(keepout
			(tracks not_allowed)
			(vias allowed)
			(pads allowed)
			(copperpour not_allowed)
			(footprints allowed)
		)
		(placement
			(enabled no)
			(sheetname "")
		)
		(fill yes
			(thermal_gap 0.5)
			(thermal_bridge_width 0.5)
			(island_removal_mode 0)
		)
		(polygon
			(pts
				(xy 223.196658 -154.643836) (xy 223.196658 -156.536136) (xy 225.203258 -156.536136) (xy 225.203258 -154.64409)
				(xy 225.203004 -154.643836)
			)
		)
	)
	(zone
		(layers "In1.Cu" "In2.Cu")
		(hatch none 0.5)
		(connect_pads
			(clearance 0)
		)
		(min_thickness 0.25)
		(keepout
			(tracks not_allowed)
			(vias allowed)
			(pads allowed)
			(copperpour not_allowed)
			(footprints allowed)
		)
		(placement
			(enabled no)
			(sheetname "")
		)
		(fill yes
			(thermal_gap 0.5)
			(thermal_bridge_width 0.5)
			(island_removal_mode 0)
		)
		(polygon
			(pts
				(xy 223.196658 -383.043938) (xy 223.196658 -384.936238) (xy 225.203258 -384.936238) (xy 225.203258 -383.044192)
				(xy 225.203004 -383.043938)
			)
		)
	)
	(zone
		(layers "In1.Cu" "In2.Cu")
		(hatch none 0.5)
		(connect_pads
			(clearance 0)
		)
		(min_thickness 0.25)
		(keepout
			(tracks not_allowed)
			(vias allowed)
			(pads allowed)
			(copperpour not_allowed)
			(footprints allowed)
		)
		(placement
			(enabled no)
			(sheetname "")
		)
		(fill yes
			(thermal_gap 0.5)
			(thermal_bridge_width 0.5)
			(island_removal_mode 0)
		)
		(polygon
			(pts
				(xy 38.196774 -466.044026) (xy 38.196774 -467.936326) (xy 40.203374 -467.936326) (xy 40.203374 -466.04428)
				(xy 40.20312 -466.044026)
			)
		)
	)
	(zone
		(layers "In1.Cu" "In2.Cu")
		(hatch none 0.5)
		(connect_pads
			(clearance 0)
		)
		(min_thickness 0.25)
		(keepout
			(tracks not_allowed)
			(vias allowed)
			(pads allowed)
			(copperpour not_allowed)
			(footprints allowed)
		)
		(placement
			(enabled no)
			(sheetname "")
		)
		(fill yes
			(thermal_gap 0.5)
			(thermal_bridge_width 0.5)
			(island_removal_mode 0)
		)
		(polygon
			(pts
				(xy 223.196658 -56.44388) (xy 223.196658 -58.335926) (xy 225.203258 -58.335926) (xy 225.203258 -56.444134)
				(xy 225.203004 -56.44388)
			)
		)
	)
	(zone
		(layers "In1.Cu" "In2.Cu")
		(hatch none 0.5)
		(connect_pads
			(clearance 0)
		)
		(min_thickness 0.25)
		(keepout
			(tracks not_allowed)
			(vias allowed)
			(pads allowed)
			(copperpour not_allowed)
			(footprints allowed)
		)
		(placement
			(enabled no)
			(sheetname "")
		)
		(fill yes
			(thermal_gap 0.5)
			(thermal_bridge_width 0.5)
			(island_removal_mode 0)
		)
		(polygon
			(pts
				(xy 223.196658 -275.243798) (xy 223.196658 -277.136098) (xy 225.203258 -277.136098) (xy 225.203258 -275.244052)
				(xy 225.203004 -275.243798)
			)
		)
	)
	(zone
		(layers "In1.Cu" "In2.Cu")
		(hatch none 0.5)
		(connect_pads
			(clearance 0)
		)
		(min_thickness 0.25)
		(keepout
			(tracks not_allowed)
			(vias allowed)
			(pads allowed)
			(copperpour not_allowed)
			(footprints allowed)
		)
		(placement
			(enabled no)
			(sheetname "")
		)
		(fill yes
			(thermal_gap 0.5)
			(thermal_bridge_width 0.5)
			(island_removal_mode 0)
		)
		(polygon
			(pts
				(xy 38.196774 -172.24375) (xy 38.196774 -174.13605) (xy 40.203374 -174.13605) (xy 40.203374 -172.244004)
				(xy 40.20312 -172.24375)
			)
		)
	)
	(zone
		(layers "In1.Cu" "In2.Cu")
		(hatch none 0.5)
		(connect_pads
			(clearance 0)
		)
		(min_thickness 0.25)
		(keepout
			(tracks not_allowed)
			(vias allowed)
			(pads allowed)
			(copperpour not_allowed)
			(footprints allowed)
		)
		(placement
			(enabled no)
			(sheetname "")
		)
		(fill yes
			(thermal_gap 0.5)
			(thermal_bridge_width 0.5)
			(island_removal_mode 0)
		)
		(polygon
			(pts
				(xy 223.196658 -71.643748) (xy 223.196658 -73.536048) (xy 225.203258 -73.536048) (xy 225.203258 -71.644002)
				(xy 225.203004 -71.643748)
			)
		)
	)
	(zone
		(layers "In1.Cu" "In2.Cu")
		(hatch none 0.5)
		(connect_pads
			(clearance 0)
		)
		(min_thickness 0.25)
		(keepout
			(tracks not_allowed)
			(vias allowed)
			(pads allowed)
			(copperpour not_allowed)
			(footprints allowed)
		)
		(placement
			(enabled no)
			(sheetname "")
		)
		(fill yes
			(thermal_gap 0.5)
			(thermal_bridge_width 0.5)
			(island_removal_mode 0)
		)
		(polygon
			(pts
				(xy 23.803356 -245.956074) (xy 23.803356 -244.063774) (xy 21.796756 -244.063774) (xy 21.796756 -245.95582)
				(xy 21.79701 -245.956074)
			)
		)
	)
	(zone
		(layers "In1.Cu" "In2.Cu")
		(hatch none 0.5)
		(connect_pads
			(clearance 0)
		)
		(min_thickness 0.25)
		(keepout
			(tracks not_allowed)
			(vias allowed)
			(pads allowed)
			(copperpour not_allowed)
			(footprints allowed)
		)
		(placement
			(enabled no)
			(sheetname "")
		)
		(fill yes
			(thermal_gap 0.5)
			(thermal_bridge_width 0.5)
			(island_removal_mode 0)
		)
		(polygon
			(pts
				(xy 23.803356 -434.356256) (xy 23.803356 -432.463956) (xy 21.796756 -432.463956) (xy 21.796756 -434.356002)
				(xy 21.79701 -434.356256)
			)
		)
	)
	(zone
		(layers "In1.Cu" "In2.Cu")
		(hatch none 0.5)
		(connect_pads
			(clearance 0)
		)
		(min_thickness 0.25)
		(keepout
			(tracks not_allowed)
			(vias allowed)
			(pads allowed)
			(copperpour not_allowed)
			(footprints allowed)
		)
		(placement
			(enabled no)
			(sheetname "")
		)
		(fill yes
			(thermal_gap 0.5)
			(thermal_bridge_width 0.5)
			(island_removal_mode 0)
		)
		(polygon
			(pts
				(xy 23.803356 -122.956066) (xy 23.803356 -121.063766) (xy 21.796756 -121.063766) (xy 21.796756 -122.955812)
				(xy 21.79701 -122.956066)
			)
		)
	)
	(zone
		(layers "In1.Cu" "In2.Cu")
		(hatch none 0.5)
		(connect_pads
			(clearance 0)
		)
		(min_thickness 0.25)
		(keepout
			(tracks not_allowed)
			(vias allowed)
			(pads allowed)
			(copperpour not_allowed)
			(footprints allowed)
		)
		(placement
			(enabled no)
			(sheetname "")
		)
		(fill yes
			(thermal_gap 0.5)
			(thermal_bridge_width 0.5)
			(island_removal_mode 0)
		)
		(polygon
			(pts
				(xy 23.803356 -225.956114) (xy 23.803356 -224.063814) (xy 21.796756 -224.063814) (xy 21.796756 -225.95586)
				(xy 21.79701 -225.956114)
			)
		)
	)
	(zone
		(layers "In1.Cu" "In2.Cu")
		(hatch none 0.5)
		(connect_pads
			(clearance 0)
		)
		(min_thickness 0.25)
		(keepout
			(tracks not_allowed)
			(vias allowed)
			(pads allowed)
			(copperpour not_allowed)
			(footprints allowed)
		)
		(placement
			(enabled no)
			(sheetname "")
		)
		(fill yes
			(thermal_gap 0.5)
			(thermal_bridge_width 0.5)
			(island_removal_mode 0)
		)
		(polygon
			(pts
				(xy 38.196774 -66.84391) (xy 38.196774 -68.735956) (xy 40.203374 -68.735956) (xy 40.203374 -66.844164)
				(xy 40.20312 -66.84391)
			)
		)
	)
	(zone
		(layers "In1.Cu" "In2.Cu")
		(hatch none 0.5)
		(connect_pads
			(clearance 0)
		)
		(min_thickness 0.25)
		(keepout
			(tracks not_allowed)
			(vias allowed)
			(pads allowed)
			(copperpour not_allowed)
			(footprints allowed)
		)
		(placement
			(enabled no)
			(sheetname "")
		)
		(fill yes
			(thermal_gap 0.5)
			(thermal_bridge_width 0.5)
			(island_removal_mode 0)
		)
		(polygon
			(pts
				(xy 38.196774 -280.04389) (xy 38.196774 -281.93619) (xy 40.203374 -281.93619) (xy 40.203374 -280.044144)
				(xy 40.20312 -280.04389)
			)
		)
	)
	(zone
		(layers "In1.Cu" "In2.Cu")
		(hatch none 0.5)
		(connect_pads
			(clearance 0)
		)
		(min_thickness 0.25)
		(keepout
			(tracks not_allowed)
			(vias allowed)
			(pads allowed)
			(copperpour not_allowed)
			(footprints allowed)
		)
		(placement
			(enabled no)
			(sheetname "")
		)
		(fill yes
			(thermal_gap 0.5)
			(thermal_bridge_width 0.5)
			(island_removal_mode 0)
		)
		(polygon
			(pts
				(xy 223.196658 -179.443888) (xy 223.196658 -181.336188) (xy 225.203258 -181.336188) (xy 225.203258 -179.444142)
				(xy 225.203004 -179.443888)
			)
		)
	)
	(zone
		(layers "In1.Cu" "In2.Cu")
		(hatch none 0.5)
		(connect_pads
			(clearance 0)
		)
		(min_thickness 0.25)
		(keepout
			(tracks not_allowed)
			(vias allowed)
			(pads allowed)
			(copperpour not_allowed)
			(footprints allowed)
		)
		(placement
			(enabled no)
			(sheetname "")
		)
		(fill yes
			(thermal_gap 0.5)
			(thermal_bridge_width 0.5)
			(island_removal_mode 0)
		)
		(polygon
			(pts
				(xy 38.196774 -169.843958) (xy 38.196774 -171.736004) (xy 40.203374 -171.736004) (xy 40.203374 -169.844212)
				(xy 40.20312 -169.843958)
			)
		)
	)
	(zone
		(layers "In1.Cu" "In2.Cu")
		(hatch none 0.5)
		(connect_pads
			(clearance 0)
		)
		(min_thickness 0.25)
		(keepout
			(tracks not_allowed)
			(vias allowed)
			(pads allowed)
			(copperpour not_allowed)
			(footprints allowed)
		)
		(placement
			(enabled no)
			(sheetname "")
		)
		(fill yes
			(thermal_gap 0.5)
			(thermal_bridge_width 0.5)
			(island_removal_mode 0)
		)
		(polygon
			(pts
				(xy 23.803356 -326.556116) (xy 23.803356 -324.663816) (xy 21.796756 -324.663816) (xy 21.796756 -326.555862)
				(xy 21.79701 -326.556116)
			)
		)
	)
	(zone
		(layers "In1.Cu" "In2.Cu")
		(hatch none 0.5)
		(connect_pads
			(clearance 0)
		)
		(min_thickness 0.25)
		(keepout
			(tracks not_allowed)
			(vias allowed)
			(pads allowed)
			(copperpour not_allowed)
			(footprints allowed)
		)
		(placement
			(enabled no)
			(sheetname "")
		)
		(fill yes
			(thermal_gap 0.5)
			(thermal_bridge_width 0.5)
			(island_removal_mode 0)
		)
		(polygon
			(pts
				(xy 23.803356 -348.956122) (xy 23.803356 -347.063822) (xy 21.796756 -347.063822) (xy 21.796756 -348.955868)
				(xy 21.79701 -348.956122)
			)
		)
	)
	(zone
		(layers "In1.Cu" "In2.Cu")
		(hatch none 0.5)
		(connect_pads
			(clearance 0)
		)
		(min_thickness 0.25)
		(keepout
			(tracks not_allowed)
			(vias allowed)
			(pads allowed)
			(copperpour not_allowed)
			(footprints allowed)
		)
		(placement
			(enabled no)
			(sheetname "")
		)
		(fill yes
			(thermal_gap 0.5)
			(thermal_bridge_width 0.5)
			(island_removal_mode 0)
		)
		(polygon
			(pts
				(xy 223.196658 -375.844054) (xy 223.196658 -377.7361) (xy 225.203258 -377.7361) (xy 225.203258 -375.844308)
				(xy 225.203004 -375.844054)
			)
		)
	)
	(zone
		(layers "In1.Cu" "In2.Cu")
		(hatch none 0.5)
		(connect_pads
			(clearance 0)
		)
		(min_thickness 0.25)
		(keepout
			(tracks not_allowed)
			(vias allowed)
			(pads allowed)
			(copperpour not_allowed)
			(footprints allowed)
		)
		(placement
			(enabled no)
			(sheetname "")
		)
		(fill yes
			(thermal_gap 0.5)
			(thermal_bridge_width 0.5)
			(island_removal_mode 0)
		)
		(polygon
			(pts
				(xy 20.61337 -33.95599) (xy 20.61337 -32.06369) (xy 18.60677 -32.06369) (xy 18.60677 -33.955736)
				(xy 18.607024 -33.95599)
			)
		)
	)
	(zone
		(layers "In1.Cu" "In2.Cu")
		(hatch none 0.5)
		(connect_pads
			(clearance 0)
		)
		(min_thickness 0.25)
		(keepout
			(tracks not_allowed)
			(vias allowed)
			(pads allowed)
			(copperpour not_allowed)
			(footprints allowed)
		)
		(placement
			(enabled no)
			(sheetname "")
		)
		(fill yes
			(thermal_gap 0.5)
			(thermal_bridge_width 0.5)
			(island_removal_mode 0)
		)
		(polygon
			(pts
				(xy 223.196658 -360.643932) (xy 223.196658 -362.536232) (xy 225.203258 -362.536232) (xy 225.203258 -360.644186)
				(xy 225.203004 -360.643932)
			)
		)
	)
	(zone
		(layers "In1.Cu" "In2.Cu")
		(hatch none 0.5)
		(connect_pads
			(clearance 0)
		)
		(min_thickness 0.25)
		(keepout
			(tracks not_allowed)
			(vias allowed)
			(pads allowed)
			(copperpour not_allowed)
			(footprints allowed)
		)
		(placement
			(enabled no)
			(sheetname "")
		)
		(fill yes
			(thermal_gap 0.5)
			(thermal_bridge_width 0.5)
			(island_removal_mode 0)
		)
		(polygon
			(pts
				(xy 23.803356 -42.356024) (xy 23.803356 -40.463724) (xy 21.796756 -40.463724) (xy 21.796756 -42.35577)
				(xy 21.79701 -42.356024)
			)
		)
	)
	(zone
		(layers "In1.Cu" "In2.Cu")
		(hatch none 0.5)
		(connect_pads
			(clearance 0)
		)
		(min_thickness 0.25)
		(keepout
			(tracks not_allowed)
			(vias allowed)
			(pads allowed)
			(copperpour not_allowed)
			(footprints allowed)
		)
		(placement
			(enabled no)
			(sheetname "")
		)
		(fill yes
			(thermal_gap 0.5)
			(thermal_bridge_width 0.5)
			(island_removal_mode 0)
		)
		(polygon
			(pts
				(xy 38.196774 -76.44384) (xy 38.196774 -78.33614) (xy 40.203374 -78.33614) (xy 40.203374 -76.444094)
				(xy 40.20312 -76.44384)
			)
		)
	)
	(zone
		(layers "In1.Cu" "In2.Cu")
		(hatch none 0.5)
		(connect_pads
			(clearance 0)
		)
		(min_thickness 0.25)
		(keepout
			(tracks not_allowed)
			(vias allowed)
			(pads allowed)
			(copperpour not_allowed)
			(footprints allowed)
		)
		(placement
			(enabled no)
			(sheetname "")
		)
		(fill yes
			(thermal_gap 0.5)
			(thermal_bridge_width 0.5)
			(island_removal_mode 0)
		)
		(polygon
			(pts
				(xy 23.803356 -248.35612) (xy 23.803356 -246.46382) (xy 21.796756 -246.46382) (xy 21.796756 -248.355866)
				(xy 21.79701 -248.35612)
			)
		)
	)
	(zone
		(layers "In1.Cu" "In2.Cu")
		(hatch none 0.5)
		(connect_pads
			(clearance 0)
		)
		(min_thickness 0.25)
		(keepout
			(tracks not_allowed)
			(vias allowed)
			(pads allowed)
			(copperpour not_allowed)
			(footprints allowed)
		)
		(placement
			(enabled no)
			(sheetname "")
		)
		(fill yes
			(thermal_gap 0.5)
			(thermal_bridge_width 0.5)
			(island_removal_mode 0)
		)
		(polygon
			(pts
				(xy 38.196774 -179.443888) (xy 38.196774 -181.336188) (xy 40.203374 -181.336188) (xy 40.203374 -179.444142)
				(xy 40.20312 -179.443888)
			)
		)
	)
	(zone
		(layers "In1.Cu" "In2.Cu")
		(hatch none 0.5)
		(connect_pads
			(clearance 0)
		)
		(min_thickness 0.25)
		(keepout
			(tracks not_allowed)
			(vias allowed)
			(pads allowed)
			(copperpour not_allowed)
			(footprints allowed)
		)
		(placement
			(enabled no)
			(sheetname "")
		)
		(fill yes
			(thermal_gap 0.5)
			(thermal_bridge_width 0.5)
			(island_removal_mode 0)
		)
		(polygon
			(pts
				(xy 38.196774 -56.44388) (xy 38.196774 -58.335926) (xy 40.203374 -58.335926) (xy 40.203374 -56.444134)
				(xy 40.20312 -56.44388)
			)
		)
	)
	(zone
		(layers "In1.Cu" "In2.Cu")
		(hatch none 0.5)
		(connect_pads
			(clearance 0)
		)
		(min_thickness 0.25)
		(keepout
			(tracks not_allowed)
			(vias allowed)
			(pads allowed)
			(copperpour not_allowed)
			(footprints allowed)
		)
		(placement
			(enabled no)
			(sheetname "")
		)
		(fill yes
			(thermal_gap 0.5)
			(thermal_bridge_width 0.5)
			(island_removal_mode 0)
		)
		(polygon
			(pts
				(xy 223.196658 -363.043978) (xy 223.196658 -364.936278) (xy 225.203258 -364.936278) (xy 225.203258 -363.044232)
				(xy 225.203004 -363.043978)
			)
		)
	)
	(zone
		(layers "In1.Cu" "In2.Cu")
		(hatch none 0.5)
		(connect_pads
			(clearance 0)
		)
		(min_thickness 0.25)
		(keepout
			(tracks not_allowed)
			(vias allowed)
			(pads allowed)
			(copperpour not_allowed)
			(footprints allowed)
		)
		(placement
			(enabled no)
			(sheetname "")
		)
		(fill yes
			(thermal_gap 0.5)
			(thermal_bridge_width 0.5)
			(island_removal_mode 0)
		)
		(polygon
			(pts
				(xy 23.803356 -145.356072) (xy 23.803356 -143.463772) (xy 21.796756 -143.463772) (xy 21.796756 -145.355818)
				(xy 21.79701 -145.356072)
			)
		)
	)
	(zone
		(layers "In1.Cu" "In2.Cu")
		(hatch none 0.5)
		(connect_pads
			(clearance 0)
		)
		(min_thickness 0.25)
		(keepout
			(tracks not_allowed)
			(vias allowed)
			(pads allowed)
			(copperpour not_allowed)
			(footprints allowed)
		)
		(placement
			(enabled no)
			(sheetname "")
		)
		(fill yes
			(thermal_gap 0.5)
			(thermal_bridge_width 0.5)
			(island_removal_mode 0)
		)
		(polygon
			(pts
				(xy 223.196658 -378.243846) (xy 223.196658 -380.136146) (xy 225.203258 -380.136146) (xy 225.203258 -378.2441)
				(xy 225.203004 -378.243846)
			)
		)
	)
	(zone
		(layers "In1.Cu" "In2.Cu")
		(hatch none 0.5)
		(connect_pads
			(clearance 0)
		)
		(min_thickness 0.25)
		(keepout
			(tracks not_allowed)
			(vias allowed)
			(pads allowed)
			(copperpour not_allowed)
			(footprints allowed)
		)
		(placement
			(enabled no)
			(sheetname "")
		)
		(fill yes
			(thermal_gap 0.5)
			(thermal_bridge_width 0.5)
			(island_removal_mode 0)
		)
		(polygon
			(pts
				(xy 23.803356 -429.556164) (xy 23.803356 -427.663864) (xy 21.796756 -427.663864) (xy 21.796756 -429.55591)
				(xy 21.79701 -429.556164)
			)
		)
	)
	(zone
		(layers "In1.Cu" "In2.Cu")
		(hatch none 0.5)
		(connect_pads
			(clearance 0)
		)
		(min_thickness 0.25)
		(keepout
			(tracks not_allowed)
			(vias allowed)
			(pads allowed)
			(copperpour not_allowed)
			(footprints allowed)
		)
		(placement
			(enabled no)
			(sheetname "")
		)
		(fill yes
			(thermal_gap 0.5)
			(thermal_bridge_width 0.5)
			(island_removal_mode 0)
		)
		(polygon
			(pts
				(xy 23.803356 -431.95621) (xy 23.803356 -430.06391) (xy 21.796756 -430.06391) (xy 21.796756 -431.955956)
				(xy 21.79701 -431.95621)
			)
		)
	)
	(zone
		(layers "In1.Cu" "In2.Cu")
		(hatch none 0.5)
		(connect_pads
			(clearance 0)
		)
		(min_thickness 0.25)
		(keepout
			(tracks not_allowed)
			(vias allowed)
			(pads allowed)
			(copperpour not_allowed)
			(footprints allowed)
		)
		(placement
			(enabled no)
			(sheetname "")
		)
		(fill yes
			(thermal_gap 0.5)
			(thermal_bridge_width 0.5)
			(island_removal_mode 0)
		)
		(polygon
			(pts
				(xy 38.196774 -154.643836) (xy 38.196774 -156.536136) (xy 40.203374 -156.536136) (xy 40.203374 -154.64409)
				(xy 40.20312 -154.643836)
			)
		)
	)
	(zone
		(layers "In1.Cu" "In2.Cu")
		(hatch none 0.5)
		(connect_pads
			(clearance 0)
		)
		(min_thickness 0.25)
		(keepout
			(tracks not_allowed)
			(vias allowed)
			(pads allowed)
			(copperpour not_allowed)
			(footprints allowed)
		)
		(placement
			(enabled no)
			(sheetname "")
		)
		(fill yes
			(thermal_gap 0.5)
			(thermal_bridge_width 0.5)
			(island_removal_mode 0)
		)
		(polygon
			(pts
				(xy 223.196658 -277.643844) (xy 223.196658 -279.536144) (xy 225.203258 -279.536144) (xy 225.203258 -277.644098)
				(xy 225.203004 -277.643844)
			)
		)
	)
	(zone
		(layers "In1.Cu" "In2.Cu")
		(hatch none 0.5)
		(connect_pads
			(clearance 0)
		)
		(min_thickness 0.25)
		(keepout
			(tracks not_allowed)
			(vias allowed)
			(pads allowed)
			(copperpour not_allowed)
			(footprints allowed)
		)
		(placement
			(enabled no)
			(sheetname "")
		)
		(fill yes
			(thermal_gap 0.5)
			(thermal_bridge_width 0.5)
			(island_removal_mode 0)
		)
		(polygon
			(pts
				(xy 23.803356 -439.156094) (xy 23.803356 -437.264048) (xy 21.796756 -437.264048) (xy 21.796756 -439.15584)
				(xy 21.79701 -439.156094)
			)
		)
	)
	(zone
		(layers "In1.Cu" "In2.Cu")
		(hatch none 0.5)
		(connect_pads
			(clearance 0)
		)
		(min_thickness 0.25)
		(keepout
			(tracks not_allowed)
			(vias allowed)
			(pads allowed)
			(copperpour not_allowed)
			(footprints allowed)
		)
		(placement
			(enabled no)
			(sheetname "")
		)
		(fill yes
			(thermal_gap 0.5)
			(thermal_bridge_width 0.5)
			(island_removal_mode 0)
		)
		(polygon
			(pts
				(xy 38.196774 -360.643932) (xy 38.196774 -362.536232) (xy 40.203374 -362.536232) (xy 40.203374 -360.644186)
				(xy 40.20312 -360.643932)
			)
		)
	)
	(zone
		(layers "In1.Cu" "In2.Cu")
		(hatch none 0.5)
		(connect_pads
			(clearance 0)
		)
		(min_thickness 0.25)
		(keepout
			(tracks not_allowed)
			(vias allowed)
			(pads allowed)
			(copperpour not_allowed)
			(footprints allowed)
		)
		(placement
			(enabled no)
			(sheetname "")
		)
		(fill yes
			(thermal_gap 0.5)
			(thermal_bridge_width 0.5)
			(island_removal_mode 0)
		)
		(polygon
			(pts
				(xy 23.803356 -17.555972) (xy 23.803356 -15.663672) (xy 21.796756 -15.663672) (xy 21.796756 -17.555718)
				(xy 21.79701 -17.555972)
			)
		)
	)
	(zone
		(layers "In1.Cu" "In2.Cu")
		(hatch none 0.5)
		(connect_pads
			(clearance 0)
		)
		(min_thickness 0.25)
		(keepout
			(tracks not_allowed)
			(vias allowed)
			(pads allowed)
			(copperpour not_allowed)
			(footprints allowed)
		)
		(placement
			(enabled no)
			(sheetname "")
		)
		(fill yes
			(thermal_gap 0.5)
			(thermal_bridge_width 0.5)
			(island_removal_mode 0)
		)
		(polygon
			(pts
				(xy 223.196658 -466.044026) (xy 223.196658 -467.936326) (xy 225.203258 -467.936326) (xy 225.203258 -466.04428)
				(xy 225.203004 -466.044026)
			)
		)
	)
	(zone
		(layers "In1.Cu" "In2.Cu")
		(hatch none 0.5)
		(connect_pads
			(clearance 0)
		)
		(min_thickness 0.25)
		(keepout
			(tracks not_allowed)
			(vias allowed)
			(pads allowed)
			(copperpour not_allowed)
			(footprints allowed)
		)
		(placement
			(enabled no)
			(sheetname "")
		)
		(fill yes
			(thermal_gap 0.5)
			(thermal_bridge_width 0.5)
			(island_removal_mode 0)
		)
		(polygon
			(pts
				(xy 23.803356 -15.155926) (xy 23.803356 -13.26388) (xy 21.796756 -13.26388) (xy 21.796756 -15.155672)
				(xy 21.79701 -15.155926)
			)
		)
	)
	(zone
		(layers "In1.Cu" "In2.Cu")
		(hatch none 0.5)
		(connect_pads
			(clearance 0)
		)
		(min_thickness 0.25)
		(keepout
			(tracks not_allowed)
			(vias allowed)
			(pads allowed)
			(copperpour not_allowed)
			(footprints allowed)
		)
		(placement
			(enabled no)
			(sheetname "")
		)
		(fill yes
			(thermal_gap 0.5)
			(thermal_bridge_width 0.5)
			(island_removal_mode 0)
		)
		(polygon
			(pts
				(xy 223.196658 -159.443928) (xy 223.196658 -161.335974) (xy 225.203258 -161.335974) (xy 225.203258 -159.444182)
				(xy 225.203004 -159.443928)
			)
		)
	)
	(zone
		(layers "In1.Cu" "In2.Cu")
		(hatch none 0.5)
		(connect_pads
			(clearance 0)
		)
		(min_thickness 0.25)
		(keepout
			(tracks not_allowed)
			(vias allowed)
			(pads allowed)
			(copperpour not_allowed)
			(footprints allowed)
		)
		(placement
			(enabled no)
			(sheetname "")
		)
		(fill yes
			(thermal_gap 0.5)
			(thermal_bridge_width 0.5)
			(island_removal_mode 0)
		)
		(polygon
			(pts
				(xy 23.803356 -27.155902) (xy 23.803356 -25.263856) (xy 21.796756 -25.263856) (xy 21.796756 -27.155648)
				(xy 21.79701 -27.155902)
			)
		)
	)
	(zone
		(layers "In1.Cu" "In2.Cu")
		(hatch none 0.5)
		(connect_pads
			(clearance 0)
		)
		(min_thickness 0.25)
		(keepout
			(tracks not_allowed)
			(vias allowed)
			(pads allowed)
			(copperpour not_allowed)
			(footprints allowed)
		)
		(placement
			(enabled no)
			(sheetname "")
		)
		(fill yes
			(thermal_gap 0.5)
			(thermal_bridge_width 0.5)
			(island_removal_mode 0)
		)
		(polygon
			(pts
				(xy 23.803356 -243.556028) (xy 23.803356 -241.663982) (xy 21.796756 -241.663982) (xy 21.796756 -243.555774)
				(xy 21.79701 -243.556028)
			)
		)
	)
	(zone
		(layers "In1.Cu" "In2.Cu")
		(hatch none 0.5)
		(connect_pads
			(clearance 0)
		)
		(min_thickness 0.25)
		(keepout
			(tracks not_allowed)
			(vias allowed)
			(pads allowed)
			(copperpour not_allowed)
			(footprints allowed)
		)
		(placement
			(enabled no)
			(sheetname "")
		)
		(fill yes
			(thermal_gap 0.5)
			(thermal_bridge_width 0.5)
			(island_removal_mode 0)
		)
		(polygon
			(pts
				(xy 225.203258 -485.53624) (xy 225.203258 -483.64394) (xy 223.196658 -483.64394) (xy 223.196658 -485.535986)
				(xy 223.196912 -485.53624)
			)
		)
	)
	(zone
		(layers "In1.Cu" "In2.Cu")
		(hatch none 0.5)
		(connect_pads
			(clearance 0)
		)
		(min_thickness 0.25)
		(keepout
			(tracks not_allowed)
			(vias allowed)
			(pads allowed)
			(copperpour not_allowed)
			(footprints allowed)
		)
		(placement
			(enabled no)
			(sheetname "")
		)
		(fill yes
			(thermal_gap 0.5)
			(thermal_bridge_width 0.5)
			(island_removal_mode 0)
		)
		(polygon
			(pts
				(xy 223.196658 -284.843982) (xy 223.196658 -286.736028) (xy 225.203258 -286.736028) (xy 225.203258 -284.844236)
				(xy 225.203004 -284.843982)
			)
		)
	)
	(zone
		(layers "In1.Cu" "In2.Cu")
		(hatch none 0.5)
		(connect_pads
			(clearance 0)
		)
		(min_thickness 0.25)
		(keepout
			(tracks not_allowed)
			(vias allowed)
			(pads allowed)
			(copperpour not_allowed)
			(footprints allowed)
		)
		(placement
			(enabled no)
			(sheetname "")
		)
		(fill yes
			(thermal_gap 0.5)
			(thermal_bridge_width 0.5)
			(island_removal_mode 0)
		)
		(polygon
			(pts
				(xy 223.196658 -74.043794) (xy 223.196658 -75.936094) (xy 225.203258 -75.936094) (xy 225.203258 -74.044048)
				(xy 225.203004 -74.043794)
			)
		)
	)
	(zone
		(layers "In1.Cu" "In2.Cu")
		(hatch none 0.5)
		(connect_pads
			(clearance 0)
		)
		(min_thickness 0.25)
		(keepout
			(tracks not_allowed)
			(vias allowed)
			(pads allowed)
			(copperpour not_allowed)
			(footprints allowed)
		)
		(placement
			(enabled no)
			(sheetname "")
		)
		(fill yes
			(thermal_gap 0.5)
			(thermal_bridge_width 0.5)
			(island_removal_mode 0)
		)
		(polygon
			(pts
				(xy 223.196658 -490.844078) (xy 223.196658 -492.736124) (xy 225.203258 -492.736124) (xy 225.203258 -490.844332)
				(xy 225.203004 -490.844078)
			)
		)
	)
	(zone
		(layers "In1.Cu" "In2.Cu")
		(hatch none 0.5)
		(connect_pads
			(clearance 0)
		)
		(min_thickness 0.25)
		(keepout
			(tracks not_allowed)
			(vias allowed)
			(pads allowed)
			(copperpour not_allowed)
			(footprints allowed)
		)
		(placement
			(enabled no)
			(sheetname "")
		)
		(fill yes
			(thermal_gap 0.5)
			(thermal_bridge_width 0.5)
			(island_removal_mode 0)
		)
		(polygon
			(pts
				(xy 23.803356 -228.35616) (xy 23.803356 -226.46386) (xy 21.796756 -226.46386) (xy 21.796756 -228.355906)
				(xy 21.79701 -228.35616)
			)
		)
	)
	(zone
		(layers "In1.Cu" "In2.Cu")
		(hatch none 0.5)
		(connect_pads
			(clearance 0)
		)
		(min_thickness 0.25)
		(keepout
			(tracks not_allowed)
			(vias allowed)
			(pads allowed)
			(copperpour not_allowed)
			(footprints allowed)
		)
		(placement
			(enabled no)
			(sheetname "")
		)
		(fill yes
			(thermal_gap 0.5)
			(thermal_bridge_width 0.5)
			(island_removal_mode 0)
		)
		(polygon
			(pts
				(xy 38.196774 -78.843886) (xy 38.196774 -80.735932) (xy 40.203374 -80.735932) (xy 40.203374 -78.84414)
				(xy 40.20312 -78.843886)
			)
		)
	)
	(zone
		(layers "In1.Cu" "In2.Cu")
		(hatch none 0.5)
		(connect_pads
			(clearance 0)
		)
		(min_thickness 0.25)
		(keepout
			(tracks not_allowed)
			(vias allowed)
			(pads allowed)
			(copperpour not_allowed)
			(footprints allowed)
		)
		(placement
			(enabled no)
			(sheetname "")
		)
		(fill yes
			(thermal_gap 0.5)
			(thermal_bridge_width 0.5)
			(island_removal_mode 0)
		)
		(polygon
			(pts
				(xy 38.196774 -486.043986) (xy 38.196774 -487.936286) (xy 40.203374 -487.936286) (xy 40.203374 -486.04424)
				(xy 40.20312 -486.043986)
			)
		)
	)
	(zone
		(layers "In1.Cu" "In2.Cu")
		(hatch none 0.5)
		(connect_pads
			(clearance 0)
		)
		(min_thickness 0.25)
		(keepout
			(tracks not_allowed)
			(vias allowed)
			(pads allowed)
			(copperpour not_allowed)
			(footprints allowed)
		)
		(placement
			(enabled no)
			(sheetname "")
		)
		(fill yes
			(thermal_gap 0.5)
			(thermal_bridge_width 0.5)
			(island_removal_mode 0)
		)
		(polygon
			(pts
				(xy 88.97239 -209.72399) (xy 88.97239 -210.916266) (xy 90.14079 -210.916266) (xy 90.14079 -209.72399)
			)
		)
	)
	(zone
		(layers "In1.Cu" "In2.Cu")
		(hatch none 0.5)
		(connect_pads
			(clearance 0)
		)
		(min_thickness 0.25)
		(keepout
			(tracks not_allowed)
			(vias allowed)
			(pads allowed)
			(copperpour not_allowed)
			(footprints allowed)
		)
		(placement
			(enabled no)
			(sheetname "")
		)
		(fill yes
			(thermal_gap 0.5)
			(thermal_bridge_width 0.5)
			(island_removal_mode 0)
		)
		(polygon
			(pts
				(xy 23.803356 -451.95617) (xy 23.803356 -450.06387) (xy 21.796756 -450.06387) (xy 21.796756 -451.955916)
				(xy 21.79701 -451.95617)
			)
		)
	)
	(zone
		(layers "In1.Cu" "In2.Cu")
		(hatch none 0.5)
		(connect_pads
			(clearance 0)
		)
		(min_thickness 0.25)
		(keepout
			(tracks not_allowed)
			(vias allowed)
			(pads allowed)
			(copperpour not_allowed)
			(footprints allowed)
		)
		(placement
			(enabled no)
			(sheetname "")
		)
		(fill yes
			(thermal_gap 0.5)
			(thermal_bridge_width 0.5)
			(island_removal_mode 0)
		)
		(polygon
			(pts
				(xy 223.196658 -177.043842) (xy 223.196658 -178.936142) (xy 225.203258 -178.936142) (xy 225.203258 -177.044096)
				(xy 225.203004 -177.043842)
			)
		)
	)
	(zone
		(layers "In1.Cu" "In2.Cu")
		(hatch none 0.5)
		(connect_pads
			(clearance 0)
		)
		(min_thickness 0.25)
		(keepout
			(tracks not_allowed)
			(vias allowed)
			(pads allowed)
			(copperpour not_allowed)
			(footprints allowed)
		)
		(placement
			(enabled no)
			(sheetname "")
		)
		(fill yes
			(thermal_gap 0.5)
			(thermal_bridge_width 0.5)
			(island_removal_mode 0)
		)
		(polygon
			(pts
				(xy 23.803356 -333.756254) (xy 23.803356 -331.863954) (xy 21.796756 -331.863954) (xy 21.796756 -333.756)
				(xy 21.79701 -333.756254)
			)
		)
	)
	(zone
		(layers "In1.Cu" "In2.Cu")
		(hatch none 0.5)
		(connect_pads
			(clearance 0)
		)
		(min_thickness 0.25)
		(keepout
			(tracks not_allowed)
			(vias allowed)
			(pads allowed)
			(copperpour not_allowed)
			(footprints allowed)
		)
		(placement
			(enabled no)
			(sheetname "")
		)
		(fill yes
			(thermal_gap 0.5)
			(thermal_bridge_width 0.5)
			(island_removal_mode 0)
		)
		(polygon
			(pts
				(xy 38.196774 -380.643892) (xy 38.196774 -382.536192) (xy 40.203374 -382.536192) (xy 40.203374 -380.644146)
				(xy 40.20312 -380.643892)
			)
		)
	)
	(zone
		(layers "In1.Cu" "In2.Cu")
		(hatch none 0.5)
		(connect_pads
			(clearance 0)
		)
		(min_thickness 0.25)
		(keepout
			(tracks not_allowed)
			(vias allowed)
			(pads allowed)
			(copperpour not_allowed)
			(footprints allowed)
		)
		(placement
			(enabled no)
			(sheetname "")
		)
		(fill yes
			(thermal_gap 0.5)
			(thermal_bridge_width 0.5)
			(island_removal_mode 0)
		)
		(polygon
			(pts
				(xy 23.803356 -142.956026) (xy 23.803356 -141.063726) (xy 21.796756 -141.063726) (xy 21.796756 -142.955772)
				(xy 21.79701 -142.956026)
			)
		)
	)
	(zone
		(layers "In1.Cu" "In2.Cu")
		(hatch none 0.5)
		(connect_pads
			(clearance 0)
		)
		(min_thickness 0.25)
		(keepout
			(tracks not_allowed)
			(vias allowed)
			(pads allowed)
			(copperpour not_allowed)
			(footprints allowed)
		)
		(placement
			(enabled no)
			(sheetname "")
		)
		(fill yes
			(thermal_gap 0.5)
			(thermal_bridge_width 0.5)
			(island_removal_mode 0)
		)
		(polygon
			(pts
				(xy 38.196774 -481.243894) (xy 38.196774 -483.136194) (xy 40.203374 -483.136194) (xy 40.203374 -481.244148)
				(xy 40.20312 -481.243894)
			)
		)
	)
	(zone
		(layers "In1.Cu" "In2.Cu")
		(hatch none 0.5)
		(connect_pads
			(clearance 0)
		)
		(min_thickness 0.25)
		(keepout
			(tracks not_allowed)
			(vias allowed)
			(pads allowed)
			(copperpour not_allowed)
			(footprints allowed)
		)
		(placement
			(enabled no)
			(sheetname "")
		)
		(fill yes
			(thermal_gap 0.5)
			(thermal_bridge_width 0.5)
			(island_removal_mode 0)
		)
		(polygon
			(pts
				(xy 40.203374 -485.53624) (xy 40.203374 -483.64394) (xy 38.196774 -483.64394) (xy 38.196774 -485.535986)
				(xy 38.197028 -485.53624)
			)
		)
	)
	(zone
		(layers "In1.Cu" "In2.Cu")
		(hatch none 0.5)
		(connect_pads
			(clearance 0)
		)
		(min_thickness 0.25)
		(keepout
			(tracks not_allowed)
			(vias allowed)
			(pads allowed)
			(copperpour not_allowed)
			(footprints allowed)
		)
		(placement
			(enabled no)
			(sheetname "")
		)
		(fill yes
			(thermal_gap 0.5)
			(thermal_bridge_width 0.5)
			(island_removal_mode 0)
		)
		(polygon
			(pts
				(xy 38.196774 -260.04393) (xy 38.196774 -261.93623) (xy 40.203374 -261.93623) (xy 40.203374 -260.044184)
				(xy 40.20312 -260.04393)
			)
		)
	)
	(zone
		(layers "In1.Cu" "In2.Cu")
		(hatch none 0.5)
		(connect_pads
			(clearance 0)
		)
		(min_thickness 0.25)
		(keepout
			(tracks not_allowed)
			(vias allowed)
			(pads allowed)
			(copperpour not_allowed)
			(footprints allowed)
		)
		(placement
			(enabled no)
			(sheetname "")
		)
		(fill yes
			(thermal_gap 0.5)
			(thermal_bridge_width 0.5)
			(island_removal_mode 0)
		)
		(polygon
			(pts
				(xy 88.97239 -100.504244) (xy 88.97239 -101.696012) (xy 90.14079 -101.696012) (xy 90.14079 -100.504244)
			)
		)
	)
	(zone
		(layers "In1.Cu" "In2.Cu")
		(hatch none 0.5)
		(connect_pads
			(clearance 0)
		)
		(min_thickness 0.25)
		(keepout
			(tracks not_allowed)
			(vias allowed)
			(pads allowed)
			(copperpour not_allowed)
			(footprints allowed)
		)
		(placement
			(enabled no)
			(sheetname "")
		)
		(fill yes
			(thermal_gap 0.5)
			(thermal_bridge_width 0.5)
			(island_removal_mode 0)
		)
		(polygon
			(pts
				(xy 38.196774 -174.643796) (xy 38.196774 -176.536096) (xy 40.203374 -176.536096) (xy 40.203374 -174.64405)
				(xy 40.20312 -174.643796)
			)
		)
	)
	(zone
		(layers "In1.Cu" "In2.Cu")
		(hatch none 0.5)
		(connect_pads
			(clearance 0)
		)
		(min_thickness 0.25)
		(keepout
			(tracks not_allowed)
			(vias allowed)
			(pads allowed)
			(copperpour not_allowed)
			(footprints allowed)
		)
		(placement
			(enabled no)
			(sheetname "")
		)
		(fill yes
			(thermal_gap 0.5)
			(thermal_bridge_width 0.5)
			(island_removal_mode 0)
		)
		(polygon
			(pts
				(xy 23.803356 -19.956018) (xy 23.803356 -18.063718) (xy 21.796756 -18.063718) (xy 21.796756 -19.955764)
				(xy 21.79701 -19.956018)
			)
		)
	)
	(zone
		(layers "In1.Cu" "In2.Cu")
		(hatch none 0.5)
		(connect_pads
			(clearance 0)
		)
		(min_thickness 0.25)
		(keepout
			(tracks not_allowed)
			(vias allowed)
			(pads allowed)
			(copperpour not_allowed)
			(footprints allowed)
		)
		(placement
			(enabled no)
			(sheetname "")
		)
		(fill yes
			(thermal_gap 0.5)
			(thermal_bridge_width 0.5)
			(island_removal_mode 0)
		)
		(polygon
			(pts
				(xy 223.196658 -387.84403) (xy 223.196658 -389.736076) (xy 225.203258 -389.736076) (xy 225.203258 -387.844284)
				(xy 225.203004 -387.84403)
			)
		)
	)
	(zone
		(layers "In1.Cu" "In2.Cu")
		(hatch none 0.5)
		(connect_pads
			(clearance 0)
		)
		(min_thickness 0.25)
		(keepout
			(tracks not_allowed)
			(vias allowed)
			(pads allowed)
			(copperpour not_allowed)
			(footprints allowed)
		)
		(placement
			(enabled no)
			(sheetname "")
		)
		(fill yes
			(thermal_gap 0.5)
			(thermal_bridge_width 0.5)
			(island_removal_mode 0)
		)
		(polygon
			(pts
				(xy 38.196774 -257.643884) (xy 38.196774 -259.536184) (xy 40.203374 -259.536184) (xy 40.203374 -257.644138)
				(xy 40.20312 -257.643884)
			)
		)
	)
	(zone
		(layers "In1.Cu" "In2.Cu")
		(hatch none 0.5)
		(connect_pads
			(clearance 0)
		)
		(min_thickness 0.25)
		(keepout
			(tracks not_allowed)
			(vias allowed)
			(pads allowed)
			(copperpour not_allowed)
			(footprints allowed)
		)
		(placement
			(enabled no)
			(sheetname "")
		)
		(fill yes
			(thermal_gap 0.5)
			(thermal_bridge_width 0.5)
			(island_removal_mode 0)
		)
		(polygon
			(pts
				(xy 38.196774 -375.844054) (xy 38.196774 -377.7361) (xy 40.203374 -377.7361) (xy 40.203374 -375.844308)
				(xy 40.20312 -375.844054)
			)
		)
	)
	(zone
		(layers "In1.Cu" "In2.Cu")
		(hatch none 0.5)
		(connect_pads
			(clearance 0)
		)
		(min_thickness 0.25)
		(keepout
			(tracks not_allowed)
			(vias allowed)
			(pads allowed)
			(copperpour not_allowed)
			(footprints allowed)
		)
		(placement
			(enabled no)
			(sheetname "")
		)
		(fill yes
			(thermal_gap 0.5)
			(thermal_bridge_width 0.5)
			(island_removal_mode 0)
		)
		(polygon
			(pts
				(xy 38.196774 -71.643748) (xy 38.196774 -73.536048) (xy 40.203374 -73.536048) (xy 40.203374 -71.644002)
				(xy 40.20312 -71.643748)
			)
		)
	)
	(zone
		(layers "In1.Cu" "In2.Cu")
		(hatch none 0.5)
		(connect_pads
			(clearance 0)
		)
		(min_thickness 0.25)
		(keepout
			(tracks not_allowed)
			(vias allowed)
			(pads allowed)
			(copperpour not_allowed)
			(footprints allowed)
		)
		(placement
			(enabled no)
			(sheetname "")
		)
		(fill yes
			(thermal_gap 0.5)
			(thermal_bridge_width 0.5)
			(island_removal_mode 0)
		)
		(polygon
			(pts
				(xy 38.196774 -387.84403) (xy 38.196774 -389.736076) (xy 40.203374 -389.736076) (xy 40.203374 -387.844284)
				(xy 40.20312 -387.84403)
			)
		)
	)
	(zone
		(layers "In1.Cu" "In2.Cu")
		(hatch none 0.5)
		(connect_pads
			(clearance 0)
		)
		(min_thickness 0.25)
		(keepout
			(tracks not_allowed)
			(vias allowed)
			(pads allowed)
			(copperpour not_allowed)
			(footprints allowed)
		)
		(placement
			(enabled no)
			(sheetname "")
		)
		(fill yes
			(thermal_gap 0.5)
			(thermal_bridge_width 0.5)
			(island_removal_mode 0)
		)
		(polygon
			(pts
				(xy 225.203258 -264.336022) (xy 225.203258 -262.443976) (xy 223.196658 -262.443976) (xy 223.196658 -264.335768)
				(xy 223.196912 -264.336022)
			)
		)
	)
	(zone
		(layers "In1.Cu" "In2.Cu")
		(hatch none 0.5)
		(connect_pads
			(clearance 0)
		)
		(min_thickness 0.25)
		(keepout
			(tracks not_allowed)
			(vias allowed)
			(pads allowed)
			(copperpour not_allowed)
			(footprints allowed)
		)
		(placement
			(enabled no)
			(sheetname "")
		)
		(fill yes
			(thermal_gap 0.5)
			(thermal_bridge_width 0.5)
			(island_removal_mode 0)
		)
		(polygon
			(pts
				(xy 223.196658 -174.643796) (xy 223.196658 -176.536096) (xy 225.203258 -176.536096) (xy 225.203258 -174.64405)
				(xy 225.203004 -174.643796)
			)
		)
	)
	(zone
		(layers "In1.Cu" "In2.Cu")
		(hatch none 0.5)
		(connect_pads
			(clearance 0)
		)
		(min_thickness 0.25)
		(keepout
			(tracks not_allowed)
			(vias allowed)
			(pads allowed)
			(copperpour not_allowed)
			(footprints allowed)
		)
		(placement
			(enabled no)
			(sheetname "")
		)
		(fill yes
			(thermal_gap 0.5)
			(thermal_bridge_width 0.5)
			(island_removal_mode 0)
		)
		(polygon
			(pts
				(xy 23.803356 -328.956162) (xy 23.803356 -327.063862) (xy 21.796756 -327.063862) (xy 21.796756 -328.955908)
				(xy 21.79701 -328.956162)
			)
		)
	)
	(zone
		(layers "In1.Cu" "In2.Cu")
		(hatch none 0.5)
		(connect_pads
			(clearance 0)
		)
		(min_thickness 0.25)
		(keepout
			(tracks not_allowed)
			(vias allowed)
			(pads allowed)
			(copperpour not_allowed)
			(footprints allowed)
		)
		(placement
			(enabled no)
			(sheetname "")
		)
		(fill yes
			(thermal_gap 0.5)
			(thermal_bridge_width 0.5)
			(island_removal_mode 0)
		)
		(polygon
			(pts
				(xy 38.196774 -51.643788) (xy 38.196774 -53.536088) (xy 40.203374 -53.536088) (xy 40.203374 -51.644042)
				(xy 40.20312 -51.643788)
			)
		)
	)
	(zone
		(layers "In1.Cu" "In2.Cu")
		(hatch none 0.5)
		(connect_pads
			(clearance 0)
		)
		(min_thickness 0.25)
		(keepout
			(tracks not_allowed)
			(vias allowed)
			(pads allowed)
			(copperpour not_allowed)
			(footprints allowed)
		)
		(placement
			(enabled no)
			(sheetname "")
		)
		(fill yes
			(thermal_gap 0.5)
			(thermal_bridge_width 0.5)
			(island_removal_mode 0)
		)
		(polygon
			(pts
				(xy 223.196658 -51.643788) (xy 223.196658 -53.536088) (xy 225.203258 -53.536088) (xy 225.203258 -51.644042)
				(xy 225.203004 -51.643788)
			)
		)
	)
	(zone
		(layers "In1.Cu" "In2.Cu")
		(hatch none 0.5)
		(connect_pads
			(clearance 0)
		)
		(min_thickness 0.25)
		(keepout
			(tracks not_allowed)
			(vias allowed)
			(pads allowed)
			(copperpour not_allowed)
			(footprints allowed)
		)
		(placement
			(enabled no)
			(sheetname "")
		)
		(fill yes
			(thermal_gap 0.5)
			(thermal_bridge_width 0.5)
			(island_removal_mode 0)
		)
		(polygon
			(pts
				(xy 223.196658 -169.843958) (xy 223.196658 -171.736004) (xy 225.203258 -171.736004) (xy 225.203258 -169.844212)
				(xy 225.203004 -169.843958)
			)
		)
	)
	(zone
		(layers "In1.Cu" "In2.Cu")
		(hatch none 0.5)
		(connect_pads
			(clearance 0)
		)
		(min_thickness 0.25)
		(keepout
			(tracks not_allowed)
			(vias allowed)
			(pads allowed)
			(copperpour not_allowed)
			(footprints allowed)
		)
		(placement
			(enabled no)
			(sheetname "")
		)
		(fill yes
			(thermal_gap 0.5)
			(thermal_bridge_width 0.5)
			(island_removal_mode 0)
		)
		(polygon
			(pts
				(xy 23.803356 -454.356216) (xy 23.803356 -452.463916) (xy 21.796756 -452.463916) (xy 21.796756 -454.355962)
				(xy 21.79701 -454.356216)
			)
		)
	)
	(zone
		(layers "In1.Cu" "In2.Cu")
		(hatch none 0.5)
		(connect_pads
			(clearance 0)
		)
		(min_thickness 0.25)
		(keepout
			(tracks not_allowed)
			(vias allowed)
			(pads allowed)
			(copperpour not_allowed)
			(footprints allowed)
		)
		(placement
			(enabled no)
			(sheetname "")
		)
		(fill yes
			(thermal_gap 0.5)
			(thermal_bridge_width 0.5)
			(island_removal_mode 0)
		)
		(polygon
			(pts
				(xy 223.196658 -272.844006) (xy 223.196658 -274.736052) (xy 225.203258 -274.736052) (xy 225.203258 -272.84426)
				(xy 225.203004 -272.844006)
			)
		)
	)
	(zone
		(layers "In1.Cu" "In2.Cu")
		(hatch none 0.5)
		(connect_pads
			(clearance 0)
		)
		(min_thickness 0.25)
		(keepout
			(tracks not_allowed)
			(vias allowed)
			(pads allowed)
			(copperpour not_allowed)
			(footprints allowed)
		)
		(placement
			(enabled no)
			(sheetname "")
		)
		(fill yes
			(thermal_gap 0.5)
			(thermal_bridge_width 0.5)
			(island_removal_mode 0)
		)
		(polygon
			(pts
				(xy 23.803356 -233.155998) (xy 23.803356 -231.263952) (xy 21.796756 -231.263952) (xy 21.796756 -233.155744)
				(xy 21.79701 -233.155998)
			)
		)
	)
	(zone
		(layers "In1.Cu" "In2.Cu")
		(hatch none 0.5)
		(connect_pads
			(clearance 0)
		)
		(min_thickness 0.25)
		(keepout
			(tracks not_allowed)
			(vias allowed)
			(pads allowed)
			(copperpour not_allowed)
			(footprints allowed)
		)
		(placement
			(enabled no)
			(sheetname "")
		)
		(fill yes
			(thermal_gap 0.5)
			(thermal_bridge_width 0.5)
			(island_removal_mode 0)
		)
		(polygon
			(pts
				(xy 223.196658 -481.243894) (xy 223.196658 -483.136194) (xy 225.203258 -483.136194) (xy 225.203258 -481.244148)
				(xy 225.203004 -481.243894)
			)
		)
	)
	(zone
		(layers "In1.Cu" "In2.Cu")
		(hatch none 0.5)
		(connect_pads
			(clearance 0)
		)
		(min_thickness 0.25)
		(keepout
			(tracks not_allowed)
			(vias allowed)
			(pads allowed)
			(copperpour not_allowed)
			(footprints allowed)
		)
		(placement
			(enabled no)
			(sheetname "")
		)
		(fill yes
			(thermal_gap 0.5)
			(thermal_bridge_width 0.5)
			(island_removal_mode 0)
		)
		(polygon
			(pts
				(xy 223.196658 -78.843886) (xy 223.196658 -80.735932) (xy 225.203258 -80.735932) (xy 225.203258 -78.84414)
				(xy 225.203004 -78.843886)
			)
		)
	)
	(zone
		(layers "In1.Cu" "In2.Cu")
		(hatch none 0.5)
		(connect_pads
			(clearance 0)
		)
		(min_thickness 0.25)
		(keepout
			(tracks not_allowed)
			(vias allowed)
			(pads allowed)
			(copperpour not_allowed)
			(footprints allowed)
		)
		(placement
			(enabled no)
			(sheetname "")
		)
		(fill yes
			(thermal_gap 0.5)
			(thermal_bridge_width 0.5)
			(island_removal_mode 0)
		)
		(polygon
			(pts
				(xy 223.196658 -478.844102) (xy 223.196658 -480.736148) (xy 225.203258 -480.736148) (xy 225.203258 -478.844356)
				(xy 225.203004 -478.844102)
			)
		)
	)
	(zone
		(layers "In1.Cu" "In2.Cu")
		(hatch none 0.5)
		(connect_pads
			(clearance 0)
		)
		(min_thickness 0.25)
		(keepout
			(tracks not_allowed)
			(vias allowed)
			(pads allowed)
			(copperpour not_allowed)
			(footprints allowed)
		)
		(placement
			(enabled no)
			(sheetname "")
		)
		(fill yes
			(thermal_gap 0.5)
			(thermal_bridge_width 0.5)
			(island_removal_mode 0)
		)
		(polygon
			(pts
				(xy 38.196774 -365.444024) (xy 38.196774 -367.33607) (xy 40.203374 -367.33607) (xy 40.203374 -365.444278)
				(xy 40.20312 -365.444024)
			)
		)
	)
	(zone
		(layers "In1.Cu" "In2.Cu")
		(hatch none 0.5)
		(connect_pads
			(clearance 0)
		)
		(min_thickness 0.25)
		(keepout
			(tracks not_allowed)
			(vias allowed)
			(pads allowed)
			(copperpour not_allowed)
			(footprints allowed)
		)
		(placement
			(enabled no)
			(sheetname "")
		)
		(fill yes
			(thermal_gap 0.5)
			(thermal_bridge_width 0.5)
			(island_removal_mode 0)
		)
		(polygon
			(pts
				(xy 38.196774 -363.043978) (xy 38.196774 -364.936278) (xy 40.203374 -364.936278) (xy 40.203374 -363.044232)
				(xy 40.20312 -363.043978)
			)
		)
	)
	(zone
		(layers "In1.Cu" "In2.Cu")
		(hatch none 0.5)
		(connect_pads
			(clearance 0)
		)
		(min_thickness 0.25)
		(keepout
			(tracks not_allowed)
			(vias allowed)
			(pads allowed)
			(copperpour not_allowed)
			(footprints allowed)
		)
		(placement
			(enabled no)
			(sheetname "")
		)
		(fill yes
			(thermal_gap 0.5)
			(thermal_bridge_width 0.5)
			(island_removal_mode 0)
		)
		(polygon
			(pts
				(xy 223.196658 -181.843934) (xy 223.196658 -183.73598) (xy 225.203258 -183.73598) (xy 225.203258 -181.844188)
				(xy 225.203004 -181.843934)
			)
		)
	)
	(zone
		(layers "In1.Cu" "In2.Cu")
		(hatch none 0.5)
		(connect_pads
			(clearance 0)
		)
		(min_thickness 0.25)
		(keepout
			(tracks not_allowed)
			(vias allowed)
			(pads allowed)
			(copperpour not_allowed)
			(footprints allowed)
		)
		(placement
			(enabled no)
			(sheetname "")
		)
		(fill yes
			(thermal_gap 0.5)
			(thermal_bridge_width 0.5)
			(island_removal_mode 0)
		)
		(polygon
			(pts
				(xy 38.196774 -284.843982) (xy 38.196774 -286.736028) (xy 40.203374 -286.736028) (xy 40.203374 -284.844236)
				(xy 40.20312 -284.843982)
			)
		)
	)
	(zone
		(layers "In1.Cu" "In2.Cu")
		(hatch none 0.5)
		(connect_pads
			(clearance 0)
		)
		(min_thickness 0.25)
		(keepout
			(tracks not_allowed)
			(vias allowed)
			(pads allowed)
			(copperpour not_allowed)
			(footprints allowed)
		)
		(placement
			(enabled no)
			(sheetname "")
		)
		(fill yes
			(thermal_gap 0.5)
			(thermal_bridge_width 0.5)
			(island_removal_mode 0)
		)
		(polygon
			(pts
				(xy 23.803356 -127.756158) (xy 23.803356 -125.863858) (xy 21.796756 -125.863858) (xy 21.796756 -127.755904)
				(xy 21.79701 -127.756158)
			)
		)
	)
	(zone
		(layers "In1.Cu" "In2.Cu")
		(hatch none 0.5)
		(connect_pads
			(clearance 0)
		)
		(min_thickness 0.25)
		(keepout
			(tracks not_allowed)
			(vias allowed)
			(pads allowed)
			(copperpour not_allowed)
			(footprints allowed)
		)
		(placement
			(enabled no)
			(sheetname "")
		)
		(fill yes
			(thermal_gap 0.5)
			(thermal_bridge_width 0.5)
			(island_removal_mode 0)
		)
		(polygon
			(pts
				(xy 223.196658 -365.444024) (xy 223.196658 -367.33607) (xy 225.203258 -367.33607) (xy 225.203258 -365.444278)
				(xy 225.203004 -365.444024)
			)
		)
	)
	(zone
		(layers "In1.Cu" "In2.Cu")
		(hatch none 0.5)
		(connect_pads
			(clearance 0)
		)
		(min_thickness 0.25)
		(keepout
			(tracks not_allowed)
			(vias allowed)
			(pads allowed)
			(copperpour not_allowed)
			(footprints allowed)
		)
		(placement
			(enabled no)
			(sheetname "")
		)
		(fill yes
			(thermal_gap 0.5)
			(thermal_bridge_width 0.5)
			(island_removal_mode 0)
		)
		(polygon
			(pts
				(xy 223.196658 -54.043834) (xy 223.196658 -55.936134) (xy 225.203258 -55.936134) (xy 225.203258 -54.044088)
				(xy 225.203004 -54.043834)
			)
		)
	)
	(zone
		(layers "In1.Cu" "In2.Cu")
		(hatch none 0.5)
		(connect_pads
			(clearance 0)
		)
		(min_thickness 0.25)
		(keepout
			(tracks not_allowed)
			(vias allowed)
			(pads allowed)
			(copperpour not_allowed)
			(footprints allowed)
		)
		(placement
			(enabled no)
			(sheetname "")
		)
		(fill yes
			(thermal_gap 0.5)
			(thermal_bridge_width 0.5)
			(island_removal_mode 0)
		)
		(polygon
			(pts
				(xy 91.07678 -96.59239) (xy 89.88806 -96.59239) (xy 89.88806 -97.76079) (xy 91.07678 -97.76079)
			)
		)
	)
	(zone
		(layers "In1.Cu" "In2.Cu")
		(hatch none 0.5)
		(connect_pads
			(clearance 0)
		)
		(min_thickness 0.25)
		(keepout
			(tracks not_allowed)
			(vias allowed)
			(pads allowed)
			(copperpour not_allowed)
			(footprints allowed)
		)
		(placement
			(enabled no)
			(sheetname "")
		)
		(fill yes
			(thermal_gap 0.5)
			(thermal_bridge_width 0.5)
			(island_removal_mode 0)
		)
		(polygon
			(pts
				(xy 38.196774 -468.444072) (xy 38.196774 -470.336118) (xy 40.203374 -470.336118) (xy 40.203374 -468.444326)
				(xy 40.20312 -468.444072)
			)
		)
	)
	(zone
		(layers "In1.Cu" "In2.Cu")
		(hatch none 0.5)
		(connect_pads
			(clearance 0)
		)
		(min_thickness 0.25)
		(keepout
			(tracks not_allowed)
			(vias allowed)
			(pads allowed)
			(copperpour not_allowed)
			(footprints allowed)
		)
		(placement
			(enabled no)
			(sheetname "")
		)
		(fill yes
			(thermal_gap 0.5)
			(thermal_bridge_width 0.5)
			(island_removal_mode 0)
		)
		(polygon
			(pts
				(xy 23.803356 -120.55602) (xy 23.803356 -118.66372) (xy 21.796756 -118.66372) (xy 21.796756 -120.555766)
				(xy 21.79701 -120.55602)
			)
		)
	)
	(zone
		(layers "In1.Cu" "In2.Cu")
		(hatch none 0.5)
		(connect_pads
			(clearance 0)
		)
		(min_thickness 0.25)
		(keepout
			(tracks not_allowed)
			(vias allowed)
			(pads allowed)
			(copperpour not_allowed)
			(footprints allowed)
		)
		(placement
			(enabled no)
			(sheetname "")
		)
		(fill yes
			(thermal_gap 0.5)
			(thermal_bridge_width 0.5)
			(island_removal_mode 0)
		)
		(polygon
			(pts
				(xy 226.386644 -369.043966) (xy 226.386644 -370.936266) (xy 228.393244 -370.936266) (xy 228.393244 -369.04422)
				(xy 228.39299 -369.043966)
			)
		)
	)
	(zone
		(layers "In1.Cu" "In2.Cu")
		(hatch none 0.5)
		(connect_pads
			(clearance 0)
		)
		(min_thickness 0.25)
		(keepout
			(tracks not_allowed)
			(vias allowed)
			(pads allowed)
			(copperpour not_allowed)
			(footprints allowed)
		)
		(placement
			(enabled no)
			(sheetname "")
		)
		(fill yes
			(thermal_gap 0.5)
			(thermal_bridge_width 0.5)
			(island_removal_mode 0)
		)
		(polygon
			(pts
				(xy 23.803356 -125.356112) (xy 23.803356 -123.463812) (xy 21.796756 -123.463812) (xy 21.796756 -125.355858)
				(xy 21.79701 -125.356112)
			)
		)
	)
	(zone
		(layers "In1.Cu" "In2.Cu")
		(hatch none 0.5)
		(connect_pads
			(clearance 0)
		)
		(min_thickness 0.25)
		(keepout
			(tracks not_allowed)
			(vias allowed)
			(pads allowed)
			(copperpour not_allowed)
			(footprints allowed)
		)
		(placement
			(enabled no)
			(sheetname "")
		)
		(fill yes
			(thermal_gap 0.5)
			(thermal_bridge_width 0.5)
			(island_removal_mode 0)
		)
		(polygon
			(pts
				(xy 223.196658 -76.44384) (xy 223.196658 -78.33614) (xy 225.203258 -78.33614) (xy 225.203258 -76.444094)
				(xy 225.203004 -76.44384)
			)
		)
	)
	(zone
		(layers "In1.Cu" "In2.Cu")
		(hatch none 0.5)
		(connect_pads
			(clearance 0)
		)
		(min_thickness 0.25)
		(keepout
			(tracks not_allowed)
			(vias allowed)
			(pads allowed)
			(copperpour not_allowed)
			(footprints allowed)
		)
		(placement
			(enabled no)
			(sheetname "")
		)
		(fill yes
			(thermal_gap 0.5)
			(thermal_bridge_width 0.5)
			(island_removal_mode 0)
		)
		(polygon
			(pts
				(xy 38.196774 -378.243846) (xy 38.196774 -380.136146) (xy 40.203374 -380.136146) (xy 40.203374 -378.2441)
				(xy 40.20312 -378.243846)
			)
		)
	)
	(zone
		(layers "In1.Cu" "In2.Cu")
		(hatch none 0.5)
		(connect_pads
			(clearance 0)
		)
		(min_thickness 0.25)
		(keepout
			(tracks not_allowed)
			(vias allowed)
			(pads allowed)
			(copperpour not_allowed)
			(footprints allowed)
		)
		(placement
			(enabled no)
			(sheetname "")
		)
		(fill yes
			(thermal_gap 0.5)
			(thermal_bridge_width 0.5)
			(island_removal_mode 0)
		)
		(polygon
			(pts
				(xy 223.196658 -66.84391) (xy 223.196658 -68.735956) (xy 225.203258 -68.735956) (xy 225.203258 -66.844164)
				(xy 225.203004 -66.84391)
			)
		)
	)
	(zone
		(layers "In1.Cu" "In2.Cu")
		(hatch none 0.5)
		(connect_pads
			(clearance 0)
		)
		(min_thickness 0.25)
		(keepout
			(tracks not_allowed)
			(vias allowed)
			(pads allowed)
			(copperpour not_allowed)
			(footprints allowed)
		)
		(placement
			(enabled no)
			(sheetname "")
		)
		(fill yes
			(thermal_gap 0.5)
			(thermal_bridge_width 0.5)
			(island_removal_mode 0)
		)
		(polygon
			(pts
				(xy 23.803356 -221.156022) (xy 23.803356 -219.263722) (xy 21.796756 -219.263722) (xy 21.796756 -221.155768)
				(xy 21.79701 -221.156022)
			)
		)
	)
	(zone
		(layers "In1.Cu" "In2.Cu")
		(hatch none 0.5)
		(connect_pads
			(clearance 0)
		)
		(min_thickness 0.25)
		(keepout
			(tracks not_allowed)
			(vias allowed)
			(pads allowed)
			(copperpour not_allowed)
			(footprints allowed)
		)
		(placement
			(enabled no)
			(sheetname "")
		)
		(fill yes
			(thermal_gap 0.5)
			(thermal_bridge_width 0.5)
			(island_removal_mode 0)
		)
		(polygon
			(pts
				(xy 23.803356 -37.555932) (xy 23.803356 -35.663886) (xy 21.796756 -35.663886) (xy 21.796756 -37.555678)
				(xy 21.79701 -37.555932)
			)
		)
	)
	(zone
		(layers "In1.Cu" "In2.Cu")
		(hatch none 0.5)
		(connect_pads
			(clearance 0)
		)
		(min_thickness 0.25)
		(keepout
			(tracks not_allowed)
			(vias allowed)
			(pads allowed)
			(copperpour not_allowed)
			(footprints allowed)
		)
		(placement
			(enabled no)
			(sheetname "")
		)
		(fill yes
			(thermal_gap 0.5)
			(thermal_bridge_width 0.5)
			(island_removal_mode 0)
		)
		(polygon
			(pts
				(xy 223.196658 -282.443936) (xy 223.196658 -284.336236) (xy 225.203258 -284.336236) (xy 225.203258 -282.44419)
				(xy 225.203004 -282.443936)
			)
		)
	)
	(zone
		(layers "In1.Cu" "In2.Cu")
		(hatch none 0.5)
		(connect_pads
			(clearance 0)
		)
		(min_thickness 0.25)
		(keepout
			(tracks not_allowed)
			(vias allowed)
			(pads allowed)
			(copperpour not_allowed)
			(footprints allowed)
		)
		(placement
			(enabled no)
			(sheetname "")
		)
		(fill yes
			(thermal_gap 0.5)
			(thermal_bridge_width 0.5)
			(island_removal_mode 0)
		)
		(polygon
			(pts
				(xy 23.803356 -24.75611) (xy 23.803356 -22.86381) (xy 21.796756 -22.86381) (xy 21.796756 -24.755856)
				(xy 21.79701 -24.75611)
			)
		)
	)
	(zone
		(layers "In1.Cu" "In2.Cu")
		(hatch none 0.5)
		(connect_pads
			(clearance 0)
		)
		(min_thickness 0.25)
		(keepout
			(tracks not_allowed)
			(vias allowed)
			(pads allowed)
			(copperpour not_allowed)
			(footprints allowed)
		)
		(placement
			(enabled no)
			(sheetname "")
		)
		(fill yes
			(thermal_gap 0.5)
			(thermal_bridge_width 0.5)
			(island_removal_mode 0)
		)
		(polygon
			(pts
				(xy 38.196774 -159.443928) (xy 38.196774 -161.335974) (xy 40.203374 -161.335974) (xy 40.203374 -159.444182)
				(xy 40.20312 -159.443928)
			)
		)
	)
	(zone
		(layers "In1.Cu" "In2.Cu")
		(hatch none 0.5)
		(connect_pads
			(clearance 0)
		)
		(min_thickness 0.25)
		(keepout
			(tracks not_allowed)
			(vias allowed)
			(pads allowed)
			(copperpour not_allowed)
			(footprints allowed)
		)
		(placement
			(enabled no)
			(sheetname "")
		)
		(fill yes
			(thermal_gap 0.5)
			(thermal_bridge_width 0.5)
			(island_removal_mode 0)
		)
		(polygon
			(pts
				(xy 23.803356 -449.556124) (xy 23.803356 -447.664078) (xy 21.796756 -447.664078) (xy 21.796756 -449.55587)
				(xy 21.79701 -449.556124)
			)
		)
	)
	(zone
		(layers "In1.Cu" "In2.Cu")
		(hatch none 0.5)
		(connect_pads
			(clearance 0)
		)
		(min_thickness 0.25)
		(keepout
			(tracks not_allowed)
			(vias allowed)
			(pads allowed)
			(copperpour not_allowed)
			(footprints allowed)
		)
		(placement
			(enabled no)
			(sheetname "")
		)
		(fill yes
			(thermal_gap 0.5)
			(thermal_bridge_width 0.5)
			(island_removal_mode 0)
		)
		(polygon
			(pts
				(xy 38.196774 -177.043842) (xy 38.196774 -178.936142) (xy 40.203374 -178.936142) (xy 40.203374 -177.044096)
				(xy 40.20312 -177.043842)
			)
		)
	)
	(zone
		(layers "In1.Cu" "In2.Cu")
		(hatch none 0.5)
		(connect_pads
			(clearance 0)
		)
		(min_thickness 0.25)
		(keepout
			(tracks not_allowed)
			(vias allowed)
			(pads allowed)
			(copperpour not_allowed)
			(footprints allowed)
		)
		(placement
			(enabled no)
			(sheetname "")
		)
		(fill yes
			(thermal_gap 0.5)
			(thermal_bridge_width 0.5)
			(island_removal_mode 0)
		)
		(polygon
			(pts
				(xy 20.61337 -445.956182) (xy 20.61337 -444.063882) (xy 18.60677 -444.063882) (xy 18.60677 -445.955928)
				(xy 18.607024 -445.956182)
			)
		)
	)
	(zone
		(layers "In1.Cu" "In2.Cu")
		(hatch none 0.5)
		(connect_pads
			(clearance 0)
		)
		(min_thickness 0.25)
		(keepout
			(tracks not_allowed)
			(vias allowed)
			(pads allowed)
			(copperpour not_allowed)
			(footprints allowed)
		)
		(placement
			(enabled no)
			(sheetname "")
		)
		(fill yes
			(thermal_gap 0.5)
			(thermal_bridge_width 0.5)
			(island_removal_mode 0)
		)
		(polygon
			(pts
				(xy 20.61337 -136.956038) (xy 20.61337 -135.063738) (xy 18.60677 -135.063738) (xy 18.60677 -136.955784)
				(xy 18.607024 -136.956038)
			)
		)
	)
	(zone
		(layers "In1.Cu" "In2.Cu")
		(hatch none 0.5)
		(connect_pads
			(clearance 0)
		)
		(min_thickness 0.25)
		(keepout
			(tracks not_allowed)
			(vias allowed)
			(pads allowed)
			(copperpour not_allowed)
			(footprints allowed)
		)
		(placement
			(enabled no)
			(sheetname "")
		)
		(fill yes
			(thermal_gap 0.5)
			(thermal_bridge_width 0.5)
			(island_removal_mode 0)
		)
		(polygon
			(pts
				(xy 223.196658 -463.64398) (xy 223.196658 -465.53628) (xy 225.203258 -465.53628) (xy 225.203258 -463.644234)
				(xy 225.203004 -463.64398)
			)
		)
	)
	(zone
		(layers "In1.Cu" "In2.Cu" "In3.Cu" "In4.Cu" "In5.Cu" "In6.Cu")
		(hatch none 0.5)
		(connect_pads
			(clearance 0)
		)
		(min_thickness 0.25)
		(keepout
			(tracks not_allowed)
			(vias allowed)
			(pads allowed)
			(copperpour not_allowed)
			(footprints allowed)
		)
		(placement
			(enabled no)
			(sheetname "")
		)
		(fill yes
			(thermal_gap 0.5)
			(thermal_bridge_width 0.5)
			(island_removal_mode 0)
		)
		(polygon
			(pts
				(xy -0.127 -151.638) (xy 3.494532 -151.638) (xy 3.494532 -234.696) (xy -0.127 -234.696)
			)
		)
	)
	(zone
		(layers "In1.Cu" "In2.Cu" "In3.Cu" "In4.Cu" "In5.Cu" "In6.Cu")
		(hatch none 0.5)
		(connect_pads
			(clearance 0)
		)
		(min_thickness 0.25)
		(keepout
			(tracks not_allowed)
			(vias allowed)
			(pads allowed)
			(copperpour not_allowed)
			(footprints allowed)
		)
		(placement
			(enabled no)
			(sheetname "")
		)
		(fill yes
			(thermal_gap 0.5)
			(thermal_bridge_width 0.5)
			(island_removal_mode 0)
		)
		(polygon
			(pts
				(arc
					(start 73.50506 -378.498608)
					(mid 63.49746 -378.498608)
					(end 73.50506 -378.498608)
				)
			)
		)
	)
	(zone
		(layers "In1.Cu" "In2.Cu" "In3.Cu" "In4.Cu" "In5.Cu" "In6.Cu")
		(hatch none 0.5)
		(connect_pads
			(clearance 0)
		)
		(min_thickness 0.25)
		(keepout
			(tracks not_allowed)
			(vias allowed)
			(pads allowed)
			(copperpour not_allowed)
			(footprints allowed)
		)
		(placement
			(enabled no)
			(sheetname "")
		)
		(fill yes
			(thermal_gap 0.5)
			(thermal_bridge_width 0.5)
			(island_removal_mode 0)
		)
		(polygon
			(pts
				(xy -0.127 -277.622) (xy 3.494532 -277.622) (xy 3.494532 -360.68) (xy -0.127 -360.68)
			)
		)
	)
	(zone
		(layers "In1.Cu" "In2.Cu" "In3.Cu" "In4.Cu" "In5.Cu" "In6.Cu")
		(hatch none 0.5)
		(connect_pads
			(clearance 0)
		)
		(min_thickness 0.25)
		(keepout
			(tracks not_allowed)
			(vias allowed)
			(pads allowed)
			(copperpour not_allowed)
			(footprints allowed)
		)
		(placement
			(enabled no)
			(sheetname "")
		)
		(fill yes
			(thermal_gap 0.5)
			(thermal_bridge_width 0.5)
			(island_removal_mode 0)
		)
		(polygon
			(pts
				(arc
					(start 13.504926 -261.498842)
					(mid 3.497326 -261.498842)
					(end 13.504926 -261.498842)
				)
			)
		)
	)
	(zone
		(layers "In1.Cu" "In2.Cu" "In3.Cu" "In4.Cu" "In5.Cu" "In6.Cu")
		(hatch none 0.5)
		(connect_pads
			(clearance 0)
		)
		(min_thickness 0.25)
		(keepout
			(tracks not_allowed)
			(vias allowed)
			(pads allowed)
			(copperpour not_allowed)
			(footprints allowed)
		)
		(placement
			(enabled no)
			(sheetname "")
		)
		(fill yes
			(thermal_gap 0.5)
			(thermal_bridge_width 0.5)
			(island_removal_mode 0)
		)
		(polygon
			(pts
				(xy -0.127 -383.667) (xy 3.494532 -383.667) (xy 3.494532 -466.852) (xy -0.127 -466.852)
			)
		)
	)
	(zone
		(layers "In1.Cu" "In3.Cu" "In4.Cu" "In6.Cu")
		(hatch none 0.5)
		(connect_pads
			(clearance 0)
		)
		(min_thickness 0.25)
		(keepout
			(tracks not_allowed)
			(vias allowed)
			(pads allowed)
			(copperpour not_allowed)
			(footprints allowed)
		)
		(placement
			(enabled no)
			(sheetname "")
		)
		(fill yes
			(thermal_gap 0.5)
			(thermal_bridge_width 0.5)
			(island_removal_mode 0)
		)
		(polygon
			(pts
				(arc
					(start 5.59054 -296.335704)
					(mid 5.080127 -295.82491)
					(end 4.56946 -296.33545)
				)
				(arc
					(start 4.56946 -297.14825)
					(mid 5.08 -297.65879)
					(end 5.59054 -297.14825)
				)
			)
		)
	)
	(zone
		(layers "In1.Cu" "In3.Cu" "In4.Cu" "In6.Cu")
		(hatch none 0.5)
		(connect_pads
			(clearance 0)
		)
		(min_thickness 0.25)
		(keepout
			(tracks not_allowed)
			(vias allowed)
			(pads allowed)
			(copperpour not_allowed)
			(footprints allowed)
		)
		(placement
			(enabled no)
			(sheetname "")
		)
		(fill yes
			(thermal_gap 0.5)
			(thermal_bridge_width 0.5)
			(island_removal_mode 0)
		)
		(polygon
			(pts
				(arc
					(start 35.84067 -67.383914)
					(mid 35.330257 -66.87312)
					(end 34.81959 -67.38366)
				)
				(arc
					(start 34.81959 -68.19646)
					(mid 35.33013 -68.707)
					(end 35.84067 -68.19646)
				)
			)
		)
	)
	(zone
		(layers "In1.Cu" "In3.Cu" "In4.Cu" "In6.Cu")
		(hatch none 0.5)
		(connect_pads
			(clearance 0)
		)
		(min_thickness 0.25)
		(keepout
			(tracks not_allowed)
			(vias allowed)
			(pads allowed)
			(copperpour not_allowed)
			(footprints allowed)
		)
		(placement
			(enabled no)
			(sheetname "")
		)
		(fill yes
			(thermal_gap 0.5)
			(thermal_bridge_width 0.5)
			(island_removal_mode 0)
		)
		(polygon
			(pts
				(arc
					(start 6.481826 -443.996826)
					(mid 6.992239 -444.50762)
					(end 7.502906 -443.99708)
				)
				(arc
					(start 7.502906 -443.18428)
					(mid 6.992366 -442.67374)
					(end 6.481826 -443.18428)
				)
			)
		)
	)
	(zone
		(layers "In1.Cu" "In3.Cu" "In4.Cu" "In6.Cu")
		(hatch none 0.5)
		(connect_pads
			(clearance 0)
		)
		(min_thickness 0.25)
		(keepout
			(tracks not_allowed)
			(vias allowed)
			(pads allowed)
			(copperpour not_allowed)
			(footprints allowed)
		)
		(placement
			(enabled no)
			(sheetname "")
		)
		(fill yes
			(thermal_gap 0.5)
			(thermal_bridge_width 0.5)
			(island_removal_mode 0)
		)
		(polygon
			(pts
				(arc
					(start 35.84067 -385.983988)
					(mid 35.330257 -385.473194)
					(end 34.81959 -385.983734)
				)
				(arc
					(start 34.81959 -386.796534)
					(mid 35.33013 -387.307074)
					(end 35.84067 -386.796534)
				)
			)
		)
	)
	(zone
		(layers "In1.Cu" "In3.Cu" "In4.Cu" "In6.Cu")
		(hatch none 0.5)
		(connect_pads
			(clearance 0)
		)
		(min_thickness 0.25)
		(keepout
			(tracks not_allowed)
			(vias allowed)
			(pads allowed)
			(copperpour not_allowed)
			(footprints allowed)
		)
		(placement
			(enabled no)
			(sheetname "")
		)
		(fill yes
			(thermal_gap 0.5)
			(thermal_bridge_width 0.5)
			(island_removal_mode 0)
		)
		(polygon
			(pts
				(arc
					(start 7.502906 -201.536046)
					(mid 6.992493 -201.025252)
					(end 6.481826 -201.535792)
				)
				(arc
					(start 6.481826 -202.348592)
					(mid 6.992366 -202.859132)
					(end 7.502906 -202.348592)
				)
			)
		)
	)
	(zone
		(layers "In1.Cu" "In3.Cu" "In4.Cu" "In6.Cu")
		(hatch none 0.5)
		(connect_pads
			(clearance 0)
		)
		(min_thickness 0.25)
		(keepout
			(tracks not_allowed)
			(vias allowed)
			(pads allowed)
			(copperpour not_allowed)
			(footprints allowed)
		)
		(placement
			(enabled no)
			(sheetname "")
		)
		(fill yes
			(thermal_gap 0.5)
			(thermal_bridge_width 0.5)
			(island_removal_mode 0)
		)
		(polygon
			(pts
				(arc
					(start 5.59054 -293.135558)
					(mid 5.080127 -292.624764)
					(end 4.56946 -293.135304)
				)
				(arc
					(start 4.56946 -293.948104)
					(mid 5.08 -294.458644)
					(end 5.59054 -293.948104)
				)
			)
		)
	)
	(zone
		(layers "In1.Cu" "In3.Cu" "In4.Cu" "In6.Cu")
		(hatch none 0.5)
		(connect_pads
			(clearance 0)
		)
		(min_thickness 0.25)
		(keepout
			(tracks not_allowed)
			(vias allowed)
			(pads allowed)
			(copperpour not_allowed)
			(footprints allowed)
		)
		(placement
			(enabled no)
			(sheetname "")
		)
		(fill yes
			(thermal_gap 0.5)
			(thermal_bridge_width 0.5)
			(island_removal_mode 0)
		)
		(polygon
			(pts
				(arc
					(start 25.88514 -435.251606)
					(mid 25.273127 -434.639212)
					(end 24.66086 -435.251352)
				)
				(arc
					(start 24.66086 -436.368952)
					(mid 25.273 -436.981092)
					(end 25.88514 -436.368952)
				)
			)
		)
	)
	(zone
		(layers "In1.Cu" "In3.Cu" "In4.Cu" "In6.Cu")
		(hatch none 0.5)
		(connect_pads
			(clearance 0)
		)
		(min_thickness 0.25)
		(keepout
			(tracks not_allowed)
			(vias allowed)
			(pads allowed)
			(copperpour not_allowed)
			(footprints allowed)
		)
		(placement
			(enabled no)
			(sheetname "")
		)
		(fill yes
			(thermal_gap 0.5)
			(thermal_bridge_width 0.5)
			(island_removal_mode 0)
		)
		(polygon
			(pts
				(arc
					(start 222.339154 -177.431446)
					(mid 221.727141 -176.819052)
					(end 221.114874 -177.431192)
				)
				(arc
					(start 221.114874 -178.548792)
					(mid 221.727014 -179.160932)
					(end 222.339154 -178.548792)
				)
			)
		)
	)
	(zone
		(layers "In1.Cu" "In3.Cu" "In4.Cu" "In6.Cu")
		(hatch none 0.5)
		(connect_pads
			(clearance 0)
		)
		(min_thickness 0.25)
		(keepout
			(tracks not_allowed)
			(vias allowed)
			(pads allowed)
			(copperpour not_allowed)
			(footprints allowed)
		)
		(placement
			(enabled no)
			(sheetname "")
		)
		(fill yes
			(thermal_gap 0.5)
			(thermal_bridge_width 0.5)
			(island_removal_mode 0)
		)
		(polygon
			(pts
				(arc
					(start 7.502906 -396.736062)
					(mid 6.992493 -396.225268)
					(end 6.481826 -396.735808)
				)
				(arc
					(start 6.481826 -397.548608)
					(mid 6.992366 -398.059148)
					(end 7.502906 -397.548608)
				)
			)
		)
	)
	(zone
		(layers "In1.Cu" "In3.Cu" "In4.Cu" "In6.Cu")
		(hatch none 0.5)
		(connect_pads
			(clearance 0)
		)
		(min_thickness 0.25)
		(keepout
			(tracks not_allowed)
			(vias allowed)
			(pads allowed)
			(copperpour not_allowed)
			(footprints allowed)
		)
		(placement
			(enabled no)
			(sheetname "")
		)
		(fill yes
			(thermal_gap 0.5)
			(thermal_bridge_width 0.5)
			(island_removal_mode 0)
		)
		(polygon
			(pts
				(arc
					(start 6.481826 -311.548526)
					(mid 6.992239 -312.05932)
					(end 7.502906 -311.54878)
				)
				(arc
					(start 7.502906 -310.73598)
					(mid 6.992366 -310.22544)
					(end 6.481826 -310.73598)
				)
			)
		)
	)
	(zone
		(layers "In1.Cu" "In3.Cu" "In4.Cu" "In6.Cu")
		(hatch none 0.5)
		(connect_pads
			(clearance 0)
		)
		(min_thickness 0.25)
		(keepout
			(tracks not_allowed)
			(vias allowed)
			(pads allowed)
			(copperpour not_allowed)
			(footprints allowed)
		)
		(placement
			(enabled no)
			(sheetname "")
		)
		(fill yes
			(thermal_gap 0.5)
			(thermal_bridge_width 0.5)
			(island_removal_mode 0)
		)
		(polygon
			(pts
				(arc
					(start 220.840554 -157.583886)
					(mid 220.330141 -157.073092)
					(end 219.819474 -157.583632)
				)
				(arc
					(start 219.819474 -158.396432)
					(mid 220.330014 -158.906972)
					(end 220.840554 -158.396432)
				)
			)
		)
	)
	(zone
		(layers "In1.Cu" "In3.Cu" "In4.Cu" "In6.Cu")
		(hatch none 0.5)
		(connect_pads
			(clearance 0)
		)
		(min_thickness 0.25)
		(keepout
			(tracks not_allowed)
			(vias allowed)
			(pads allowed)
			(copperpour not_allowed)
			(footprints allowed)
		)
		(placement
			(enabled no)
			(sheetname "")
		)
		(fill yes
			(thermal_gap 0.5)
			(thermal_bridge_width 0.5)
			(island_removal_mode 0)
		)
		(polygon
			(pts
				(arc
					(start 5.59054 -395.135354)
					(mid 5.080127 -394.62456)
					(end 4.56946 -395.1351)
				)
				(arc
					(start 4.56946 -395.9479)
					(mid 5.08 -396.45844)
					(end 5.59054 -395.9479)
				)
			)
		)
	)
	(zone
		(layers "In1.Cu" "In3.Cu" "In4.Cu" "In6.Cu")
		(hatch none 0.5)
		(connect_pads
			(clearance 0)
		)
		(min_thickness 0.25)
		(keepout
			(tracks not_allowed)
			(vias allowed)
			(pads allowed)
			(copperpour not_allowed)
			(footprints allowed)
		)
		(placement
			(enabled no)
			(sheetname "")
		)
		(fill yes
			(thermal_gap 0.5)
			(thermal_bridge_width 0.5)
			(island_removal_mode 0)
		)
		(polygon
			(pts
				(arc
					(start 7.502906 -337.187032)
					(mid 6.992493 -336.676238)
					(end 6.481826 -337.186778)
				)
				(arc
					(start 6.481826 -337.999578)
					(mid 6.992366 -338.510118)
					(end 7.502906 -337.999578)
				)
			)
		)
	)
	(zone
		(layers "In1.Cu" "In3.Cu" "In4.Cu" "In6.Cu")
		(hatch none 0.5)
		(connect_pads
			(clearance 0)
		)
		(min_thickness 0.25)
		(keepout
			(tracks not_allowed)
			(vias allowed)
			(pads allowed)
			(copperpour not_allowed)
			(footprints allowed)
		)
		(placement
			(enabled no)
			(sheetname "")
		)
		(fill yes
			(thermal_gap 0.5)
			(thermal_bridge_width 0.5)
			(island_removal_mode 0)
		)
		(polygon
			(pts
				(arc
					(start 222.339154 -56.831484)
					(mid 221.727141 -56.21909)
					(end 221.114874 -56.83123)
				)
				(arc
					(start 221.114874 -57.94883)
					(mid 221.727014 -58.56097)
					(end 222.339154 -57.94883)
				)
			)
		)
	)
	(zone
		(layers "In1.Cu" "In3.Cu" "In4.Cu" "In6.Cu")
		(hatch none 0.5)
		(connect_pads
			(clearance 0)
		)
		(min_thickness 0.25)
		(keepout
			(tracks not_allowed)
			(vias allowed)
			(pads allowed)
			(copperpour not_allowed)
			(footprints allowed)
		)
		(placement
			(enabled no)
			(sheetname "")
		)
		(fill yes
			(thermal_gap 0.5)
			(thermal_bridge_width 0.5)
			(island_removal_mode 0)
		)
		(polygon
			(pts
				(arc
					(start 37.33927 -159.831532)
					(mid 36.727257 -159.219138)
					(end 36.11499 -159.831278)
				)
				(arc
					(start 36.11499 -160.948878)
					(mid 36.72713 -161.561018)
					(end 37.33927 -160.948878)
				)
			)
		)
	)
	(zone
		(layers "In1.Cu" "In3.Cu" "In4.Cu" "In6.Cu")
		(hatch none 0.5)
		(connect_pads
			(clearance 0)
		)
		(min_thickness 0.25)
		(keepout
			(tracks not_allowed)
			(vias allowed)
			(pads allowed)
			(copperpour not_allowed)
			(footprints allowed)
		)
		(placement
			(enabled no)
			(sheetname "")
		)
		(fill yes
			(thermal_gap 0.5)
			(thermal_bridge_width 0.5)
			(island_removal_mode 0)
		)
		(polygon
			(pts
				(arc
					(start 25.88514 -13.67663)
					(mid 25.273127 -13.064236)
					(end 24.66086 -13.676376)
				)
				(arc
					(start 24.66086 -14.793976)
					(mid 25.273 -15.406116)
					(end 25.88514 -14.793976)
				)
			)
		)
	)
	(zone
		(layers "In1.Cu" "In3.Cu" "In4.Cu" "In6.Cu")
		(hatch none 0.5)
		(connect_pads
			(clearance 0)
		)
		(min_thickness 0.25)
		(keepout
			(tracks not_allowed)
			(vias allowed)
			(pads allowed)
			(copperpour not_allowed)
			(footprints allowed)
		)
		(placement
			(enabled no)
			(sheetname "")
		)
		(fill yes
			(thermal_gap 0.5)
			(thermal_bridge_width 0.5)
			(island_removal_mode 0)
		)
		(polygon
			(pts
				(arc
					(start 35.84067 -376.384058)
					(mid 35.330257 -375.873264)
					(end 34.81959 -376.383804)
				)
				(arc
					(start 34.81959 -377.196604)
					(mid 35.33013 -377.707144)
					(end 35.84067 -377.196604)
				)
			)
		)
	)
	(zone
		(layers "In1.Cu" "In3.Cu" "In4.Cu" "In6.Cu")
		(hatch none 0.5)
		(connect_pads
			(clearance 0)
		)
		(min_thickness 0.25)
		(keepout
			(tracks not_allowed)
			(vias allowed)
			(pads allowed)
			(copperpour not_allowed)
			(footprints allowed)
		)
		(placement
			(enabled no)
			(sheetname "")
		)
		(fill yes
			(thermal_gap 0.5)
			(thermal_bridge_width 0.5)
			(island_removal_mode 0)
		)
		(polygon
			(pts
				(arc
					(start 7.502906 -162.387026)
					(mid 6.992493 -161.876232)
					(end 6.481826 -162.386772)
				)
				(arc
					(start 6.481826 -163.199572)
					(mid 6.992366 -163.710112)
					(end 7.502906 -163.199572)
				)
			)
		)
	)
	(zone
		(layers "In1.Cu" "In3.Cu" "In4.Cu" "In6.Cu")
		(hatch none 0.5)
		(connect_pads
			(clearance 0)
		)
		(min_thickness 0.25)
		(keepout
			(tracks not_allowed)
			(vias allowed)
			(pads allowed)
			(copperpour not_allowed)
			(footprints allowed)
		)
		(placement
			(enabled no)
			(sheetname "")
		)
		(fill yes
			(thermal_gap 0.5)
			(thermal_bridge_width 0.5)
			(island_removal_mode 0)
		)
		(polygon
			(pts
				(arc
					(start 220.840554 -488.984036)
					(mid 220.330141 -488.473242)
					(end 219.819474 -488.983782)
				)
				(arc
					(start 219.819474 -489.796582)
					(mid 220.330014 -490.307122)
					(end 220.840554 -489.796582)
				)
			)
		)
	)
	(zone
		(layers "In1.Cu" "In3.Cu" "In4.Cu" "In6.Cu")
		(hatch none 0.5)
		(connect_pads
			(clearance 0)
		)
		(min_thickness 0.25)
		(keepout
			(tracks not_allowed)
			(vias allowed)
			(pads allowed)
			(copperpour not_allowed)
			(footprints allowed)
		)
		(placement
			(enabled no)
			(sheetname "")
		)
		(fill yes
			(thermal_gap 0.5)
			(thermal_bridge_width 0.5)
			(island_removal_mode 0)
		)
		(polygon
			(pts
				(arc
					(start 230.71963 -60.300616)
					(mid 231.230424 -59.790203)
					(end 230.719884 -59.279536)
				)
				(arc
					(start 229.907084 -59.279536)
					(mid 229.396544 -59.790076)
					(end 229.907084 -60.300616)
				)
			)
		)
	)
	(zone
		(layers "In1.Cu" "In3.Cu" "In4.Cu" "In6.Cu")
		(hatch none 0.5)
		(connect_pads
			(clearance 0)
		)
		(min_thickness 0.25)
		(keepout
			(tracks not_allowed)
			(vias allowed)
			(pads allowed)
			(copperpour not_allowed)
			(footprints allowed)
		)
		(placement
			(enabled no)
			(sheetname "")
		)
		(fill yes
			(thermal_gap 0.5)
			(thermal_bridge_width 0.5)
			(island_removal_mode 0)
		)
		(polygon
			(pts
				(arc
					(start 5.59054 -222.335598)
					(mid 5.080127 -221.824804)
					(end 4.56946 -222.335344)
				)
				(arc
					(start 4.56946 -223.148144)
					(mid 5.08 -223.658684)
					(end 5.59054 -223.148144)
				)
			)
		)
	)
	(zone
		(layers "In1.Cu" "In3.Cu" "In4.Cu" "In6.Cu")
		(hatch none 0.5)
		(connect_pads
			(clearance 0)
		)
		(min_thickness 0.25)
		(keepout
			(tracks not_allowed)
			(vias allowed)
			(pads allowed)
			(copperpour not_allowed)
			(footprints allowed)
		)
		(placement
			(enabled no)
			(sheetname "")
		)
		(fill yes
			(thermal_gap 0.5)
			(thermal_bridge_width 0.5)
			(island_removal_mode 0)
		)
		(polygon
			(pts
				(arc
					(start 26.15946 -326.016112)
					(mid 26.669873 -326.526906)
					(end 27.18054 -326.016366)
				)
				(arc
					(start 27.18054 -325.203566)
					(mid 26.67 -324.693026)
					(end 26.15946 -325.203566)
				)
			)
		)
	)
	(zone
		(layers "In1.Cu" "In3.Cu" "In4.Cu" "In6.Cu")
		(hatch none 0.5)
		(connect_pads
			(clearance 0)
		)
		(min_thickness 0.25)
		(keepout
			(tracks not_allowed)
			(vias allowed)
			(pads allowed)
			(copperpour not_allowed)
			(footprints allowed)
		)
		(placement
			(enabled no)
			(sheetname "")
		)
		(fill yes
			(thermal_gap 0.5)
			(thermal_bridge_width 0.5)
			(island_removal_mode 0)
		)
		(polygon
			(pts
				(arc
					(start 220.840554 -175.1838)
					(mid 220.330141 -174.673006)
					(end 219.819474 -175.183546)
				)
				(arc
					(start 219.819474 -175.996346)
					(mid 220.330014 -176.506886)
					(end 220.840554 -175.996346)
				)
			)
		)
	)
	(zone
		(layers "In1.Cu" "In3.Cu" "In4.Cu" "In6.Cu")
		(hatch none 0.5)
		(connect_pads
			(clearance 0)
		)
		(min_thickness 0.25)
		(keepout
			(tracks not_allowed)
			(vias allowed)
			(pads allowed)
			(copperpour not_allowed)
			(footprints allowed)
		)
		(placement
			(enabled no)
			(sheetname "")
		)
		(fill yes
			(thermal_gap 0.5)
			(thermal_bridge_width 0.5)
			(island_removal_mode 0)
		)
		(polygon
			(pts
				(arc
					(start 37.33927 -388.231634)
					(mid 36.727257 -387.61924)
					(end 36.11499 -388.23138)
				)
				(arc
					(start 36.11499 -389.34898)
					(mid 36.72713 -389.96112)
					(end 37.33927 -389.34898)
				)
			)
		)
	)
	(zone
		(layers "In1.Cu" "In3.Cu" "In4.Cu" "In6.Cu")
		(hatch none 0.5)
		(connect_pads
			(clearance 0)
		)
		(min_thickness 0.25)
		(keepout
			(tracks not_allowed)
			(vias allowed)
			(pads allowed)
			(copperpour not_allowed)
			(footprints allowed)
		)
		(placement
			(enabled no)
			(sheetname "")
		)
		(fill yes
			(thermal_gap 0.5)
			(thermal_bridge_width 0.5)
			(island_removal_mode 0)
		)
		(polygon
			(pts
				(arc
					(start 5.59054 -423.135552)
					(mid 5.080127 -422.624758)
					(end 4.56946 -423.135298)
				)
				(arc
					(start 4.56946 -423.948098)
					(mid 5.08 -424.458638)
					(end 5.59054 -423.948098)
				)
			)
		)
	)
	(zone
		(layers "In1.Cu" "In3.Cu" "In4.Cu" "In6.Cu")
		(hatch none 0.5)
		(connect_pads
			(clearance 0)
		)
		(min_thickness 0.25)
		(keepout
			(tracks not_allowed)
			(vias allowed)
			(pads allowed)
			(copperpour not_allowed)
			(footprints allowed)
		)
		(placement
			(enabled no)
			(sheetname "")
		)
		(fill yes
			(thermal_gap 0.5)
			(thermal_bridge_width 0.5)
			(island_removal_mode 0)
		)
		(polygon
			(pts
				(arc
					(start 37.33927 -172.631354)
					(mid 36.727257 -172.01896)
					(end 36.11499 -172.6311)
				)
				(arc
					(start 36.11499 -173.7487)
					(mid 36.72713 -174.36084)
					(end 37.33927 -173.7487)
				)
			)
		)
	)
	(zone
		(layers "In1.Cu" "In3.Cu" "In4.Cu" "In6.Cu")
		(hatch none 0.5)
		(connect_pads
			(clearance 0)
		)
		(min_thickness 0.25)
		(keepout
			(tracks not_allowed)
			(vias allowed)
			(pads allowed)
			(copperpour not_allowed)
			(footprints allowed)
		)
		(placement
			(enabled no)
			(sheetname "")
		)
		(fill yes
			(thermal_gap 0.5)
			(thermal_bridge_width 0.5)
			(island_removal_mode 0)
		)
		(polygon
			(pts
				(arc
					(start 222.339154 -79.23149)
					(mid 221.727141 -78.619096)
					(end 221.114874 -79.231236)
				)
				(arc
					(start 221.114874 -80.348836)
					(mid 221.727014 -80.960976)
					(end 222.339154 -80.348836)
				)
			)
		)
	)
	(zone
		(layers "In1.Cu" "In3.Cu" "In4.Cu" "In6.Cu")
		(hatch none 0.5)
		(connect_pads
			(clearance 0)
		)
		(min_thickness 0.25)
		(keepout
			(tracks not_allowed)
			(vias allowed)
			(pads allowed)
			(copperpour not_allowed)
			(footprints allowed)
		)
		(placement
			(enabled no)
			(sheetname "")
		)
		(fill yes
			(thermal_gap 0.5)
			(thermal_bridge_width 0.5)
			(island_removal_mode 0)
		)
		(polygon
			(pts
				(arc
					(start 44.907454 -265.279632)
					(mid 44.39666 -265.790045)
					(end 44.9072 -266.300712)
				)
				(arc
					(start 45.72 -266.300712)
					(mid 46.23054 -265.790172)
					(end 45.72 -265.279632)
				)
			)
		)
	)
	(zone
		(layers "In1.Cu" "In3.Cu" "In4.Cu" "In6.Cu")
		(hatch none 0.5)
		(connect_pads
			(clearance 0)
		)
		(min_thickness 0.25)
		(keepout
			(tracks not_allowed)
			(vias allowed)
			(pads allowed)
			(copperpour not_allowed)
			(footprints allowed)
		)
		(placement
			(enabled no)
			(sheetname "")
		)
		(fill yes
			(thermal_gap 0.5)
			(thermal_bridge_width 0.5)
			(island_removal_mode 0)
		)
		(polygon
			(pts
				(arc
					(start 35.84067 -157.583886)
					(mid 35.330257 -157.073092)
					(end 34.81959 -157.583632)
				)
				(arc
					(start 34.81959 -158.396432)
					(mid 35.33013 -158.906972)
					(end 35.84067 -158.396432)
				)
			)
		)
	)
	(zone
		(layers "In1.Cu" "In3.Cu" "In4.Cu" "In6.Cu")
		(hatch none 0.5)
		(connect_pads
			(clearance 0)
		)
		(min_thickness 0.25)
		(keepout
			(tracks not_allowed)
			(vias allowed)
			(pads allowed)
			(copperpour not_allowed)
			(footprints allowed)
		)
		(placement
			(enabled no)
			(sheetname "")
		)
		(fill yes
			(thermal_gap 0.5)
			(thermal_bridge_width 0.5)
			(island_removal_mode 0)
		)
		(polygon
			(pts
				(arc
					(start 230.71963 -163.300664)
					(mid 231.230424 -162.790251)
					(end 230.719884 -162.279584)
				)
				(arc
					(start 229.907084 -162.279584)
					(mid 229.396544 -162.790124)
					(end 229.907084 -163.300664)
				)
			)
		)
	)
	(zone
		(layers "In1.Cu" "In3.Cu" "In4.Cu" "In6.Cu")
		(hatch none 0.5)
		(connect_pads
			(clearance 0)
		)
		(min_thickness 0.25)
		(keepout
			(tracks not_allowed)
			(vias allowed)
			(pads allowed)
			(copperpour not_allowed)
			(footprints allowed)
		)
		(placement
			(enabled no)
			(sheetname "")
		)
		(fill yes
			(thermal_gap 0.5)
			(thermal_bridge_width 0.5)
			(island_removal_mode 0)
		)
		(polygon
			(pts
				(arc
					(start 35.84067 -170.383962)
					(mid 35.330257 -169.873168)
					(end 34.81959 -170.383708)
				)
				(arc
					(start 34.81959 -171.196508)
					(mid 35.33013 -171.707048)
					(end 35.84067 -171.196508)
				)
			)
		)
	)
	(zone
		(layers "In1.Cu" "In3.Cu" "In4.Cu" "In6.Cu")
		(hatch none 0.5)
		(connect_pads
			(clearance 0)
		)
		(min_thickness 0.25)
		(keepout
			(tracks not_allowed)
			(vias allowed)
			(pads allowed)
			(copperpour not_allowed)
			(footprints allowed)
		)
		(placement
			(enabled no)
			(sheetname "")
		)
		(fill yes
			(thermal_gap 0.5)
			(thermal_bridge_width 0.5)
			(island_removal_mode 0)
		)
		(polygon
			(pts
				(arc
					(start 6.481826 -437.596788)
					(mid 6.992239 -438.107582)
					(end 7.502906 -437.597042)
				)
				(arc
					(start 7.502906 -436.784242)
					(mid 6.992366 -436.273702)
					(end 6.481826 -436.784242)
				)
			)
		)
	)
	(zone
		(layers "In1.Cu" "In3.Cu" "In4.Cu" "In6.Cu")
		(hatch none 0.5)
		(connect_pads
			(clearance 0)
		)
		(min_thickness 0.25)
		(keepout
			(tracks not_allowed)
			(vias allowed)
			(pads allowed)
			(copperpour not_allowed)
			(footprints allowed)
		)
		(placement
			(enabled no)
			(sheetname "")
		)
		(fill yes
			(thermal_gap 0.5)
			(thermal_bridge_width 0.5)
			(island_removal_mode 0)
		)
		(polygon
			(pts
				(arc
					(start 35.84067 -76.983844)
					(mid 35.330257 -76.47305)
					(end 34.81959 -76.98359)
				)
				(arc
					(start 34.81959 -77.79639)
					(mid 35.33013 -78.30693)
					(end 35.84067 -77.79639)
				)
			)
		)
	)
	(zone
		(layers "In1.Cu" "In3.Cu" "In4.Cu" "In6.Cu")
		(hatch none 0.5)
		(connect_pads
			(clearance 0)
		)
		(min_thickness 0.25)
		(keepout
			(tracks not_allowed)
			(vias allowed)
			(pads allowed)
			(copperpour not_allowed)
			(footprints allowed)
		)
		(placement
			(enabled no)
			(sheetname "")
		)
		(fill yes
			(thermal_gap 0.5)
			(thermal_bridge_width 0.5)
			(island_removal_mode 0)
		)
		(polygon
			(pts
				(arc
					(start 7.502906 -223.897952)
					(mid 6.992493 -223.387158)
					(end 6.481826 -223.897698)
				)
				(arc
					(start 6.481826 -224.710498)
					(mid 6.992366 -225.221038)
					(end 7.502906 -224.710498)
				)
			)
		)
	)
	(zone
		(layers "In1.Cu" "In3.Cu" "In4.Cu" "In6.Cu")
		(hatch none 0.5)
		(connect_pads
			(clearance 0)
		)
		(min_thickness 0.25)
		(keepout
			(tracks not_allowed)
			(vias allowed)
			(pads allowed)
			(copperpour not_allowed)
			(footprints allowed)
		)
		(placement
			(enabled no)
			(sheetname "")
		)
		(fill yes
			(thermal_gap 0.5)
			(thermal_bridge_width 0.5)
			(island_removal_mode 0)
		)
		(polygon
			(pts
				(arc
					(start 16.76146 -342.415876)
					(mid 17.271873 -342.92667)
					(end 17.78254 -342.41613)
				)
				(arc
					(start 17.78254 -341.60333)
					(mid 17.272 -341.09279)
					(end 16.76146 -341.60333)
				)
			)
		)
	)
	(zone
		(layers "In1.Cu" "In3.Cu" "In4.Cu" "In6.Cu")
		(hatch none 0.5)
		(connect_pads
			(clearance 0)
		)
		(min_thickness 0.25)
		(keepout
			(tracks not_allowed)
			(vias allowed)
			(pads allowed)
			(copperpour not_allowed)
			(footprints allowed)
		)
		(placement
			(enabled no)
			(sheetname "")
		)
		(fill yes
			(thermal_gap 0.5)
			(thermal_bridge_width 0.5)
			(island_removal_mode 0)
		)
		(polygon
			(pts
				(arc
					(start 25.88514 -224.451164)
					(mid 25.273 -223.839024)
					(end 24.66086 -224.451164)
				)
				(arc
					(start 24.66086 -225.56851)
					(mid 25.272873 -226.180904)
					(end 25.88514 -225.568764)
				)
			)
		)
	)
	(zone
		(layers "In1.Cu" "In3.Cu" "In4.Cu" "In6.Cu")
		(hatch none 0.5)
		(connect_pads
			(clearance 0)
		)
		(min_thickness 0.25)
		(keepout
			(tracks not_allowed)
			(vias allowed)
			(pads allowed)
			(copperpour not_allowed)
			(footprints allowed)
		)
		(placement
			(enabled no)
			(sheetname "")
		)
		(fill yes
			(thermal_gap 0.5)
			(thermal_bridge_width 0.5)
			(island_removal_mode 0)
		)
		(polygon
			(pts
				(arc
					(start 7.502906 -181.536086)
					(mid 6.992493 -181.025292)
					(end 6.481826 -181.535832)
				)
				(arc
					(start 6.481826 -182.348632)
					(mid 6.992366 -182.859172)
					(end 7.502906 -182.348632)
				)
			)
		)
	)
	(zone
		(layers "In1.Cu" "In3.Cu" "In4.Cu" "In6.Cu")
		(hatch none 0.5)
		(connect_pads
			(clearance 0)
		)
		(min_thickness 0.25)
		(keepout
			(tracks not_allowed)
			(vias allowed)
			(pads allowed)
			(copperpour not_allowed)
			(footprints allowed)
		)
		(placement
			(enabled no)
			(sheetname "")
		)
		(fill yes
			(thermal_gap 0.5)
			(thermal_bridge_width 0.5)
			(island_removal_mode 0)
		)
		(polygon
			(pts
				(arc
					(start 6.477254 -448.957192)
					(mid 5.96646 -449.467605)
					(end 6.477 -449.978272)
				)
				(arc
					(start 7.2898 -449.978272)
					(mid 7.80034 -449.467732)
					(end 7.2898 -448.957192)
				)
			)
		)
	)
	(zone
		(layers "In1.Cu" "In3.Cu" "In4.Cu" "In6.Cu")
		(hatch none 0.5)
		(connect_pads
			(clearance 0)
		)
		(min_thickness 0.25)
		(keepout
			(tracks not_allowed)
			(vias allowed)
			(pads allowed)
			(copperpour not_allowed)
			(footprints allowed)
		)
		(placement
			(enabled no)
			(sheetname "")
		)
		(fill yes
			(thermal_gap 0.5)
			(thermal_bridge_width 0.5)
			(island_removal_mode 0)
		)
		(polygon
			(pts
				(arc
					(start 220.840554 -282.98394)
					(mid 220.330141 -282.473146)
					(end 219.819474 -282.983686)
				)
				(arc
					(start 219.819474 -283.796486)
					(mid 220.330014 -284.307026)
					(end 220.840554 -283.796486)
				)
			)
		)
	)
	(zone
		(layers "In1.Cu" "In3.Cu" "In4.Cu" "In6.Cu")
		(hatch none 0.5)
		(connect_pads
			(clearance 0)
		)
		(min_thickness 0.25)
		(keepout
			(tracks not_allowed)
			(vias allowed)
			(pads allowed)
			(copperpour not_allowed)
			(footprints allowed)
		)
		(placement
			(enabled no)
			(sheetname "")
		)
		(fill yes
			(thermal_gap 0.5)
			(thermal_bridge_width 0.5)
			(island_removal_mode 0)
		)
		(polygon
			(pts
				(arc
					(start 44.907454 -368.27968)
					(mid 44.39666 -368.790093)
					(end 44.9072 -369.30076)
				)
				(arc
					(start 45.72 -369.30076)
					(mid 46.23054 -368.79022)
					(end 45.72 -368.27968)
				)
			)
		)
	)
	(zone
		(layers "In1.Cu" "In3.Cu" "In4.Cu" "In6.Cu")
		(hatch none 0.5)
		(connect_pads
			(clearance 0)
		)
		(min_thickness 0.25)
		(keepout
			(tracks not_allowed)
			(vias allowed)
			(pads allowed)
			(copperpour not_allowed)
			(footprints allowed)
		)
		(placement
			(enabled no)
			(sheetname "")
		)
		(fill yes
			(thermal_gap 0.5)
			(thermal_bridge_width 0.5)
			(island_removal_mode 0)
		)
		(polygon
			(pts
				(arc
					(start 5.59054 -209.535776)
					(mid 5.080127 -209.024982)
					(end 4.56946 -209.535522)
				)
				(arc
					(start 4.56946 -210.348322)
					(mid 5.08 -210.858862)
					(end 5.59054 -210.348322)
				)
			)
		)
	)
	(zone
		(layers "In1.Cu" "In3.Cu" "In4.Cu" "In6.Cu")
		(hatch none 0.5)
		(connect_pads
			(clearance 0)
		)
		(min_thickness 0.25)
		(keepout
			(tracks not_allowed)
			(vias allowed)
			(pads allowed)
			(copperpour not_allowed)
			(footprints allowed)
		)
		(placement
			(enabled no)
			(sheetname "")
		)
		(fill yes
			(thermal_gap 0.5)
			(thermal_bridge_width 0.5)
			(island_removal_mode 0)
		)
		(polygon
			(pts
				(arc
					(start 5.59054 -157.535626)
					(mid 5.080127 -157.024832)
					(end 4.56946 -157.535372)
				)
				(arc
					(start 4.56946 -158.348172)
					(mid 5.08 -158.858712)
					(end 5.59054 -158.348172)
				)
			)
		)
	)
	(zone
		(layers "In1.Cu" "In3.Cu" "In4.Cu" "In6.Cu")
		(hatch none 0.5)
		(connect_pads
			(clearance 0)
		)
		(min_thickness 0.25)
		(keepout
			(tracks not_allowed)
			(vias allowed)
			(pads allowed)
			(copperpour not_allowed)
			(footprints allowed)
		)
		(placement
			(enabled no)
			(sheetname "")
		)
		(fill yes
			(thermal_gap 0.5)
			(thermal_bridge_width 0.5)
			(island_removal_mode 0)
		)
		(polygon
			(pts
				(arc
					(start 6.481826 -350.748346)
					(mid 6.992239 -351.25914)
					(end 7.502906 -350.7486)
				)
				(arc
					(start 7.502906 -349.9358)
					(mid 6.992366 -349.42526)
					(end 6.481826 -349.9358)
				)
			)
		)
	)
	(zone
		(layers "In1.Cu" "In3.Cu" "In4.Cu" "In6.Cu")
		(hatch none 0.5)
		(connect_pads
			(clearance 0)
		)
		(min_thickness 0.25)
		(keepout
			(tracks not_allowed)
			(vias allowed)
			(pads allowed)
			(copperpour not_allowed)
			(footprints allowed)
		)
		(placement
			(enabled no)
			(sheetname "")
		)
		(fill yes
			(thermal_gap 0.5)
			(thermal_bridge_width 0.5)
			(island_removal_mode 0)
		)
		(polygon
			(pts
				(arc
					(start 37.33927 -365.831628)
					(mid 36.727257 -365.219234)
					(end 36.11499 -365.831374)
				)
				(arc
					(start 36.11499 -366.948974)
					(mid 36.72713 -367.561114)
					(end 37.33927 -366.948974)
				)
			)
		)
	)
	(zone
		(layers "In1.Cu" "In3.Cu" "In4.Cu" "In6.Cu")
		(hatch none 0.5)
		(connect_pads
			(clearance 0)
		)
		(min_thickness 0.25)
		(keepout
			(tracks not_allowed)
			(vias allowed)
			(pads allowed)
			(copperpour not_allowed)
			(footprints allowed)
		)
		(placement
			(enabled no)
			(sheetname "")
		)
		(fill yes
			(thermal_gap 0.5)
			(thermal_bridge_width 0.5)
			(island_removal_mode 0)
		)
		(polygon
			(pts
				(arc
					(start 16.76146 -445.415924)
					(mid 17.271873 -445.926718)
					(end 17.78254 -445.416178)
				)
				(arc
					(start 17.78254 -444.603378)
					(mid 17.272 -444.092838)
					(end 16.76146 -444.603378)
				)
			)
		)
	)
	(zone
		(layers "In1.Cu" "In3.Cu" "In4.Cu" "In6.Cu")
		(hatch none 0.5)
		(connect_pads
			(clearance 0)
		)
		(min_thickness 0.25)
		(keepout
			(tracks not_allowed)
			(vias allowed)
			(pads allowed)
			(copperpour not_allowed)
			(footprints allowed)
		)
		(placement
			(enabled no)
			(sheetname "")
		)
		(fill yes
			(thermal_gap 0.5)
			(thermal_bridge_width 0.5)
			(island_removal_mode 0)
		)
		(polygon
			(pts
				(arc
					(start 25.88514 -229.251256)
					(mid 25.273 -228.639116)
					(end 24.66086 -229.251256)
				)
				(arc
					(start 24.66086 -230.368602)
					(mid 25.272873 -230.980996)
					(end 25.88514 -230.368856)
				)
			)
		)
	)
	(zone
		(layers "In1.Cu" "In3.Cu" "In4.Cu" "In6.Cu")
		(hatch none 0.5)
		(connect_pads
			(clearance 0)
		)
		(min_thickness 0.25)
		(keepout
			(tracks not_allowed)
			(vias allowed)
			(pads allowed)
			(copperpour not_allowed)
			(footprints allowed)
		)
		(placement
			(enabled no)
			(sheetname "")
		)
		(fill yes
			(thermal_gap 0.5)
			(thermal_bridge_width 0.5)
			(island_removal_mode 0)
		)
		(polygon
			(pts
				(arc
					(start 35.84067 -381.183896)
					(mid 35.330257 -380.673102)
					(end 34.81959 -381.183642)
				)
				(arc
					(start 34.81959 -381.996442)
					(mid 35.33013 -382.506982)
					(end 35.84067 -381.996442)
				)
			)
		)
	)
	(zone
		(layers "In1.Cu" "In3.Cu" "In4.Cu" "In6.Cu")
		(hatch none 0.5)
		(connect_pads
			(clearance 0)
		)
		(min_thickness 0.25)
		(keepout
			(tracks not_allowed)
			(vias allowed)
			(pads allowed)
			(copperpour not_allowed)
			(footprints allowed)
		)
		(placement
			(enabled no)
			(sheetname "")
		)
		(fill yes
			(thermal_gap 0.5)
			(thermal_bridge_width 0.5)
			(island_removal_mode 0)
		)
		(polygon
			(pts
				(arc
					(start 27.18054 -128.8034)
					(mid 26.67 -128.29286)
					(end 26.15946 -128.8034)
				)
				(arc
					(start 26.15946 -129.615946)
					(mid 26.669873 -130.12674)
					(end 27.18054 -129.6162)
				)
			)
		)
	)
	(zone
		(layers "In1.Cu" "In3.Cu" "In4.Cu" "In6.Cu")
		(hatch none 0.5)
		(connect_pads
			(clearance 0)
		)
		(min_thickness 0.25)
		(keepout
			(tracks not_allowed)
			(vias allowed)
			(pads allowed)
			(copperpour not_allowed)
			(footprints allowed)
		)
		(placement
			(enabled no)
			(sheetname "")
		)
		(fill yes
			(thermal_gap 0.5)
			(thermal_bridge_width 0.5)
			(island_removal_mode 0)
		)
		(polygon
			(pts
				(arc
					(start 222.339154 -383.431542)
					(mid 221.727141 -382.819148)
					(end 221.114874 -383.431288)
				)
				(arc
					(start 221.114874 -384.548888)
					(mid 221.727014 -385.161028)
					(end 222.339154 -384.548888)
				)
			)
		)
	)
	(zone
		(layers "In1.Cu" "In3.Cu" "In4.Cu" "In6.Cu")
		(hatch none 0.5)
		(connect_pads
			(clearance 0)
		)
		(min_thickness 0.25)
		(keepout
			(tracks not_allowed)
			(vias allowed)
			(pads allowed)
			(copperpour not_allowed)
			(footprints allowed)
		)
		(placement
			(enabled no)
			(sheetname "")
		)
		(fill yes
			(thermal_gap 0.5)
			(thermal_bridge_width 0.5)
			(island_removal_mode 0)
		)
		(polygon
			(pts
				(arc
					(start 5.59054 -191.135762)
					(mid 5.080127 -190.624968)
					(end 4.56946 -191.135508)
				)
				(arc
					(start 4.56946 -191.948308)
					(mid 5.08 -192.458848)
					(end 5.59054 -191.948308)
				)
			)
		)
	)
	(zone
		(layers "In1.Cu" "In3.Cu" "In4.Cu" "In6.Cu")
		(hatch none 0.5)
		(connect_pads
			(clearance 0)
		)
		(min_thickness 0.25)
		(keepout
			(tracks not_allowed)
			(vias allowed)
			(pads allowed)
			(copperpour not_allowed)
			(footprints allowed)
		)
		(placement
			(enabled no)
			(sheetname "")
		)
		(fill yes
			(thermal_gap 0.5)
			(thermal_bridge_width 0.5)
			(island_removal_mode 0)
		)
		(polygon
			(pts
				(arc
					(start 6.481826 -319.54851)
					(mid 6.992239 -320.059304)
					(end 7.502906 -319.548764)
				)
				(arc
					(start 7.502906 -318.735964)
					(mid 6.992366 -318.225424)
					(end 6.481826 -318.735964)
				)
			)
		)
	)
	(zone
		(layers "In1.Cu" "In3.Cu" "In4.Cu" "In6.Cu")
		(hatch none 0.5)
		(connect_pads
			(clearance 0)
		)
		(min_thickness 0.25)
		(keepout
			(tracks not_allowed)
			(vias allowed)
			(pads allowed)
			(copperpour not_allowed)
			(footprints allowed)
		)
		(placement
			(enabled no)
			(sheetname "")
		)
		(fill yes
			(thermal_gap 0.5)
			(thermal_bridge_width 0.5)
			(island_removal_mode 0)
		)
		(polygon
			(pts
				(arc
					(start 37.33927 -79.23149)
					(mid 36.727257 -78.619096)
					(end 36.11499 -79.231236)
				)
				(arc
					(start 36.11499 -80.348836)
					(mid 36.72713 -80.960976)
					(end 37.33927 -80.348836)
				)
			)
		)
	)
	(zone
		(layers "In1.Cu" "In3.Cu" "In4.Cu" "In6.Cu")
		(hatch none 0.5)
		(connect_pads
			(clearance 0)
		)
		(min_thickness 0.25)
		(keepout
			(tracks not_allowed)
			(vias allowed)
			(pads allowed)
			(copperpour not_allowed)
			(footprints allowed)
		)
		(placement
			(enabled no)
			(sheetname "")
		)
		(fill yes
			(thermal_gap 0.5)
			(thermal_bridge_width 0.5)
			(island_removal_mode 0)
		)
		(polygon
			(pts
				(arc
					(start 229.907084 -368.27968)
					(mid 229.396544 -368.79022)
					(end 229.907084 -369.30076)
				)
				(arc
					(start 230.71963 -369.30076)
					(mid 231.230424 -368.790347)
					(end 230.719884 -368.27968)
				)
			)
		)
	)
	(zone
		(layers "In1.Cu" "In3.Cu" "In4.Cu" "In6.Cu")
		(hatch none 0.5)
		(connect_pads
			(clearance 0)
		)
		(min_thickness 0.25)
		(keepout
			(tracks not_allowed)
			(vias allowed)
			(pads allowed)
			(copperpour not_allowed)
			(footprints allowed)
		)
		(placement
			(enabled no)
			(sheetname "")
		)
		(fill yes
			(thermal_gap 0.5)
			(thermal_bridge_width 0.5)
			(island_removal_mode 0)
		)
		(polygon
			(pts
				(arc
					(start 4.56946 -435.94782)
					(mid 5.079873 -436.458614)
					(end 5.59054 -435.948074)
				)
				(arc
					(start 5.59054 -435.135274)
					(mid 5.08 -434.624734)
					(end 4.56946 -435.135274)
				)
			)
		)
	)
	(zone
		(layers "In1.Cu" "In3.Cu" "In4.Cu" "In6.Cu")
		(hatch none 0.5)
		(connect_pads
			(clearance 0)
		)
		(min_thickness 0.25)
		(keepout
			(tracks not_allowed)
			(vias allowed)
			(pads allowed)
			(copperpour not_allowed)
			(footprints allowed)
		)
		(placement
			(enabled no)
			(sheetname "")
		)
		(fill yes
			(thermal_gap 0.5)
			(thermal_bridge_width 0.5)
			(island_removal_mode 0)
		)
		(polygon
			(pts
				(arc
					(start 5.59054 -163.935664)
					(mid 5.080127 -163.42487)
					(end 4.56946 -163.93541)
				)
				(arc
					(start 4.56946 -164.74821)
					(mid 5.08 -165.25875)
					(end 5.59054 -164.74821)
				)
			)
		)
	)
	(zone
		(layers "In1.Cu" "In3.Cu" "In4.Cu" "In6.Cu")
		(hatch none 0.5)
		(connect_pads
			(clearance 0)
		)
		(min_thickness 0.25)
		(keepout
			(tracks not_allowed)
			(vias allowed)
			(pads allowed)
			(copperpour not_allowed)
			(footprints allowed)
		)
		(placement
			(enabled no)
			(sheetname "")
		)
		(fill yes
			(thermal_gap 0.5)
			(thermal_bridge_width 0.5)
			(island_removal_mode 0)
		)
		(polygon
			(pts
				(arc
					(start 37.33927 -182.231538)
					(mid 36.727257 -181.619144)
					(end 36.11499 -182.231284)
				)
				(arc
					(start 36.11499 -183.348884)
					(mid 36.72713 -183.961024)
					(end 37.33927 -183.348884)
				)
			)
		)
	)
	(zone
		(layers "In1.Cu" "In3.Cu" "In4.Cu" "In6.Cu")
		(hatch none 0.5)
		(connect_pads
			(clearance 0)
		)
		(min_thickness 0.25)
		(keepout
			(tracks not_allowed)
			(vias allowed)
			(pads allowed)
			(copperpour not_allowed)
			(footprints allowed)
		)
		(placement
			(enabled no)
			(sheetname "")
		)
		(fill yes
			(thermal_gap 0.5)
			(thermal_bridge_width 0.5)
			(island_removal_mode 0)
		)
		(polygon
			(pts
				(arc
					(start 5.59054 -345.135708)
					(mid 5.080127 -344.624914)
					(end 4.56946 -345.135454)
				)
				(arc
					(start 4.56946 -345.948254)
					(mid 5.08 -346.458794)
					(end 5.59054 -345.948254)
				)
			)
		)
	)
	(zone
		(layers "In1.Cu" "In3.Cu" "In4.Cu" "In6.Cu")
		(hatch none 0.5)
		(connect_pads
			(clearance 0)
		)
		(min_thickness 0.25)
		(keepout
			(tracks not_allowed)
			(vias allowed)
			(pads allowed)
			(copperpour not_allowed)
			(footprints allowed)
		)
		(placement
			(enabled no)
			(sheetname "")
		)
		(fill yes
			(thermal_gap 0.5)
			(thermal_bridge_width 0.5)
			(island_removal_mode 0)
		)
		(polygon
			(pts
				(arc
					(start 7.502906 -431.184558)
					(mid 6.992493 -430.673764)
					(end 6.481826 -431.184304)
				)
				(arc
					(start 6.481826 -431.997104)
					(mid 6.992366 -432.507644)
					(end 7.502906 -431.997104)
				)
			)
		)
	)
	(zone
		(layers "In1.Cu" "In3.Cu" "In4.Cu" "In6.Cu")
		(hatch none 0.5)
		(connect_pads
			(clearance 0)
		)
		(min_thickness 0.25)
		(keepout
			(tracks not_allowed)
			(vias allowed)
			(pads allowed)
			(copperpour not_allowed)
			(footprints allowed)
		)
		(placement
			(enabled no)
			(sheetname "")
		)
		(fill yes
			(thermal_gap 0.5)
			(thermal_bridge_width 0.5)
			(island_removal_mode 0)
		)
		(polygon
			(pts
				(arc
					(start 220.840554 -381.183896)
					(mid 220.330141 -380.673102)
					(end 219.819474 -381.183642)
				)
				(arc
					(start 219.819474 -381.996442)
					(mid 220.330014 -382.506982)
					(end 220.840554 -381.996442)
				)
			)
		)
	)
	(zone
		(layers "In1.Cu" "In3.Cu" "In4.Cu" "In6.Cu")
		(hatch none 0.5)
		(connect_pads
			(clearance 0)
		)
		(min_thickness 0.25)
		(keepout
			(tracks not_allowed)
			(vias allowed)
			(pads allowed)
			(copperpour not_allowed)
			(footprints allowed)
		)
		(placement
			(enabled no)
			(sheetname "")
		)
		(fill yes
			(thermal_gap 0.5)
			(thermal_bridge_width 0.5)
			(island_removal_mode 0)
		)
		(polygon
			(pts
				(arc
					(start 5.59054 -206.33563)
					(mid 5.080127 -205.824836)
					(end 4.56946 -206.335376)
				)
				(arc
					(start 4.56946 -207.148176)
					(mid 5.08 -207.658716)
					(end 5.59054 -207.148176)
				)
			)
		)
	)
	(zone
		(layers "In1.Cu" "In3.Cu" "In4.Cu" "In6.Cu")
		(hatch none 0.5)
		(connect_pads
			(clearance 0)
		)
		(min_thickness 0.25)
		(keepout
			(tracks not_allowed)
			(vias allowed)
			(pads allowed)
			(copperpour not_allowed)
			(footprints allowed)
		)
		(placement
			(enabled no)
			(sheetname "")
		)
		(fill yes
			(thermal_gap 0.5)
			(thermal_bridge_width 0.5)
			(island_removal_mode 0)
		)
		(polygon
			(pts
				(arc
					(start 5.59054 -203.135738)
					(mid 5.080127 -202.624944)
					(end 4.56946 -203.135484)
				)
				(arc
					(start 4.56946 -203.948284)
					(mid 5.08 -204.458824)
					(end 5.59054 -203.948284)
				)
			)
		)
	)
	(zone
		(layers "In1.Cu" "In3.Cu" "In4.Cu" "In6.Cu")
		(hatch none 0.5)
		(connect_pads
			(clearance 0)
		)
		(min_thickness 0.25)
		(keepout
			(tracks not_allowed)
			(vias allowed)
			(pads allowed)
			(copperpour not_allowed)
			(footprints allowed)
		)
		(placement
			(enabled no)
			(sheetname "")
		)
		(fill yes
			(thermal_gap 0.5)
			(thermal_bridge_width 0.5)
			(island_removal_mode 0)
		)
		(polygon
			(pts
				(arc
					(start 7.502906 -281.98699)
					(mid 6.992493 -281.476196)
					(end 6.481826 -281.986736)
				)
				(arc
					(start 6.481826 -282.799536)
					(mid 6.992366 -283.310076)
					(end 7.502906 -282.799536)
				)
			)
		)
	)
	(zone
		(layers "In1.Cu" "In3.Cu" "In4.Cu" "In6.Cu")
		(hatch none 0.5)
		(connect_pads
			(clearance 0)
		)
		(min_thickness 0.25)
		(keepout
			(tracks not_allowed)
			(vias allowed)
			(pads allowed)
			(copperpour not_allowed)
			(footprints allowed)
		)
		(placement
			(enabled no)
			(sheetname "")
		)
		(fill yes
			(thermal_gap 0.5)
			(thermal_bridge_width 0.5)
			(island_removal_mode 0)
		)
		(polygon
			(pts
				(arc
					(start 5.59054 -326.735694)
					(mid 5.080127 -326.2249)
					(end 4.56946 -326.73544)
				)
				(arc
					(start 4.56946 -327.54824)
					(mid 5.08 -328.05878)
					(end 5.59054 -327.54824)
				)
			)
		)
	)
	(zone
		(layers "In1.Cu" "In3.Cu" "In4.Cu" "In6.Cu")
		(hatch none 0.5)
		(connect_pads
			(clearance 0)
		)
		(min_thickness 0.25)
		(keepout
			(tracks not_allowed)
			(vias allowed)
			(pads allowed)
			(copperpour not_allowed)
			(footprints allowed)
		)
		(placement
			(enabled no)
			(sheetname "")
		)
		(fill yes
			(thermal_gap 0.5)
			(thermal_bridge_width 0.5)
			(island_removal_mode 0)
		)
		(polygon
			(pts
				(arc
					(start 27.18054 -428.203868)
					(mid 26.670127 -427.693074)
					(end 26.15946 -428.203614)
				)
				(arc
					(start 26.15946 -429.016414)
					(mid 26.67 -429.526954)
					(end 27.18054 -429.016414)
				)
			)
		)
	)
	(zone
		(layers "In1.Cu" "In3.Cu" "In4.Cu" "In6.Cu")
		(hatch none 0.5)
		(connect_pads
			(clearance 0)
		)
		(min_thickness 0.25)
		(keepout
			(tracks not_allowed)
			(vias allowed)
			(pads allowed)
			(copperpour not_allowed)
			(footprints allowed)
		)
		(placement
			(enabled no)
			(sheetname "")
		)
		(fill yes
			(thermal_gap 0.5)
			(thermal_bridge_width 0.5)
			(island_removal_mode 0)
		)
		(polygon
			(pts
				(arc
					(start 5.59054 -280.335736)
					(mid 5.080127 -279.824942)
					(end 4.56946 -280.335482)
				)
				(arc
					(start 4.56946 -281.148282)
					(mid 5.08 -281.658822)
					(end 5.59054 -281.148282)
				)
			)
		)
	)
	(zone
		(layers "In1.Cu" "In3.Cu" "In4.Cu" "In6.Cu")
		(hatch none 0.5)
		(connect_pads
			(clearance 0)
		)
		(min_thickness 0.25)
		(keepout
			(tracks not_allowed)
			(vias allowed)
			(pads allowed)
			(copperpour not_allowed)
			(footprints allowed)
		)
		(placement
			(enabled no)
			(sheetname "")
		)
		(fill yes
			(thermal_gap 0.5)
			(thermal_bridge_width 0.5)
			(island_removal_mode 0)
		)
		(polygon
			(pts
				(arc
					(start 222.339154 -262.83158)
					(mid 221.727141 -262.219186)
					(end 221.114874 -262.831326)
				)
				(arc
					(start 221.114874 -263.948926)
					(mid 221.727014 -264.561066)
					(end 222.339154 -263.948926)
				)
			)
		)
	)
	(zone
		(layers "In1.Cu" "In3.Cu" "In4.Cu" "In6.Cu")
		(hatch none 0.5)
		(connect_pads
			(clearance 0)
		)
		(min_thickness 0.25)
		(keepout
			(tracks not_allowed)
			(vias allowed)
			(pads allowed)
			(copperpour not_allowed)
			(footprints allowed)
		)
		(placement
			(enabled no)
			(sheetname "")
		)
		(fill yes
			(thermal_gap 0.5)
			(thermal_bridge_width 0.5)
			(island_removal_mode 0)
		)
		(polygon
			(pts
				(arc
					(start 25.88514 -116.651278)
					(mid 25.273127 -116.038884)
					(end 24.66086 -116.651024)
				)
				(arc
					(start 24.66086 -117.768624)
					(mid 25.273 -118.380764)
					(end 25.88514 -117.768624)
				)
			)
		)
	)
	(zone
		(layers "In1.Cu" "In3.Cu" "In4.Cu" "In6.Cu")
		(hatch none 0.5)
		(connect_pads
			(clearance 0)
		)
		(min_thickness 0.25)
		(keepout
			(tracks not_allowed)
			(vias allowed)
			(pads allowed)
			(copperpour not_allowed)
			(footprints allowed)
		)
		(placement
			(enabled no)
			(sheetname "")
		)
		(fill yes
			(thermal_gap 0.5)
			(thermal_bridge_width 0.5)
			(island_removal_mode 0)
		)
		(polygon
			(pts
				(arc
					(start 5.59054 -199.935592)
					(mid 5.080127 -199.424798)
					(end 4.56946 -199.935338)
				)
				(arc
					(start 4.56946 -200.748138)
					(mid 5.08 -201.258678)
					(end 5.59054 -200.748138)
				)
			)
		)
	)
	(zone
		(layers "In1.Cu" "In3.Cu" "In4.Cu" "In6.Cu")
		(hatch none 0.5)
		(connect_pads
			(clearance 0)
		)
		(min_thickness 0.25)
		(keepout
			(tracks not_allowed)
			(vias allowed)
			(pads allowed)
			(copperpour not_allowed)
			(footprints allowed)
		)
		(placement
			(enabled no)
			(sheetname "")
		)
		(fill yes
			(thermal_gap 0.5)
			(thermal_bridge_width 0.5)
			(island_removal_mode 0)
		)
		(polygon
			(pts
				(arc
					(start 25.88514 -242.051078)
					(mid 25.273 -241.438938)
					(end 24.66086 -242.051078)
				)
				(arc
					(start 24.66086 -243.168424)
					(mid 25.272873 -243.780818)
					(end 25.88514 -243.168678)
				)
			)
		)
	)
	(zone
		(layers "In1.Cu" "In3.Cu" "In4.Cu" "In6.Cu")
		(hatch none 0.5)
		(connect_pads
			(clearance 0)
		)
		(min_thickness 0.25)
		(keepout
			(tracks not_allowed)
			(vias allowed)
			(pads allowed)
			(copperpour not_allowed)
			(footprints allowed)
		)
		(placement
			(enabled no)
			(sheetname "")
		)
		(fill yes
			(thermal_gap 0.5)
			(thermal_bridge_width 0.5)
			(island_removal_mode 0)
		)
		(polygon
			(pts
				(arc
					(start 222.339154 -468.831676)
					(mid 221.727141 -468.219282)
					(end 221.114874 -468.831422)
				)
				(arc
					(start 221.114874 -469.949022)
					(mid 221.727014 -470.561162)
					(end 222.339154 -469.949022)
				)
			)
		)
	)
	(zone
		(layers "In1.Cu" "In3.Cu" "In4.Cu" "In6.Cu")
		(hatch none 0.5)
		(connect_pads
			(clearance 0)
		)
		(min_thickness 0.25)
		(keepout
			(tracks not_allowed)
			(vias allowed)
			(pads allowed)
			(copperpour not_allowed)
			(footprints allowed)
		)
		(placement
			(enabled no)
			(sheetname "")
		)
		(fill yes
			(thermal_gap 0.5)
			(thermal_bridge_width 0.5)
			(island_removal_mode 0)
		)
		(polygon
			(pts
				(arc
					(start 26.15946 -348.416118)
					(mid 26.669873 -348.926912)
					(end 27.18054 -348.416372)
				)
				(arc
					(start 27.18054 -347.603572)
					(mid 26.67 -347.093032)
					(end 26.15946 -347.603572)
				)
			)
		)
	)
	(zone
		(layers "In1.Cu" "In3.Cu" "In4.Cu" "In6.Cu")
		(hatch none 0.5)
		(connect_pads
			(clearance 0)
		)
		(min_thickness 0.25)
		(keepout
			(tracks not_allowed)
			(vias allowed)
			(pads allowed)
			(copperpour not_allowed)
			(footprints allowed)
		)
		(placement
			(enabled no)
			(sheetname "")
		)
		(fill yes
			(thermal_gap 0.5)
			(thermal_bridge_width 0.5)
			(island_removal_mode 0)
		)
		(polygon
			(pts
				(arc
					(start 7.502906 -333.986886)
					(mid 6.992493 -333.476092)
					(end 6.481826 -333.986632)
				)
				(arc
					(start 6.481826 -334.799432)
					(mid 6.992366 -335.309972)
					(end 7.502906 -334.799432)
				)
			)
		)
	)
	(zone
		(layers "In1.Cu" "In3.Cu" "In4.Cu" "In6.Cu")
		(hatch none 0.5)
		(connect_pads
			(clearance 0)
		)
		(min_thickness 0.25)
		(keepout
			(tracks not_allowed)
			(vias allowed)
			(pads allowed)
			(copperpour not_allowed)
			(footprints allowed)
		)
		(placement
			(enabled no)
			(sheetname "")
		)
		(fill yes
			(thermal_gap 0.5)
			(thermal_bridge_width 0.5)
			(island_removal_mode 0)
		)
		(polygon
			(pts
				(arc
					(start 34.81959 -484.996236)
					(mid 35.330003 -485.50703)
					(end 35.84067 -484.99649)
				)
				(arc
					(start 35.84067 -484.18369)
					(mid 35.33013 -483.67315)
					(end 34.81959 -484.18369)
				)
			)
		)
	)
	(zone
		(layers "In1.Cu" "In3.Cu" "In4.Cu" "In6.Cu")
		(hatch none 0.5)
		(connect_pads
			(clearance 0)
		)
		(min_thickness 0.25)
		(keepout
			(tracks not_allowed)
			(vias allowed)
			(pads allowed)
			(copperpour not_allowed)
			(footprints allowed)
		)
		(placement
			(enabled no)
			(sheetname "")
		)
		(fill yes
			(thermal_gap 0.5)
			(thermal_bridge_width 0.5)
			(island_removal_mode 0)
		)
		(polygon
			(pts
				(arc
					(start 5.59054 -317.135764)
					(mid 5.080127 -316.62497)
					(end 4.56946 -317.13551)
				)
				(arc
					(start 4.56946 -317.94831)
					(mid 5.08 -318.45885)
					(end 5.59054 -317.94831)
				)
			)
		)
	)
	(zone
		(layers "In1.Cu" "In3.Cu" "In4.Cu" "In6.Cu")
		(hatch none 0.5)
		(connect_pads
			(clearance 0)
		)
		(min_thickness 0.25)
		(keepout
			(tracks not_allowed)
			(vias allowed)
			(pads allowed)
			(copperpour not_allowed)
			(footprints allowed)
		)
		(placement
			(enabled no)
			(sheetname "")
		)
		(fill yes
			(thermal_gap 0.5)
			(thermal_bridge_width 0.5)
			(island_removal_mode 0)
		)
		(polygon
			(pts
				(arc
					(start 16.76146 -136.41578)
					(mid 17.271873 -136.926574)
					(end 17.78254 -136.416034)
				)
				(arc
					(start 17.78254 -135.603234)
					(mid 17.272 -135.092694)
					(end 16.76146 -135.603234)
				)
			)
		)
	)
	(zone
		(layers "In1.Cu" "In3.Cu" "In4.Cu" "In6.Cu")
		(hatch none 0.5)
		(connect_pads
			(clearance 0)
		)
		(min_thickness 0.25)
		(keepout
			(tracks not_allowed)
			(vias allowed)
			(pads allowed)
			(copperpour not_allowed)
			(footprints allowed)
		)
		(placement
			(enabled no)
			(sheetname "")
		)
		(fill yes
			(thermal_gap 0.5)
			(thermal_bridge_width 0.5)
			(island_removal_mode 0)
		)
		(polygon
			(pts
				(arc
					(start 48.89754 -369.579652)
					(mid 48.387127 -369.068858)
					(end 47.87646 -369.579398)
				)
				(arc
					(start 47.87646 -370.392198)
					(mid 48.387 -370.902738)
					(end 48.89754 -370.392198)
				)
			)
		)
	)
	(zone
		(layers "In1.Cu" "In3.Cu" "In4.Cu" "In6.Cu")
		(hatch none 0.5)
		(connect_pads
			(clearance 0)
		)
		(min_thickness 0.25)
		(keepout
			(tracks not_allowed)
			(vias allowed)
			(pads allowed)
			(copperpour not_allowed)
			(footprints allowed)
		)
		(placement
			(enabled no)
			(sheetname "")
		)
		(fill yes
			(thermal_gap 0.5)
			(thermal_bridge_width 0.5)
			(island_removal_mode 0)
		)
		(polygon
			(pts
				(arc
					(start 222.339154 -172.631354)
					(mid 221.727141 -172.01896)
					(end 221.114874 -172.6311)
				)
				(arc
					(start 221.114874 -173.7487)
					(mid 221.727014 -174.36084)
					(end 222.339154 -173.7487)
				)
			)
		)
	)
	(zone
		(layers "In1.Cu" "In3.Cu" "In4.Cu" "In6.Cu")
		(hatch none 0.5)
		(connect_pads
			(clearance 0)
		)
		(min_thickness 0.25)
		(keepout
			(tracks not_allowed)
			(vias allowed)
			(pads allowed)
			(copperpour not_allowed)
			(footprints allowed)
		)
		(placement
			(enabled no)
			(sheetname "")
		)
		(fill yes
			(thermal_gap 0.5)
			(thermal_bridge_width 0.5)
			(island_removal_mode 0)
		)
		(polygon
			(pts
				(arc
					(start 7.502906 -390.336024)
					(mid 6.992493 -389.82523)
					(end 6.481826 -390.33577)
				)
				(arc
					(start 6.481826 -391.14857)
					(mid 6.992366 -391.65911)
					(end 7.502906 -391.14857)
				)
			)
		)
	)
	(zone
		(layers "In1.Cu" "In3.Cu" "In4.Cu" "In6.Cu")
		(hatch none 0.5)
		(connect_pads
			(clearance 0)
		)
		(min_thickness 0.25)
		(keepout
			(tracks not_allowed)
			(vias allowed)
			(pads allowed)
			(copperpour not_allowed)
			(footprints allowed)
		)
		(placement
			(enabled no)
			(sheetname "")
		)
		(fill yes
			(thermal_gap 0.5)
			(thermal_bridge_width 0.5)
			(island_removal_mode 0)
		)
		(polygon
			(pts
				(arc
					(start 6.481826 -440.79668)
					(mid 6.992239 -441.307474)
					(end 7.502906 -440.796934)
				)
				(arc
					(start 7.502906 -439.984134)
					(mid 6.992366 -439.473594)
					(end 6.481826 -439.984134)
				)
			)
		)
	)
	(zone
		(layers "In1.Cu" "In3.Cu" "In4.Cu" "In6.Cu")
		(hatch none 0.5)
		(connect_pads
			(clearance 0)
		)
		(min_thickness 0.25)
		(keepout
			(tracks not_allowed)
			(vias allowed)
			(pads allowed)
			(copperpour not_allowed)
			(footprints allowed)
		)
		(placement
			(enabled no)
			(sheetname "")
		)
		(fill yes
			(thermal_gap 0.5)
			(thermal_bridge_width 0.5)
			(island_removal_mode 0)
		)
		(polygon
			(pts
				(arc
					(start 7.502906 -184.736232)
					(mid 6.992493 -184.225438)
					(end 6.481826 -184.735978)
				)
				(arc
					(start 6.481826 -185.548778)
					(mid 6.992366 -186.059318)
					(end 7.502906 -185.548778)
				)
			)
		)
	)
	(zone
		(layers "In1.Cu" "In3.Cu" "In4.Cu" "In6.Cu")
		(hatch none 0.5)
		(connect_pads
			(clearance 0)
		)
		(min_thickness 0.25)
		(keepout
			(tracks not_allowed)
			(vias allowed)
			(pads allowed)
			(copperpour not_allowed)
			(footprints allowed)
		)
		(placement
			(enabled no)
			(sheetname "")
		)
		(fill yes
			(thermal_gap 0.5)
			(thermal_bridge_width 0.5)
			(island_removal_mode 0)
		)
		(polygon
			(pts
				(arc
					(start 32.00654 -32.60344)
					(mid 31.496127 -32.092646)
					(end 30.98546 -32.603186)
				)
				(arc
					(start 30.98546 -33.415986)
					(mid 31.496 -33.926526)
					(end 32.00654 -33.415986)
				)
			)
		)
	)
	(zone
		(layers "In1.Cu" "In3.Cu" "In4.Cu" "In6.Cu")
		(hatch none 0.5)
		(connect_pads
			(clearance 0)
		)
		(min_thickness 0.25)
		(keepout
			(tracks not_allowed)
			(vias allowed)
			(pads allowed)
			(copperpour not_allowed)
			(footprints allowed)
		)
		(placement
			(enabled no)
			(sheetname "")
		)
		(fill yes
			(thermal_gap 0.5)
			(thermal_bridge_width 0.5)
			(island_removal_mode 0)
		)
		(polygon
			(pts
				(arc
					(start 17.78254 -32.60344)
					(mid 17.272127 -32.092646)
					(end 16.76146 -32.603186)
				)
				(arc
					(start 16.76146 -33.415986)
					(mid 17.272 -33.926526)
					(end 17.78254 -33.415986)
				)
			)
		)
	)
	(zone
		(layers "In1.Cu" "In3.Cu" "In4.Cu" "In6.Cu")
		(hatch none 0.5)
		(connect_pads
			(clearance 0)
		)
		(min_thickness 0.25)
		(keepout
			(tracks not_allowed)
			(vias allowed)
			(pads allowed)
			(copperpour not_allowed)
			(footprints allowed)
		)
		(placement
			(enabled no)
			(sheetname "")
		)
		(fill yes
			(thermal_gap 0.5)
			(thermal_bridge_width 0.5)
			(island_removal_mode 0)
		)
		(polygon
			(pts
				(arc
					(start 6.481826 -412.748222)
					(mid 6.992239 -413.259016)
					(end 7.502906 -412.748476)
				)
				(arc
					(start 7.502906 -411.935676)
					(mid 6.992366 -411.425136)
					(end 6.481826 -411.935676)
				)
			)
		)
	)
	(zone
		(layers "In1.Cu" "In3.Cu" "In4.Cu" "In6.Cu")
		(hatch none 0.5)
		(connect_pads
			(clearance 0)
		)
		(min_thickness 0.25)
		(keepout
			(tracks not_allowed)
			(vias allowed)
			(pads allowed)
			(copperpour not_allowed)
			(footprints allowed)
		)
		(placement
			(enabled no)
			(sheetname "")
		)
		(fill yes
			(thermal_gap 0.5)
			(thermal_bridge_width 0.5)
			(island_removal_mode 0)
		)
		(polygon
			(pts
				(arc
					(start 44.907454 -162.279584)
					(mid 44.39666 -162.789997)
					(end 44.9072 -163.300664)
				)
				(arc
					(start 45.72 -163.300664)
					(mid 46.23054 -162.790124)
					(end 45.72 -162.279584)
				)
			)
		)
	)
	(zone
		(layers "In1.Cu" "In3.Cu" "In4.Cu" "In6.Cu")
		(hatch none 0.5)
		(connect_pads
			(clearance 0)
		)
		(min_thickness 0.25)
		(keepout
			(tracks not_allowed)
			(vias allowed)
			(pads allowed)
			(copperpour not_allowed)
			(footprints allowed)
		)
		(placement
			(enabled no)
			(sheetname "")
		)
		(fill yes
			(thermal_gap 0.5)
			(thermal_bridge_width 0.5)
			(island_removal_mode 0)
		)
		(polygon
			(pts
				(arc
					(start 35.84067 -72.183752)
					(mid 35.330257 -71.672958)
					(end 34.81959 -72.183498)
				)
				(arc
					(start 34.81959 -72.996298)
					(mid 35.33013 -73.506838)
					(end 35.84067 -72.996298)
				)
			)
		)
	)
	(zone
		(layers "In1.Cu" "In3.Cu" "In4.Cu" "In6.Cu")
		(hatch none 0.5)
		(connect_pads
			(clearance 0)
		)
		(min_thickness 0.25)
		(keepout
			(tracks not_allowed)
			(vias allowed)
			(pads allowed)
			(copperpour not_allowed)
			(footprints allowed)
		)
		(placement
			(enabled no)
			(sheetname "")
		)
		(fill yes
			(thermal_gap 0.5)
			(thermal_bridge_width 0.5)
			(island_removal_mode 0)
		)
		(polygon
			(pts
				(arc
					(start 220.840554 -54.583838)
					(mid 220.330141 -54.073044)
					(end 219.819474 -54.583584)
				)
				(arc
					(start 219.819474 -55.396384)
					(mid 220.330014 -55.906924)
					(end 220.840554 -55.396384)
				)
			)
		)
	)
	(zone
		(layers "In1.Cu" "In3.Cu" "In4.Cu" "In6.Cu")
		(hatch none 0.5)
		(connect_pads
			(clearance 0)
		)
		(min_thickness 0.25)
		(keepout
			(tracks not_allowed)
			(vias allowed)
			(pads allowed)
			(copperpour not_allowed)
			(footprints allowed)
		)
		(placement
			(enabled no)
			(sheetname "")
		)
		(fill yes
			(thermal_gap 0.5)
			(thermal_bridge_width 0.5)
			(island_removal_mode 0)
		)
		(polygon
			(pts
				(arc
					(start 7.502906 -211.13623)
					(mid 6.992493 -210.625436)
					(end 6.481826 -211.135976)
				)
				(arc
					(start 6.481826 -211.948776)
					(mid 6.992366 -212.459316)
					(end 7.502906 -211.948776)
				)
			)
		)
	)
	(zone
		(layers "In1.Cu" "In3.Cu" "In4.Cu" "In6.Cu")
		(hatch none 0.5)
		(connect_pads
			(clearance 0)
		)
		(min_thickness 0.25)
		(keepout
			(tracks not_allowed)
			(vias allowed)
			(pads allowed)
			(copperpour not_allowed)
			(footprints allowed)
		)
		(placement
			(enabled no)
			(sheetname "")
		)
		(fill yes
			(thermal_gap 0.5)
			(thermal_bridge_width 0.5)
			(island_removal_mode 0)
		)
		(polygon
			(pts
				(arc
					(start 27.18054 -38.603428)
					(mid 26.67 -38.092888)
					(end 26.15946 -38.603428)
				)
				(arc
					(start 26.15946 -39.415974)
					(mid 26.669873 -39.926768)
					(end 27.18054 -39.416228)
				)
			)
		)
	)
	(zone
		(layers "In1.Cu" "In3.Cu" "In4.Cu" "In6.Cu")
		(hatch none 0.5)
		(connect_pads
			(clearance 0)
		)
		(min_thickness 0.25)
		(keepout
			(tracks not_allowed)
			(vias allowed)
			(pads allowed)
			(copperpour not_allowed)
			(footprints allowed)
		)
		(placement
			(enabled no)
			(sheetname "")
		)
		(fill yes
			(thermal_gap 0.5)
			(thermal_bridge_width 0.5)
			(island_removal_mode 0)
		)
		(polygon
			(pts
				(arc
					(start 25.88514 -36.050982)
					(mid 25.273 -35.438842)
					(end 24.66086 -36.050982)
				)
				(arc
					(start 24.66086 -37.168328)
					(mid 25.272873 -37.780722)
					(end 25.88514 -37.168582)
				)
			)
		)
	)
	(zone
		(layers "In1.Cu" "In3.Cu" "In4.Cu" "In6.Cu")
		(hatch none 0.5)
		(connect_pads
			(clearance 0)
		)
		(min_thickness 0.25)
		(keepout
			(tracks not_allowed)
			(vias allowed)
			(pads allowed)
			(copperpour not_allowed)
			(footprints allowed)
		)
		(placement
			(enabled no)
			(sheetname "")
		)
		(fill yes
			(thermal_gap 0.5)
			(thermal_bridge_width 0.5)
			(island_removal_mode 0)
		)
		(polygon
			(pts
				(arc
					(start 5.59054 -173.535594)
					(mid 5.080127 -173.0248)
					(end 4.56946 -173.53534)
				)
				(arc
					(start 4.56946 -174.34814)
					(mid 5.08 -174.85868)
					(end 5.59054 -174.34814)
				)
			)
		)
	)
	(zone
		(layers "In1.Cu" "In3.Cu" "In4.Cu" "In6.Cu")
		(hatch none 0.5)
		(connect_pads
			(clearance 0)
		)
		(min_thickness 0.25)
		(keepout
			(tracks not_allowed)
			(vias allowed)
			(pads allowed)
			(copperpour not_allowed)
			(footprints allowed)
		)
		(placement
			(enabled no)
			(sheetname "")
		)
		(fill yes
			(thermal_gap 0.5)
			(thermal_bridge_width 0.5)
			(island_removal_mode 0)
		)
		(polygon
			(pts
				(arc
					(start 5.59054 -354.735638)
					(mid 5.080127 -354.224844)
					(end 4.56946 -354.735384)
				)
				(arc
					(start 4.56946 -355.548184)
					(mid 5.08 -356.058724)
					(end 5.59054 -355.548184)
				)
			)
		)
	)
	(zone
		(layers "In1.Cu" "In3.Cu" "In4.Cu" "In6.Cu")
		(hatch none 0.5)
		(connect_pads
			(clearance 0)
		)
		(min_thickness 0.25)
		(keepout
			(tracks not_allowed)
			(vias allowed)
			(pads allowed)
			(copperpour not_allowed)
			(footprints allowed)
		)
		(placement
			(enabled no)
			(sheetname "")
		)
		(fill yes
			(thermal_gap 0.5)
			(thermal_bridge_width 0.5)
			(island_removal_mode 0)
		)
		(polygon
			(pts
				(arc
					(start 16.76146 -239.415828)
					(mid 17.271873 -239.926622)
					(end 17.78254 -239.416082)
				)
				(arc
					(start 17.78254 -238.603282)
					(mid 17.272 -238.092742)
					(end 16.76146 -238.603282)
				)
			)
		)
	)
	(zone
		(layers "In1.Cu" "In3.Cu" "In4.Cu" "In6.Cu")
		(hatch none 0.5)
		(connect_pads
			(clearance 0)
		)
		(min_thickness 0.25)
		(keepout
			(tracks not_allowed)
			(vias allowed)
			(pads allowed)
			(copperpour not_allowed)
			(footprints allowed)
		)
		(placement
			(enabled no)
			(sheetname "")
		)
		(fill yes
			(thermal_gap 0.5)
			(thermal_bridge_width 0.5)
			(island_removal_mode 0)
		)
		(polygon
			(pts
				(arc
					(start 7.502906 -288.336228)
					(mid 6.992493 -287.825434)
					(end 6.481826 -288.335974)
				)
				(arc
					(start 6.481826 -289.148774)
					(mid 6.992366 -289.659314)
					(end 7.502906 -289.148774)
				)
			)
		)
	)
	(zone
		(layers "In1.Cu" "In3.Cu" "In4.Cu" "In6.Cu")
		(hatch none 0.5)
		(connect_pads
			(clearance 0)
		)
		(min_thickness 0.25)
		(keepout
			(tracks not_allowed)
			(vias allowed)
			(pads allowed)
			(copperpour not_allowed)
			(footprints allowed)
		)
		(placement
			(enabled no)
			(sheetname "")
		)
		(fill yes
			(thermal_gap 0.5)
			(thermal_bridge_width 0.5)
			(island_removal_mode 0)
		)
		(polygon
			(pts
				(arc
					(start 5.59054 -429.535336)
					(mid 5.080127 -429.024542)
					(end 4.56946 -429.535082)
				)
				(arc
					(start 4.56946 -430.347882)
					(mid 5.08 -430.858422)
					(end 5.59054 -430.347882)
				)
			)
		)
	)
	(zone
		(layers "In1.Cu" "In3.Cu" "In4.Cu" "In6.Cu")
		(hatch none 0.5)
		(connect_pads
			(clearance 0)
		)
		(min_thickness 0.25)
		(keepout
			(tracks not_allowed)
			(vias allowed)
			(pads allowed)
			(copperpour not_allowed)
			(footprints allowed)
		)
		(placement
			(enabled no)
			(sheetname "")
		)
		(fill yes
			(thermal_gap 0.5)
			(thermal_bridge_width 0.5)
			(island_removal_mode 0)
		)
		(polygon
			(pts
				(arc
					(start 222.339154 -280.431494)
					(mid 221.727141 -279.8191)
					(end 221.114874 -280.43124)
				)
				(arc
					(start 221.114874 -281.54884)
					(mid 221.727014 -282.16098)
					(end 222.339154 -281.54884)
				)
			)
		)
	)
	(zone
		(layers "In1.Cu" "In3.Cu" "In4.Cu" "In6.Cu")
		(hatch none 0.5)
		(connect_pads
			(clearance 0)
		)
		(min_thickness 0.25)
		(keepout
			(tracks not_allowed)
			(vias allowed)
			(pads allowed)
			(copperpour not_allowed)
			(footprints allowed)
		)
		(placement
			(enabled no)
			(sheetname "")
		)
		(fill yes
			(thermal_gap 0.5)
			(thermal_bridge_width 0.5)
			(island_removal_mode 0)
		)
		(polygon
			(pts
				(arc
					(start 25.88514 -18.451068)
					(mid 25.273 -17.838928)
					(end 24.66086 -18.451068)
				)
				(arc
					(start 24.66086 -19.568414)
					(mid 25.272873 -20.180808)
					(end 25.88514 -19.568668)
				)
			)
		)
	)
	(zone
		(layers "In1.Cu" "In3.Cu" "In4.Cu" "In6.Cu")
		(hatch none 0.5)
		(connect_pads
			(clearance 0)
		)
		(min_thickness 0.25)
		(keepout
			(tracks not_allowed)
			(vias allowed)
			(pads allowed)
			(copperpour not_allowed)
			(footprints allowed)
		)
		(placement
			(enabled no)
			(sheetname "")
		)
		(fill yes
			(thermal_gap 0.5)
			(thermal_bridge_width 0.5)
			(island_removal_mode 0)
		)
		(polygon
			(pts
				(arc
					(start 6.481826 -292.348412)
					(mid 6.992239 -292.859206)
					(end 7.502906 -292.348666)
				)
				(arc
					(start 7.502906 -291.535866)
					(mid 6.992366 -291.025326)
					(end 6.481826 -291.535866)
				)
			)
		)
	)
	(zone
		(layers "In1.Cu" "In3.Cu" "In4.Cu" "In6.Cu")
		(hatch none 0.5)
		(connect_pads
			(clearance 0)
		)
		(min_thickness 0.25)
		(keepout
			(tracks not_allowed)
			(vias allowed)
			(pads allowed)
			(copperpour not_allowed)
			(footprints allowed)
		)
		(placement
			(enabled no)
			(sheetname "")
		)
		(fill yes
			(thermal_gap 0.5)
			(thermal_bridge_width 0.5)
			(island_removal_mode 0)
		)
		(polygon
			(pts
				(arc
					(start 5.59054 -219.135706)
					(mid 5.080127 -218.624912)
					(end 4.56946 -219.135452)
				)
				(arc
					(start 4.56946 -219.948252)
					(mid 5.08 -220.458792)
					(end 5.59054 -219.948252)
				)
			)
		)
	)
	(zone
		(layers "In1.Cu" "In3.Cu" "In4.Cu" "In6.Cu")
		(hatch none 0.5)
		(connect_pads
			(clearance 0)
		)
		(min_thickness 0.25)
		(keepout
			(tracks not_allowed)
			(vias allowed)
			(pads allowed)
			(copperpour not_allowed)
			(footprints allowed)
		)
		(placement
			(enabled no)
			(sheetname "")
		)
		(fill yes
			(thermal_gap 0.5)
			(thermal_bridge_width 0.5)
			(island_removal_mode 0)
		)
		(polygon
			(pts
				(arc
					(start 4.56946 -445.54775)
					(mid 5.079873 -446.058544)
					(end 5.59054 -445.548004)
				)
				(arc
					(start 5.59054 -444.735204)
					(mid 5.08 -444.224664)
					(end 4.56946 -444.735204)
				)
			)
		)
	)
	(zone
		(layers "In1.Cu" "In3.Cu" "In4.Cu" "In6.Cu")
		(hatch none 0.5)
		(connect_pads
			(clearance 0)
		)
		(min_thickness 0.25)
		(keepout
			(tracks not_allowed)
			(vias allowed)
			(pads allowed)
			(copperpour not_allowed)
			(footprints allowed)
		)
		(placement
			(enabled no)
			(sheetname "")
		)
		(fill yes
			(thermal_gap 0.5)
			(thermal_bridge_width 0.5)
			(island_removal_mode 0)
		)
		(polygon
			(pts
				(arc
					(start 233.897424 -266.57935)
					(mid 233.386884 -266.06881)
					(end 232.876344 -266.57935)
				)
				(arc
					(start 232.876344 -267.391896)
					(mid 233.386757 -267.90269)
					(end 233.897424 -267.39215)
				)
			)
		)
	)
	(zone
		(layers "In1.Cu" "In3.Cu" "In4.Cu" "In6.Cu")
		(hatch none 0.5)
		(connect_pads
			(clearance 0)
		)
		(min_thickness 0.25)
		(keepout
			(tracks not_allowed)
			(vias allowed)
			(pads allowed)
			(copperpour not_allowed)
			(footprints allowed)
		)
		(placement
			(enabled no)
			(sheetname "")
		)
		(fill yes
			(thermal_gap 0.5)
			(thermal_bridge_width 0.5)
			(island_removal_mode 0)
		)
		(polygon
			(pts
				(arc
					(start 7.502906 -427.984412)
					(mid 6.992493 -427.473618)
					(end 6.481826 -427.984158)
				)
				(arc
					(start 6.481826 -428.796958)
					(mid 6.992366 -429.307498)
					(end 7.502906 -428.796958)
				)
			)
		)
	)
	(zone
		(layers "In1.Cu" "In3.Cu" "In4.Cu" "In6.Cu")
		(hatch none 0.5)
		(connect_pads
			(clearance 0)
		)
		(min_thickness 0.25)
		(keepout
			(tracks not_allowed)
			(vias allowed)
			(pads allowed)
			(copperpour not_allowed)
			(footprints allowed)
		)
		(placement
			(enabled no)
			(sheetname "")
		)
		(fill yes
			(thermal_gap 0.5)
			(thermal_bridge_width 0.5)
			(island_removal_mode 0)
		)
		(polygon
			(pts
				(arc
					(start 6.481826 -298.74845)
					(mid 6.992239 -299.259244)
					(end 7.502906 -298.748704)
				)
				(arc
					(start 7.502906 -297.935904)
					(mid 6.992366 -297.425364)
					(end 6.481826 -297.935904)
				)
			)
		)
	)
	(zone
		(layers "In1.Cu" "In3.Cu" "In4.Cu" "In6.Cu")
		(hatch none 0.5)
		(connect_pads
			(clearance 0)
		)
		(min_thickness 0.25)
		(keepout
			(tracks not_allowed)
			(vias allowed)
			(pads allowed)
			(copperpour not_allowed)
			(footprints allowed)
		)
		(placement
			(enabled no)
			(sheetname "")
		)
		(fill yes
			(thermal_gap 0.5)
			(thermal_bridge_width 0.5)
			(island_removal_mode 0)
		)
		(polygon
			(pts
				(arc
					(start 222.339154 -365.831628)
					(mid 221.727141 -365.219234)
					(end 221.114874 -365.831374)
				)
				(arc
					(start 221.114874 -366.948974)
					(mid 221.727014 -367.561114)
					(end 222.339154 -366.948974)
				)
			)
		)
	)
	(zone
		(layers "In1.Cu" "In3.Cu" "In4.Cu" "In6.Cu")
		(hatch none 0.5)
		(connect_pads
			(clearance 0)
		)
		(min_thickness 0.25)
		(keepout
			(tracks not_allowed)
			(vias allowed)
			(pads allowed)
			(copperpour not_allowed)
			(footprints allowed)
		)
		(placement
			(enabled no)
			(sheetname "")
		)
		(fill yes
			(thermal_gap 0.5)
			(thermal_bridge_width 0.5)
			(island_removal_mode 0)
		)
		(polygon
			(pts
				(arc
					(start 5.59054 -348.3356)
					(mid 5.080127 -347.824806)
					(end 4.56946 -348.335346)
				)
				(arc
					(start 4.56946 -349.148146)
					(mid 5.08 -349.658686)
					(end 5.59054 -349.148146)
				)
			)
		)
	)
	(zone
		(layers "In1.Cu" "In3.Cu" "In4.Cu" "In6.Cu")
		(hatch none 0.5)
		(connect_pads
			(clearance 0)
		)
		(min_thickness 0.25)
		(keepout
			(tracks not_allowed)
			(vias allowed)
			(pads allowed)
			(copperpour not_allowed)
			(footprints allowed)
		)
		(placement
			(enabled no)
			(sheetname "")
		)
		(fill yes
			(thermal_gap 0.5)
			(thermal_bridge_width 0.5)
			(island_removal_mode 0)
		)
		(polygon
			(pts
				(arc
					(start 35.84067 -179.983892)
					(mid 35.330257 -179.473098)
					(end 34.81959 -179.983638)
				)
				(arc
					(start 34.81959 -180.796438)
					(mid 35.33013 -181.306978)
					(end 35.84067 -180.796438)
				)
			)
		)
	)
	(zone
		(layers "In1.Cu" "In3.Cu" "In4.Cu" "In6.Cu")
		(hatch none 0.5)
		(connect_pads
			(clearance 0)
		)
		(min_thickness 0.25)
		(keepout
			(tracks not_allowed)
			(vias allowed)
			(pads allowed)
			(copperpour not_allowed)
			(footprints allowed)
		)
		(placement
			(enabled no)
			(sheetname "")
		)
		(fill yes
			(thermal_gap 0.5)
			(thermal_bridge_width 0.5)
			(island_removal_mode 0)
		)
		(polygon
			(pts
				(arc
					(start 27.18054 -119.20347)
					(mid 26.67 -118.69293)
					(end 26.15946 -119.20347)
				)
				(arc
					(start 26.15946 -120.016016)
					(mid 26.669873 -120.52681)
					(end 27.18054 -120.01627)
				)
			)
		)
	)
	(zone
		(layers "In1.Cu" "In3.Cu" "In4.Cu" "In6.Cu")
		(hatch none 0.5)
		(connect_pads
			(clearance 0)
		)
		(min_thickness 0.25)
		(keepout
			(tracks not_allowed)
			(vias allowed)
			(pads allowed)
			(copperpour not_allowed)
			(footprints allowed)
		)
		(placement
			(enabled no)
			(sheetname "")
		)
		(fill yes
			(thermal_gap 0.5)
			(thermal_bridge_width 0.5)
			(island_removal_mode 0)
		)
		(polygon
			(pts
				(arc
					(start 222.339154 -285.231586)
					(mid 221.727141 -284.619192)
					(end 221.114874 -285.231332)
				)
				(arc
					(start 221.114874 -286.348932)
					(mid 221.727014 -286.961072)
					(end 222.339154 -286.348932)
				)
			)
		)
	)
	(zone
		(layers "In1.Cu" "In3.Cu" "In4.Cu" "In6.Cu")
		(hatch none 0.5)
		(connect_pads
			(clearance 0)
		)
		(min_thickness 0.25)
		(keepout
			(tracks not_allowed)
			(vias allowed)
			(pads allowed)
			(copperpour not_allowed)
			(footprints allowed)
		)
		(placement
			(enabled no)
			(sheetname "")
		)
		(fill yes
			(thermal_gap 0.5)
			(thermal_bridge_width 0.5)
			(island_removal_mode 0)
		)
		(polygon
			(pts
				(arc
					(start 222.339154 -486.43159)
					(mid 221.727141 -485.819196)
					(end 221.114874 -486.431336)
				)
				(arc
					(start 221.114874 -487.548936)
					(mid 221.727014 -488.161076)
					(end 222.339154 -487.548936)
				)
			)
		)
	)
	(zone
		(layers "In1.Cu" "In3.Cu" "In4.Cu" "In6.Cu")
		(hatch none 0.5)
		(connect_pads
			(clearance 0)
		)
		(min_thickness 0.25)
		(keepout
			(tracks not_allowed)
			(vias allowed)
			(pads allowed)
			(copperpour not_allowed)
			(footprints allowed)
		)
		(placement
			(enabled no)
			(sheetname "")
		)
		(fill yes
			(thermal_gap 0.5)
			(thermal_bridge_width 0.5)
			(island_removal_mode 0)
		)
		(polygon
			(pts
				(arc
					(start 222.339154 -74.431398)
					(mid 221.727141 -73.819004)
					(end 221.114874 -74.431144)
				)
				(arc
					(start 221.114874 -75.548744)
					(mid 221.727014 -76.160884)
					(end 222.339154 -75.548744)
				)
			)
		)
	)
	(zone
		(layers "In1.Cu" "In3.Cu" "In4.Cu" "In6.Cu")
		(hatch none 0.5)
		(connect_pads
			(clearance 0)
		)
		(min_thickness 0.25)
		(keepout
			(tracks not_allowed)
			(vias allowed)
			(pads allowed)
			(copperpour not_allowed)
			(footprints allowed)
		)
		(placement
			(enabled no)
			(sheetname "")
		)
		(fill yes
			(thermal_gap 0.5)
			(thermal_bridge_width 0.5)
			(island_removal_mode 0)
		)
		(polygon
			(pts
				(arc
					(start 27.18054 -437.803798)
					(mid 26.670127 -437.293004)
					(end 26.15946 -437.803544)
				)
				(arc
					(start 26.15946 -438.616344)
					(mid 26.67 -439.126884)
					(end 27.18054 -438.616344)
				)
			)
		)
	)
	(zone
		(layers "In1.Cu" "In3.Cu" "In4.Cu" "In6.Cu")
		(hatch none 0.5)
		(connect_pads
			(clearance 0)
		)
		(min_thickness 0.25)
		(keepout
			(tracks not_allowed)
			(vias allowed)
			(pads allowed)
			(copperpour not_allowed)
			(footprints allowed)
		)
		(placement
			(enabled no)
			(sheetname "")
		)
		(fill yes
			(thermal_gap 0.5)
			(thermal_bridge_width 0.5)
			(island_removal_mode 0)
		)
		(polygon
			(pts
				(arc
					(start 37.33927 -486.43159)
					(mid 36.727257 -485.819196)
					(end 36.11499 -486.431336)
				)
				(arc
					(start 36.11499 -487.548936)
					(mid 36.72713 -488.161076)
					(end 37.33927 -487.548936)
				)
			)
		)
	)
	(zone
		(layers "In1.Cu" "In3.Cu" "In4.Cu" "In6.Cu")
		(hatch none 0.5)
		(connect_pads
			(clearance 0)
		)
		(min_thickness 0.25)
		(keepout
			(tracks not_allowed)
			(vias allowed)
			(pads allowed)
			(copperpour not_allowed)
			(footprints allowed)
		)
		(placement
			(enabled no)
			(sheetname "")
		)
		(fill yes
			(thermal_gap 0.5)
			(thermal_bridge_width 0.5)
			(island_removal_mode 0)
		)
		(polygon
			(pts
				(arc
					(start 220.840554 -385.983988)
					(mid 220.330141 -385.473194)
					(end 219.819474 -385.983734)
				)
				(arc
					(start 219.819474 -386.796534)
					(mid 220.330014 -387.307074)
					(end 220.840554 -386.796534)
				)
			)
		)
	)
	(zone
		(layers "In1.Cu" "In3.Cu" "In4.Cu" "In6.Cu")
		(hatch none 0.5)
		(connect_pads
			(clearance 0)
		)
		(min_thickness 0.25)
		(keepout
			(tracks not_allowed)
			(vias allowed)
			(pads allowed)
			(copperpour not_allowed)
			(footprints allowed)
		)
		(placement
			(enabled no)
			(sheetname "")
		)
		(fill yes
			(thermal_gap 0.5)
			(thermal_bridge_width 0.5)
			(island_removal_mode 0)
		)
		(polygon
			(pts
				(arc
					(start 35.84067 -273.38401)
					(mid 35.330257 -272.873216)
					(end 34.81959 -273.383756)
				)
				(arc
					(start 34.81959 -274.196556)
					(mid 35.33013 -274.707096)
					(end 35.84067 -274.196556)
				)
			)
		)
	)
	(zone
		(layers "In1.Cu" "In3.Cu" "In4.Cu" "In6.Cu")
		(hatch none 0.5)
		(connect_pads
			(clearance 0)
		)
		(min_thickness 0.25)
		(keepout
			(tracks not_allowed)
			(vias allowed)
			(pads allowed)
			(copperpour not_allowed)
			(footprints allowed)
		)
		(placement
			(enabled no)
			(sheetname "")
		)
		(fill yes
			(thermal_gap 0.5)
			(thermal_bridge_width 0.5)
			(island_removal_mode 0)
		)
		(polygon
			(pts
				(arc
					(start 7.502906 -227.136198)
					(mid 6.992493 -226.625404)
					(end 6.481826 -227.135944)
				)
				(arc
					(start 6.481826 -227.948744)
					(mid 6.992366 -228.459284)
					(end 7.502906 -227.948744)
				)
			)
		)
	)
	(zone
		(layers "In1.Cu" "In3.Cu" "In4.Cu" "In6.Cu")
		(hatch none 0.5)
		(connect_pads
			(clearance 0)
		)
		(min_thickness 0.25)
		(keepout
			(tracks not_allowed)
			(vias allowed)
			(pads allowed)
			(copperpour not_allowed)
			(footprints allowed)
		)
		(placement
			(enabled no)
			(sheetname "")
		)
		(fill yes
			(thermal_gap 0.5)
			(thermal_bridge_width 0.5)
			(island_removal_mode 0)
		)
		(polygon
			(pts
				(arc
					(start 5.59054 -323.535548)
					(mid 5.080127 -323.024754)
					(end 4.56946 -323.535294)
				)
				(arc
					(start 4.56946 -324.348094)
					(mid 5.08 -324.858634)
					(end 5.59054 -324.348094)
				)
			)
		)
	)
	(zone
		(layers "In1.Cu" "In3.Cu" "In4.Cu" "In6.Cu")
		(hatch none 0.5)
		(connect_pads
			(clearance 0)
		)
		(min_thickness 0.25)
		(keepout
			(tracks not_allowed)
			(vias allowed)
			(pads allowed)
			(copperpour not_allowed)
			(footprints allowed)
		)
		(placement
			(enabled no)
			(sheetname "")
		)
		(fill yes
			(thermal_gap 0.5)
			(thermal_bridge_width 0.5)
			(island_removal_mode 0)
		)
		(polygon
			(pts
				(arc
					(start 5.59054 -391.935462)
					(mid 5.080127 -391.424668)
					(end 4.56946 -391.935208)
				)
				(arc
					(start 4.56946 -392.748008)
					(mid 5.08 -393.258548)
					(end 5.59054 -392.748008)
				)
			)
		)
	)
	(zone
		(layers "In1.Cu" "In3.Cu" "In4.Cu" "In6.Cu")
		(hatch none 0.5)
		(connect_pads
			(clearance 0)
		)
		(min_thickness 0.25)
		(keepout
			(tracks not_allowed)
			(vias allowed)
			(pads allowed)
			(copperpour not_allowed)
			(footprints allowed)
		)
		(placement
			(enabled no)
			(sheetname "")
		)
		(fill yes
			(thermal_gap 0.5)
			(thermal_bridge_width 0.5)
			(island_removal_mode 0)
		)
		(polygon
			(pts
				(arc
					(start 6.481826 -329.14844)
					(mid 6.992239 -329.659234)
					(end 7.502906 -329.148694)
				)
				(arc
					(start 7.502906 -328.335894)
					(mid 6.992366 -327.825354)
					(end 6.481826 -328.335894)
				)
			)
		)
	)
	(zone
		(layers "In1.Cu" "In3.Cu" "In4.Cu" "In6.Cu")
		(hatch none 0.5)
		(connect_pads
			(clearance 0)
		)
		(min_thickness 0.25)
		(keepout
			(tracks not_allowed)
			(vias allowed)
			(pads allowed)
			(copperpour not_allowed)
			(footprints allowed)
		)
		(placement
			(enabled no)
			(sheetname "")
		)
		(fill yes
			(thermal_gap 0.5)
			(thermal_bridge_width 0.5)
			(island_removal_mode 0)
		)
		(polygon
			(pts
				(arc
					(start 35.84067 -260.583934)
					(mid 35.330257 -260.07314)
					(end 34.81959 -260.58368)
				)
				(arc
					(start 34.81959 -261.39648)
					(mid 35.33013 -261.90702)
					(end 35.84067 -261.39648)
				)
			)
		)
	)
	(zone
		(layers "In1.Cu" "In3.Cu" "In4.Cu" "In6.Cu")
		(hatch none 0.5)
		(connect_pads
			(clearance 0)
		)
		(min_thickness 0.25)
		(keepout
			(tracks not_allowed)
			(vias allowed)
			(pads allowed)
			(copperpour not_allowed)
			(footprints allowed)
		)
		(placement
			(enabled no)
			(sheetname "")
		)
		(fill yes
			(thermal_gap 0.5)
			(thermal_bridge_width 0.5)
			(island_removal_mode 0)
		)
		(polygon
			(pts
				(arc
					(start 233.897424 -472.579446)
					(mid 233.386884 -472.068906)
					(end 232.876344 -472.579446)
				)
				(arc
					(start 232.876344 -473.391992)
					(mid 233.386757 -473.902786)
					(end 233.897424 -473.392246)
				)
			)
		)
	)
	(zone
		(layers "In1.Cu" "In3.Cu" "In4.Cu" "In6.Cu")
		(hatch none 0.5)
		(connect_pads
			(clearance 0)
		)
		(min_thickness 0.25)
		(keepout
			(tracks not_allowed)
			(vias allowed)
			(pads allowed)
			(copperpour not_allowed)
			(footprints allowed)
		)
		(placement
			(enabled no)
			(sheetname "")
		)
		(fill yes
			(thermal_gap 0.5)
			(thermal_bridge_width 0.5)
			(island_removal_mode 0)
		)
		(polygon
			(pts
				(arc
					(start 5.59054 -179.935632)
					(mid 5.080127 -179.424838)
					(end 4.56946 -179.935378)
				)
				(arc
					(start 4.56946 -180.748178)
					(mid 5.08 -181.258718)
					(end 5.59054 -180.748178)
				)
			)
		)
	)
	(zone
		(layers "In1.Cu" "In3.Cu" "In4.Cu" "In6.Cu")
		(hatch none 0.5)
		(connect_pads
			(clearance 0)
		)
		(min_thickness 0.25)
		(keepout
			(tracks not_allowed)
			(vias allowed)
			(pads allowed)
			(copperpour not_allowed)
			(footprints allowed)
		)
		(placement
			(enabled no)
			(sheetname "")
		)
		(fill yes
			(thermal_gap 0.5)
			(thermal_bridge_width 0.5)
			(island_removal_mode 0)
		)
		(polygon
			(pts
				(arc
					(start 6.481826 -406.348184)
					(mid 6.992239 -406.858978)
					(end 7.502906 -406.348438)
				)
				(arc
					(start 7.502906 -405.535638)
					(mid 6.992366 -405.025098)
					(end 6.481826 -405.535638)
				)
			)
		)
	)
	(zone
		(layers "In1.Cu" "In3.Cu" "In4.Cu" "In6.Cu")
		(hatch none 0.5)
		(connect_pads
			(clearance 0)
		)
		(min_thickness 0.25)
		(keepout
			(tracks not_allowed)
			(vias allowed)
			(pads allowed)
			(copperpour not_allowed)
			(footprints allowed)
		)
		(placement
			(enabled no)
			(sheetname "")
		)
		(fill yes
			(thermal_gap 0.5)
			(thermal_bridge_width 0.5)
			(island_removal_mode 0)
		)
		(polygon
			(pts
				(arc
					(start 42.92854 -238.58474)
					(mid 42.418127 -238.073946)
					(end 41.90746 -238.584486)
				)
				(arc
					(start 41.90746 -239.397286)
					(mid 42.418 -239.907826)
					(end 42.92854 -239.397286)
				)
			)
		)
	)
	(zone
		(layers "In1.Cu" "In3.Cu" "In4.Cu" "In6.Cu")
		(hatch none 0.5)
		(connect_pads
			(clearance 0)
		)
		(min_thickness 0.25)
		(keepout
			(tracks not_allowed)
			(vias allowed)
			(pads allowed)
			(copperpour not_allowed)
			(footprints allowed)
		)
		(placement
			(enabled no)
			(sheetname "")
		)
		(fill yes
			(thermal_gap 0.5)
			(thermal_bridge_width 0.5)
			(island_removal_mode 0)
		)
		(polygon
			(pts
				(arc
					(start 220.840554 -479.384106)
					(mid 220.330141 -478.873312)
					(end 219.819474 -479.383852)
				)
				(arc
					(start 219.819474 -480.196652)
					(mid 220.330014 -480.707192)
					(end 220.840554 -480.196652)
				)
			)
		)
	)
	(zone
		(layers "In1.Cu" "In3.Cu" "In4.Cu" "In6.Cu")
		(hatch none 0.5)
		(connect_pads
			(clearance 0)
		)
		(min_thickness 0.25)
		(keepout
			(tracks not_allowed)
			(vias allowed)
			(pads allowed)
			(copperpour not_allowed)
			(footprints allowed)
		)
		(placement
			(enabled no)
			(sheetname "")
		)
		(fill yes
			(thermal_gap 0.5)
			(thermal_bridge_width 0.5)
			(island_removal_mode 0)
		)
		(polygon
			(pts
				(arc
					(start 26.15946 -330.816204)
					(mid 26.669873 -331.326998)
					(end 27.18054 -330.816458)
				)
				(arc
					(start 27.18054 -330.003658)
					(mid 26.67 -329.493118)
					(end 26.15946 -330.003658)
				)
			)
		)
	)
	(zone
		(layers "In1.Cu" "In3.Cu" "In4.Cu" "In6.Cu")
		(hatch none 0.5)
		(connect_pads
			(clearance 0)
		)
		(min_thickness 0.25)
		(keepout
			(tracks not_allowed)
			(vias allowed)
			(pads allowed)
			(copperpour not_allowed)
			(footprints allowed)
		)
		(placement
			(enabled no)
			(sheetname "")
		)
		(fill yes
			(thermal_gap 0.5)
			(thermal_bridge_width 0.5)
			(island_removal_mode 0)
		)
		(polygon
			(pts
				(arc
					(start 24.66086 -333.36865)
					(mid 25.272873 -333.981044)
					(end 25.88514 -333.368904)
				)
				(arc
					(start 25.88514 -332.251304)
					(mid 25.273 -331.639164)
					(end 24.66086 -332.251304)
				)
			)
		)
	)
	(zone
		(layers "In1.Cu" "In3.Cu" "In4.Cu" "In6.Cu")
		(hatch none 0.5)
		(connect_pads
			(clearance 0)
		)
		(min_thickness 0.25)
		(keepout
			(tracks not_allowed)
			(vias allowed)
			(pads allowed)
			(copperpour not_allowed)
			(footprints allowed)
		)
		(placement
			(enabled no)
			(sheetname "")
		)
		(fill yes
			(thermal_gap 0.5)
			(thermal_bridge_width 0.5)
			(island_removal_mode 0)
		)
		(polygon
			(pts
				(arc
					(start 7.502906 -415.136076)
					(mid 6.992493 -414.625282)
					(end 6.481826 -415.135822)
				)
				(arc
					(start 6.481826 -415.948622)
					(mid 6.992366 -416.459162)
					(end 7.502906 -415.948622)
				)
			)
		)
	)
	(zone
		(layers "In1.Cu" "In3.Cu" "In4.Cu" "In6.Cu")
		(hatch none 0.5)
		(connect_pads
			(clearance 0)
		)
		(min_thickness 0.25)
		(keepout
			(tracks not_allowed)
			(vias allowed)
			(pads allowed)
			(copperpour not_allowed)
			(footprints allowed)
		)
		(placement
			(enabled no)
			(sheetname "")
		)
		(fill yes
			(thermal_gap 0.5)
			(thermal_bridge_width 0.5)
			(island_removal_mode 0)
		)
		(polygon
			(pts
				(arc
					(start 7.502906 -353.1362)
					(mid 6.992493 -352.625406)
					(end 6.481826 -353.135946)
				)
				(arc
					(start 6.481826 -353.948746)
					(mid 6.992366 -354.459286)
					(end 7.502906 -353.948746)
				)
			)
		)
	)
	(zone
		(layers "In1.Cu" "In3.Cu" "In4.Cu" "In6.Cu")
		(hatch none 0.5)
		(connect_pads
			(clearance 0)
		)
		(min_thickness 0.25)
		(keepout
			(tracks not_allowed)
			(vias allowed)
			(pads allowed)
			(copperpour not_allowed)
			(footprints allowed)
		)
		(placement
			(enabled no)
			(sheetname "")
		)
		(fill yes
			(thermal_gap 0.5)
			(thermal_bridge_width 0.5)
			(island_removal_mode 0)
		)
		(polygon
			(pts
				(arc
					(start 220.840554 -466.58403)
					(mid 220.330141 -466.073236)
					(end 219.819474 -466.583776)
				)
				(arc
					(start 219.819474 -467.396576)
					(mid 220.330014 -467.907116)
					(end 220.840554 -467.396576)
				)
			)
		)
	)
	(zone
		(layers "In1.Cu" "In3.Cu" "In4.Cu" "In6.Cu")
		(hatch none 0.5)
		(connect_pads
			(clearance 0)
		)
		(min_thickness 0.25)
		(keepout
			(tracks not_allowed)
			(vias allowed)
			(pads allowed)
			(copperpour not_allowed)
			(footprints allowed)
		)
		(placement
			(enabled no)
			(sheetname "")
		)
		(fill yes
			(thermal_gap 0.5)
			(thermal_bridge_width 0.5)
			(island_removal_mode 0)
		)
		(polygon
			(pts
				(arc
					(start 34.81959 -480.196398)
					(mid 35.330003 -480.707192)
					(end 35.84067 -480.196652)
				)
				(arc
					(start 35.84067 -479.383852)
					(mid 35.33013 -478.873312)
					(end 34.81959 -479.383852)
				)
			)
		)
	)
	(zone
		(layers "In1.Cu" "In3.Cu" "In4.Cu" "In6.Cu")
		(hatch none 0.5)
		(connect_pads
			(clearance 0)
		)
		(min_thickness 0.25)
		(keepout
			(tracks not_allowed)
			(vias allowed)
			(pads allowed)
			(copperpour not_allowed)
			(footprints allowed)
		)
		(placement
			(enabled no)
			(sheetname "")
		)
		(fill yes
			(thermal_gap 0.5)
			(thermal_bridge_width 0.5)
			(island_removal_mode 0)
		)
		(polygon
			(pts
				(arc
					(start 27.18054 -25.803352)
					(mid 26.67 -25.292812)
					(end 26.15946 -25.803352)
				)
				(arc
					(start 26.15946 -26.615898)
					(mid 26.669873 -27.126692)
					(end 27.18054 -26.616152)
				)
			)
		)
	)
	(zone
		(layers "In1.Cu" "In3.Cu" "In4.Cu" "In6.Cu")
		(hatch none 0.5)
		(connect_pads
			(clearance 0)
		)
		(min_thickness 0.25)
		(keepout
			(tracks not_allowed)
			(vias allowed)
			(pads allowed)
			(copperpour not_allowed)
			(footprints allowed)
		)
		(placement
			(enabled no)
			(sheetname "")
		)
		(fill yes
			(thermal_gap 0.5)
			(thermal_bridge_width 0.5)
			(island_removal_mode 0)
		)
		(polygon
			(pts
				(arc
					(start 6.481826 -447.196718)
					(mid 6.992239 -447.707512)
					(end 7.502906 -447.196972)
				)
				(arc
					(start 7.502906 -446.384172)
					(mid 6.992366 -445.873632)
					(end 6.481826 -446.384172)
				)
			)
		)
	)
	(zone
		(layers "In1.Cu" "In3.Cu" "In4.Cu" "In6.Cu")
		(hatch none 0.5)
		(connect_pads
			(clearance 0)
		)
		(min_thickness 0.25)
		(keepout
			(tracks not_allowed)
			(vias allowed)
			(pads allowed)
			(copperpour not_allowed)
			(footprints allowed)
		)
		(placement
			(enabled no)
			(sheetname "")
		)
		(fill yes
			(thermal_gap 0.5)
			(thermal_bridge_width 0.5)
			(island_removal_mode 0)
		)
		(polygon
			(pts
				(arc
					(start 7.502906 -393.535916)
					(mid 6.992493 -393.025122)
					(end 6.481826 -393.535662)
				)
				(arc
					(start 6.481826 -394.348462)
					(mid 6.992366 -394.859002)
					(end 7.502906 -394.348462)
				)
			)
		)
	)
	(zone
		(layers "In1.Cu" "In3.Cu" "In4.Cu" "In6.Cu")
		(hatch none 0.5)
		(connect_pads
			(clearance 0)
		)
		(min_thickness 0.25)
		(keepout
			(tracks not_allowed)
			(vias allowed)
			(pads allowed)
			(copperpour not_allowed)
			(footprints allowed)
		)
		(placement
			(enabled no)
			(sheetname "")
		)
		(fill yes
			(thermal_gap 0.5)
			(thermal_bridge_width 0.5)
			(island_removal_mode 0)
		)
		(polygon
			(pts
				(arc
					(start 27.18054 -16.203422)
					(mid 26.67 -15.692882)
					(end 26.15946 -16.203422)
				)
				(arc
					(start 26.15946 -17.015968)
					(mid 26.669873 -17.526762)
					(end 27.18054 -17.016222)
				)
			)
		)
	)
	(zone
		(layers "In1.Cu" "In3.Cu" "In4.Cu" "In6.Cu")
		(hatch none 0.5)
		(connect_pads
			(clearance 0)
		)
		(min_thickness 0.25)
		(keepout
			(tracks not_allowed)
			(vias allowed)
			(pads allowed)
			(copperpour not_allowed)
			(footprints allowed)
		)
		(placement
			(enabled no)
			(sheetname "")
		)
		(fill yes
			(thermal_gap 0.5)
			(thermal_bridge_width 0.5)
			(island_removal_mode 0)
		)
		(polygon
			(pts
				(arc
					(start 25.88514 -425.651422)
					(mid 25.273127 -425.039028)
					(end 24.66086 -425.651168)
				)
				(arc
					(start 24.66086 -426.768768)
					(mid 25.273 -427.380908)
					(end 25.88514 -426.768768)
				)
			)
		)
	)
	(zone
		(layers "In1.Cu" "In3.Cu" "In4.Cu" "In6.Cu")
		(hatch none 0.5)
		(connect_pads
			(clearance 0)
		)
		(min_thickness 0.25)
		(keepout
			(tracks not_allowed)
			(vias allowed)
			(pads allowed)
			(copperpour not_allowed)
			(footprints allowed)
		)
		(placement
			(enabled no)
			(sheetname "")
		)
		(fill yes
			(thermal_gap 0.5)
			(thermal_bridge_width 0.5)
			(island_removal_mode 0)
		)
		(polygon
			(pts
				(arc
					(start 25.88514 -121.451116)
					(mid 25.273 -120.838976)
					(end 24.66086 -121.451116)
				)
				(arc
					(start 24.66086 -122.568462)
					(mid 25.272873 -123.180856)
					(end 25.88514 -122.568716)
				)
			)
		)
	)
	(zone
		(layers "In1.Cu" "In3.Cu" "In4.Cu" "In6.Cu")
		(hatch none 0.5)
		(connect_pads
			(clearance 0)
		)
		(min_thickness 0.25)
		(keepout
			(tracks not_allowed)
			(vias allowed)
			(pads allowed)
			(copperpour not_allowed)
			(footprints allowed)
		)
		(placement
			(enabled no)
			(sheetname "")
		)
		(fill yes
			(thermal_gap 0.5)
			(thermal_bridge_width 0.5)
			(island_removal_mode 0)
		)
		(polygon
			(pts
				(arc
					(start 220.840554 -72.183752)
					(mid 220.330141 -71.672958)
					(end 219.819474 -72.183498)
				)
				(arc
					(start 219.819474 -72.996298)
					(mid 220.330014 -73.506838)
					(end 220.840554 -72.996298)
				)
			)
		)
	)
	(zone
		(layers "In1.Cu" "In3.Cu" "In4.Cu" "In6.Cu")
		(hatch none 0.5)
		(connect_pads
			(clearance 0)
		)
		(min_thickness 0.25)
		(keepout
			(tracks not_allowed)
			(vias allowed)
			(pads allowed)
			(copperpour not_allowed)
			(footprints allowed)
		)
		(placement
			(enabled no)
			(sheetname "")
		)
		(fill yes
			(thermal_gap 0.5)
			(thermal_bridge_width 0.5)
			(island_removal_mode 0)
		)
		(polygon
			(pts
				(arc
					(start 35.84067 -54.583838)
					(mid 35.330257 -54.073044)
					(end 34.81959 -54.583584)
				)
				(arc
					(start 34.81959 -55.396384)
					(mid 35.33013 -55.906924)
					(end 35.84067 -55.396384)
				)
			)
		)
	)
	(zone
		(layers "In1.Cu" "In3.Cu" "In4.Cu" "In6.Cu")
		(hatch none 0.5)
		(connect_pads
			(clearance 0)
		)
		(min_thickness 0.25)
		(keepout
			(tracks not_allowed)
			(vias allowed)
			(pads allowed)
			(copperpour not_allowed)
			(footprints allowed)
		)
		(placement
			(enabled no)
			(sheetname "")
		)
		(fill yes
			(thermal_gap 0.5)
			(thermal_bridge_width 0.5)
			(island_removal_mode 0)
		)
		(polygon
			(pts
				(arc
					(start 220.840554 -67.383914)
					(mid 220.330141 -66.87312)
					(end 219.819474 -67.38366)
				)
				(arc
					(start 219.819474 -68.19646)
					(mid 220.330014 -68.707)
					(end 220.840554 -68.19646)
				)
			)
		)
	)
	(zone
		(layers "In1.Cu" "In3.Cu" "In4.Cu" "In6.Cu")
		(hatch none 0.5)
		(connect_pads
			(clearance 0)
		)
		(min_thickness 0.25)
		(keepout
			(tracks not_allowed)
			(vias allowed)
			(pads allowed)
			(copperpour not_allowed)
			(footprints allowed)
		)
		(placement
			(enabled no)
			(sheetname "")
		)
		(fill yes
			(thermal_gap 0.5)
			(thermal_bridge_width 0.5)
			(island_removal_mode 0)
		)
		(polygon
			(pts
				(arc
					(start 220.840554 -260.583934)
					(mid 220.330141 -260.07314)
					(end 219.819474 -260.58368)
				)
				(arc
					(start 219.819474 -261.39648)
					(mid 220.330014 -261.90702)
					(end 220.840554 -261.39648)
				)
			)
		)
	)
	(zone
		(layers "In1.Cu" "In3.Cu" "In4.Cu" "In6.Cu")
		(hatch none 0.5)
		(connect_pads
			(clearance 0)
		)
		(min_thickness 0.25)
		(keepout
			(tracks not_allowed)
			(vias allowed)
			(pads allowed)
			(copperpour not_allowed)
			(footprints allowed)
		)
		(placement
			(enabled no)
			(sheetname "")
		)
		(fill yes
			(thermal_gap 0.5)
			(thermal_bridge_width 0.5)
			(island_removal_mode 0)
		)
		(polygon
			(pts
				(arc
					(start 5.59054 -351.535746)
					(mid 5.080127 -351.024952)
					(end 4.56946 -351.535492)
				)
				(arc
					(start 4.56946 -352.348292)
					(mid 5.08 -352.858832)
					(end 5.59054 -352.348292)
				)
			)
		)
	)
	(zone
		(layers "In1.Cu" "In3.Cu" "In4.Cu" "In6.Cu")
		(hatch none 0.5)
		(connect_pads
			(clearance 0)
		)
		(min_thickness 0.25)
		(keepout
			(tracks not_allowed)
			(vias allowed)
			(pads allowed)
			(copperpour not_allowed)
			(footprints allowed)
		)
		(placement
			(enabled no)
			(sheetname "")
		)
		(fill yes
			(thermal_gap 0.5)
			(thermal_bridge_width 0.5)
			(island_removal_mode 0)
		)
		(polygon
			(pts
				(arc
					(start 5.59054 -170.335702)
					(mid 5.080127 -169.824908)
					(end 4.56946 -170.335448)
				)
				(arc
					(start 4.56946 -171.148248)
					(mid 5.08 -171.658788)
					(end 5.59054 -171.148248)
				)
			)
		)
	)
	(zone
		(layers "In1.Cu" "In3.Cu" "In4.Cu" "In6.Cu")
		(hatch none 0.5)
		(connect_pads
			(clearance 0)
		)
		(min_thickness 0.25)
		(keepout
			(tracks not_allowed)
			(vias allowed)
			(pads allowed)
			(copperpour not_allowed)
			(footprints allowed)
		)
		(placement
			(enabled no)
			(sheetname "")
		)
		(fill yes
			(thermal_gap 0.5)
			(thermal_bridge_width 0.5)
			(island_removal_mode 0)
		)
		(polygon
			(pts
				(arc
					(start 4.56946 -414.34766)
					(mid 5.079873 -414.858454)
					(end 5.59054 -414.347914)
				)
				(arc
					(start 5.59054 -413.535114)
					(mid 5.08 -413.024574)
					(end 4.56946 -413.535114)
				)
			)
		)
	)
	(zone
		(layers "In1.Cu" "In3.Cu" "In4.Cu" "In6.Cu")
		(hatch none 0.5)
		(connect_pads
			(clearance 0)
		)
		(min_thickness 0.25)
		(keepout
			(tracks not_allowed)
			(vias allowed)
			(pads allowed)
			(copperpour not_allowed)
			(footprints allowed)
		)
		(placement
			(enabled no)
			(sheetname "")
		)
		(fill yes
			(thermal_gap 0.5)
			(thermal_bridge_width 0.5)
			(island_removal_mode 0)
		)
		(polygon
			(pts
				(arc
					(start 5.59054 -283.535628)
					(mid 5.080127 -283.024834)
					(end 4.56946 -283.535374)
				)
				(arc
					(start 4.56946 -284.348174)
					(mid 5.08 -284.858714)
					(end 5.59054 -284.348174)
				)
			)
		)
	)
	(zone
		(layers "In1.Cu" "In3.Cu" "In4.Cu" "In6.Cu")
		(hatch none 0.5)
		(connect_pads
			(clearance 0)
		)
		(min_thickness 0.25)
		(keepout
			(tracks not_allowed)
			(vias allowed)
			(pads allowed)
			(copperpour not_allowed)
			(footprints allowed)
		)
		(placement
			(enabled no)
			(sheetname "")
		)
		(fill yes
			(thermal_gap 0.5)
			(thermal_bridge_width 0.5)
			(island_removal_mode 0)
		)
		(polygon
			(pts
				(arc
					(start 5.59054 -302.735742)
					(mid 5.080127 -302.224948)
					(end 4.56946 -302.735488)
				)
				(arc
					(start 4.56946 -303.548288)
					(mid 5.08 -304.058828)
					(end 5.59054 -303.548288)
				)
			)
		)
	)
	(zone
		(layers "In1.Cu" "In3.Cu" "In4.Cu" "In6.Cu")
		(hatch none 0.5)
		(connect_pads
			(clearance 0)
		)
		(min_thickness 0.25)
		(keepout
			(tracks not_allowed)
			(vias allowed)
			(pads allowed)
			(copperpour not_allowed)
			(footprints allowed)
		)
		(placement
			(enabled no)
			(sheetname "")
		)
		(fill yes
			(thermal_gap 0.5)
			(thermal_bridge_width 0.5)
			(island_removal_mode 0)
		)
		(polygon
			(pts
				(arc
					(start 34.81959 -489.796328)
					(mid 35.330003 -490.307122)
					(end 35.84067 -489.796582)
				)
				(arc
					(start 35.84067 -488.983782)
					(mid 35.33013 -488.473242)
					(end 34.81959 -488.983782)
				)
			)
		)
	)
	(zone
		(layers "In1.Cu" "In3.Cu" "In4.Cu" "In6.Cu")
		(hatch none 0.5)
		(connect_pads
			(clearance 0)
		)
		(min_thickness 0.25)
		(keepout
			(tracks not_allowed)
			(vias allowed)
			(pads allowed)
			(copperpour not_allowed)
			(footprints allowed)
		)
		(placement
			(enabled no)
			(sheetname "")
		)
		(fill yes
			(thermal_gap 0.5)
			(thermal_bridge_width 0.5)
			(island_removal_mode 0)
		)
		(polygon
			(pts
				(arc
					(start 37.33927 -177.431446)
					(mid 36.727257 -176.819052)
					(end 36.11499 -177.431192)
				)
				(arc
					(start 36.11499 -178.548792)
					(mid 36.72713 -179.160932)
					(end 37.33927 -178.548792)
				)
			)
		)
	)
	(zone
		(layers "In1.Cu" "In3.Cu" "In4.Cu" "In6.Cu")
		(hatch none 0.5)
		(connect_pads
			(clearance 0)
		)
		(min_thickness 0.25)
		(keepout
			(tracks not_allowed)
			(vias allowed)
			(pads allowed)
			(copperpour not_allowed)
			(footprints allowed)
		)
		(placement
			(enabled no)
			(sheetname "")
		)
		(fill yes
			(thermal_gap 0.5)
			(thermal_bridge_width 0.5)
			(island_removal_mode 0)
		)
		(polygon
			(pts
				(arc
					(start 25.88514 -23.25116)
					(mid 25.273 -22.63902)
					(end 24.66086 -23.25116)
				)
				(arc
					(start 24.66086 -24.368506)
					(mid 25.272873 -24.9809)
					(end 25.88514 -24.36876)
				)
			)
		)
	)
	(zone
		(layers "In1.Cu" "In3.Cu" "In4.Cu" "In6.Cu")
		(hatch none 0.5)
		(connect_pads
			(clearance 0)
		)
		(min_thickness 0.25)
		(keepout
			(tracks not_allowed)
			(vias allowed)
			(pads allowed)
			(copperpour not_allowed)
			(footprints allowed)
		)
		(placement
			(enabled no)
			(sheetname "")
		)
		(fill yes
			(thermal_gap 0.5)
			(thermal_bridge_width 0.5)
			(island_removal_mode 0)
		)
		(polygon
			(pts
				(arc
					(start 5.59054 -357.935784)
					(mid 5.080127 -357.42499)
					(end 4.56946 -357.93553)
				)
				(arc
					(start 4.56946 -358.74833)
					(mid 5.08 -359.25887)
					(end 5.59054 -358.74833)
				)
			)
		)
	)
	(zone
		(layers "In1.Cu" "In3.Cu" "In4.Cu" "In6.Cu")
		(hatch none 0.5)
		(connect_pads
			(clearance 0)
		)
		(min_thickness 0.25)
		(keepout
			(tracks not_allowed)
			(vias allowed)
			(pads allowed)
			(copperpour not_allowed)
			(footprints allowed)
		)
		(placement
			(enabled no)
			(sheetname "")
		)
		(fill yes
			(thermal_gap 0.5)
			(thermal_bridge_width 0.5)
			(island_removal_mode 0)
		)
		(polygon
			(pts
				(arc
					(start 222.339154 -388.231634)
					(mid 221.727141 -387.61924)
					(end 221.114874 -388.23138)
				)
				(arc
					(start 221.114874 -389.34898)
					(mid 221.727014 -389.96112)
					(end 222.339154 -389.34898)
				)
			)
		)
	)
	(zone
		(layers "In1.Cu" "In3.Cu" "In4.Cu" "In6.Cu")
		(hatch none 0.5)
		(connect_pads
			(clearance 0)
		)
		(min_thickness 0.25)
		(keepout
			(tracks not_allowed)
			(vias allowed)
			(pads allowed)
			(copperpour not_allowed)
			(footprints allowed)
		)
		(placement
			(enabled no)
			(sheetname "")
		)
		(fill yes
			(thermal_gap 0.5)
			(thermal_bridge_width 0.5)
			(island_removal_mode 0)
		)
		(polygon
			(pts
				(arc
					(start 220.840554 -363.583982)
					(mid 220.330141 -363.073188)
					(end 219.819474 -363.583728)
				)
				(arc
					(start 219.819474 -364.396528)
					(mid 220.330014 -364.907068)
					(end 220.840554 -364.396528)
				)
			)
		)
	)
	(zone
		(layers "In1.Cu" "In3.Cu" "In4.Cu" "In6.Cu")
		(hatch none 0.5)
		(connect_pads
			(clearance 0)
		)
		(min_thickness 0.25)
		(keepout
			(tracks not_allowed)
			(vias allowed)
			(pads allowed)
			(copperpour not_allowed)
			(footprints allowed)
		)
		(placement
			(enabled no)
			(sheetname "")
		)
		(fill yes
			(thermal_gap 0.5)
			(thermal_bridge_width 0.5)
			(island_removal_mode 0)
		)
		(polygon
			(pts
				(arc
					(start 5.59054 -160.735772)
					(mid 5.080127 -160.224978)
					(end 4.56946 -160.735518)
				)
				(arc
					(start 4.56946 -161.548318)
					(mid 5.08 -162.058858)
					(end 5.59054 -161.548318)
				)
			)
		)
	)
	(zone
		(layers "In1.Cu" "In3.Cu" "In4.Cu" "In6.Cu")
		(hatch none 0.5)
		(connect_pads
			(clearance 0)
		)
		(min_thickness 0.25)
		(keepout
			(tracks not_allowed)
			(vias allowed)
			(pads allowed)
			(copperpour not_allowed)
			(footprints allowed)
		)
		(placement
			(enabled no)
			(sheetname "")
		)
		(fill yes
			(thermal_gap 0.5)
			(thermal_bridge_width 0.5)
			(island_removal_mode 0)
		)
		(polygon
			(pts
				(arc
					(start 5.59054 -194.335654)
					(mid 5.080127 -193.82486)
					(end 4.56946 -194.3354)
				)
				(arc
					(start 4.56946 -195.1482)
					(mid 5.08 -195.65874)
					(end 5.59054 -195.1482)
				)
			)
		)
	)
	(zone
		(layers "In1.Cu" "In3.Cu" "In4.Cu" "In6.Cu")
		(hatch none 0.5)
		(connect_pads
			(clearance 0)
		)
		(min_thickness 0.25)
		(keepout
			(tracks not_allowed)
			(vias allowed)
			(pads allowed)
			(copperpour not_allowed)
			(footprints allowed)
		)
		(placement
			(enabled no)
			(sheetname "")
		)
		(fill yes
			(thermal_gap 0.5)
			(thermal_bridge_width 0.5)
			(island_removal_mode 0)
		)
		(polygon
			(pts
				(arc
					(start 5.59054 -154.335734)
					(mid 5.080127 -153.82494)
					(end 4.56946 -154.33548)
				)
				(arc
					(start 4.56946 -155.14828)
					(mid 5.08 -155.65882)
					(end 5.59054 -155.14828)
				)
			)
		)
	)
	(zone
		(layers "In1.Cu" "In3.Cu" "In4.Cu" "In6.Cu")
		(hatch none 0.5)
		(connect_pads
			(clearance 0)
		)
		(min_thickness 0.25)
		(keepout
			(tracks not_allowed)
			(vias allowed)
			(pads allowed)
			(copperpour not_allowed)
			(footprints allowed)
		)
		(placement
			(enabled no)
			(sheetname "")
		)
		(fill yes
			(thermal_gap 0.5)
			(thermal_bridge_width 0.5)
			(island_removal_mode 0)
		)
		(polygon
			(pts
				(arc
					(start 5.59054 -329.935586)
					(mid 5.080127 -329.424792)
					(end 4.56946 -329.935332)
				)
				(arc
					(start 4.56946 -330.748132)
					(mid 5.08 -331.258672)
					(end 5.59054 -330.748132)
				)
			)
		)
	)
	(zone
		(layers "In1.Cu" "In3.Cu" "In4.Cu" "In6.Cu")
		(hatch none 0.5)
		(connect_pads
			(clearance 0)
		)
		(min_thickness 0.25)
		(keepout
			(tracks not_allowed)
			(vias allowed)
			(pads allowed)
			(copperpour not_allowed)
			(footprints allowed)
		)
		(placement
			(enabled no)
			(sheetname "")
		)
		(fill yes
			(thermal_gap 0.5)
			(thermal_bridge_width 0.5)
			(island_removal_mode 0)
		)
		(polygon
			(pts
				(arc
					(start 5.59054 -167.135556)
					(mid 5.080127 -166.624762)
					(end 4.56946 -167.135302)
				)
				(arc
					(start 4.56946 -167.948102)
					(mid 5.08 -168.458642)
					(end 5.59054 -167.948102)
				)
			)
		)
	)
	(zone
		(layers "In1.Cu" "In3.Cu" "In4.Cu" "In6.Cu")
		(hatch none 0.5)
		(connect_pads
			(clearance 0)
		)
		(min_thickness 0.25)
		(keepout
			(tracks not_allowed)
			(vias allowed)
			(pads allowed)
			(copperpour not_allowed)
			(footprints allowed)
		)
		(placement
			(enabled no)
			(sheetname "")
		)
		(fill yes
			(thermal_gap 0.5)
			(thermal_bridge_width 0.5)
			(island_removal_mode 0)
		)
		(polygon
			(pts
				(arc
					(start 36.11499 -482.74859)
					(mid 36.727003 -483.360984)
					(end 37.33927 -482.748844)
				)
				(arc
					(start 37.33927 -481.631244)
					(mid 36.72713 -481.019104)
					(end 36.11499 -481.631244)
				)
			)
		)
	)
	(zone
		(layers "In1.Cu" "In3.Cu" "In4.Cu" "In6.Cu")
		(hatch none 0.5)
		(connect_pads
			(clearance 0)
		)
		(min_thickness 0.25)
		(keepout
			(tracks not_allowed)
			(vias allowed)
			(pads allowed)
			(copperpour not_allowed)
			(footprints allowed)
		)
		(placement
			(enabled no)
			(sheetname "")
		)
		(fill yes
			(thermal_gap 0.5)
			(thermal_bridge_width 0.5)
			(island_removal_mode 0)
		)
		(polygon
			(pts
				(arc
					(start 7.502906 -278.786844)
					(mid 6.992493 -278.27605)
					(end 6.481826 -278.78659)
				)
				(arc
					(start 6.481826 -279.59939)
					(mid 6.992366 -280.10993)
					(end 7.502906 -279.59939)
				)
			)
		)
	)
	(zone
		(layers "In1.Cu" "In3.Cu" "In4.Cu" "In6.Cu")
		(hatch none 0.5)
		(connect_pads
			(clearance 0)
		)
		(min_thickness 0.25)
		(keepout
			(tracks not_allowed)
			(vias allowed)
			(pads allowed)
			(copperpour not_allowed)
			(footprints allowed)
		)
		(placement
			(enabled no)
			(sheetname "")
		)
		(fill yes
			(thermal_gap 0.5)
			(thermal_bridge_width 0.5)
			(island_removal_mode 0)
		)
		(polygon
			(pts
				(arc
					(start 8.382254 -385.092702)
					(mid 7.871714 -385.603242)
					(end 8.382254 -386.113782)
				)
				(arc
					(start 9.1948 -386.113782)
					(mid 9.705594 -385.603369)
					(end 9.195054 -385.092702)
				)
			)
		)
	)
	(zone
		(layers "In1.Cu" "In3.Cu" "In4.Cu" "In6.Cu")
		(hatch none 0.5)
		(connect_pads
			(clearance 0)
		)
		(min_thickness 0.25)
		(keepout
			(tracks not_allowed)
			(vias allowed)
			(pads allowed)
			(copperpour not_allowed)
			(footprints allowed)
		)
		(placement
			(enabled no)
			(sheetname "")
		)
		(fill yes
			(thermal_gap 0.5)
			(thermal_bridge_width 0.5)
			(island_removal_mode 0)
		)
		(polygon
			(pts
				(arc
					(start 36.11499 -469.948768)
					(mid 36.727003 -470.561162)
					(end 37.33927 -469.949022)
				)
				(arc
					(start 37.33927 -468.831422)
					(mid 36.72713 -468.219282)
					(end 36.11499 -468.831422)
				)
			)
		)
	)
	(zone
		(layers "In1.Cu" "In3.Cu" "In4.Cu" "In6.Cu")
		(hatch none 0.5)
		(connect_pads
			(clearance 0)
		)
		(min_thickness 0.25)
		(keepout
			(tracks not_allowed)
			(vias allowed)
			(pads allowed)
			(copperpour not_allowed)
			(footprints allowed)
		)
		(placement
			(enabled no)
			(sheetname "")
		)
		(fill yes
			(thermal_gap 0.5)
			(thermal_bridge_width 0.5)
			(island_removal_mode 0)
		)
		(polygon
			(pts
				(arc
					(start 222.339154 -378.63145)
					(mid 221.727141 -378.019056)
					(end 221.114874 -378.631196)
				)
				(arc
					(start 221.114874 -379.748796)
					(mid 221.727014 -380.360936)
					(end 222.339154 -379.748796)
				)
			)
		)
	)
	(zone
		(layers "In1.Cu" "In3.Cu" "In4.Cu" "In6.Cu")
		(hatch none 0.5)
		(connect_pads
			(clearance 0)
		)
		(min_thickness 0.25)
		(keepout
			(tracks not_allowed)
			(vias allowed)
			(pads allowed)
			(copperpour not_allowed)
			(footprints allowed)
		)
		(placement
			(enabled no)
			(sheetname "")
		)
		(fill yes
			(thermal_gap 0.5)
			(thermal_bridge_width 0.5)
			(island_removal_mode 0)
		)
		(polygon
			(pts
				(arc
					(start 5.59054 -305.935634)
					(mid 5.080127 -305.42484)
					(end 4.56946 -305.93538)
				)
				(arc
					(start 4.56946 -306.74818)
					(mid 5.08 -307.25872)
					(end 5.59054 -306.74818)
				)
			)
		)
	)
	(zone
		(layers "In1.Cu" "In3.Cu" "In4.Cu" "In6.Cu")
		(hatch none 0.5)
		(connect_pads
			(clearance 0)
		)
		(min_thickness 0.25)
		(keepout
			(tracks not_allowed)
			(vias allowed)
			(pads allowed)
			(copperpour not_allowed)
			(footprints allowed)
		)
		(placement
			(enabled no)
			(sheetname "")
		)
		(fill yes
			(thermal_gap 0.5)
			(thermal_bridge_width 0.5)
			(island_removal_mode 0)
		)
		(polygon
			(pts
				(arc
					(start 24.66086 -323.768466)
					(mid 25.272873 -324.38086)
					(end 25.88514 -323.76872)
				)
				(arc
					(start 25.88514 -322.65112)
					(mid 25.273 -322.03898)
					(end 24.66086 -322.65112)
				)
			)
		)
	)
	(zone
		(layers "In1.Cu" "In3.Cu" "In4.Cu" "In6.Cu")
		(hatch none 0.5)
		(connect_pads
			(clearance 0)
		)
		(min_thickness 0.25)
		(keepout
			(tracks not_allowed)
			(vias allowed)
			(pads allowed)
			(copperpour not_allowed)
			(footprints allowed)
		)
		(placement
			(enabled no)
			(sheetname "")
		)
		(fill yes
			(thermal_gap 0.5)
			(thermal_bridge_width 0.5)
			(island_removal_mode 0)
		)
		(polygon
			(pts
				(arc
					(start 222.339154 -491.231682)
					(mid 221.727141 -490.619288)
					(end 221.114874 -491.231428)
				)
				(arc
					(start 221.114874 -492.349028)
					(mid 221.727014 -492.961168)
					(end 222.339154 -492.349028)
				)
			)
		)
	)
	(zone
		(layers "In1.Cu" "In3.Cu" "In4.Cu" "In6.Cu")
		(hatch none 0.5)
		(connect_pads
			(clearance 0)
		)
		(min_thickness 0.25)
		(keepout
			(tracks not_allowed)
			(vias allowed)
			(pads allowed)
			(copperpour not_allowed)
			(footprints allowed)
		)
		(placement
			(enabled no)
			(sheetname "")
		)
		(fill yes
			(thermal_gap 0.5)
			(thermal_bridge_width 0.5)
			(island_removal_mode 0)
		)
		(polygon
			(pts
				(arc
					(start 37.33927 -285.231586)
					(mid 36.727257 -284.619192)
					(end 36.11499 -285.231332)
				)
				(arc
					(start 36.11499 -286.348932)
					(mid 36.72713 -286.961072)
					(end 37.33927 -286.348932)
				)
			)
		)
	)
	(zone
		(layers "In1.Cu" "In3.Cu" "In4.Cu" "In6.Cu")
		(hatch none 0.5)
		(connect_pads
			(clearance 0)
		)
		(min_thickness 0.25)
		(keepout
			(tracks not_allowed)
			(vias allowed)
			(pads allowed)
			(copperpour not_allowed)
			(footprints allowed)
		)
		(placement
			(enabled no)
			(sheetname "")
		)
		(fill yes
			(thermal_gap 0.5)
			(thermal_bridge_width 0.5)
			(island_removal_mode 0)
		)
		(polygon
			(pts
				(arc
					(start 25.88514 -345.05138)
					(mid 25.273127 -344.438986)
					(end 24.66086 -345.051126)
				)
				(arc
					(start 24.66086 -346.168726)
					(mid 25.273 -346.780866)
					(end 25.88514 -346.168726)
				)
			)
		)
	)
	(zone
		(layers "In1.Cu" "In3.Cu" "In4.Cu" "In6.Cu")
		(hatch none 0.5)
		(connect_pads
			(clearance 0)
		)
		(min_thickness 0.25)
		(keepout
			(tracks not_allowed)
			(vias allowed)
			(pads allowed)
			(copperpour not_allowed)
			(footprints allowed)
		)
		(placement
			(enabled no)
			(sheetname "")
		)
		(fill yes
			(thermal_gap 0.5)
			(thermal_bridge_width 0.5)
			(island_removal_mode 0)
		)
		(polygon
			(pts
				(arc
					(start 25.88514 -219.651326)
					(mid 25.273127 -219.038932)
					(end 24.66086 -219.651072)
				)
				(arc
					(start 24.66086 -220.768672)
					(mid 25.273 -221.380812)
					(end 25.88514 -220.768672)
				)
			)
		)
	)
	(zone
		(layers "In1.Cu" "In3.Cu" "In4.Cu" "In6.Cu")
		(hatch none 0.5)
		(connect_pads
			(clearance 0)
		)
		(min_thickness 0.25)
		(keepout
			(tracks not_allowed)
			(vias allowed)
			(pads allowed)
			(copperpour not_allowed)
			(footprints allowed)
		)
		(placement
			(enabled no)
			(sheetname "")
		)
		(fill yes
			(thermal_gap 0.5)
			(thermal_bridge_width 0.5)
			(island_removal_mode 0)
		)
		(polygon
			(pts
				(arc
					(start 220.840554 -278.183848)
					(mid 220.330141 -277.673054)
					(end 219.819474 -278.183594)
				)
				(arc
					(start 219.819474 -278.996394)
					(mid 220.330014 -279.506934)
					(end 220.840554 -278.996394)
				)
			)
		)
	)
	(zone
		(layers "In1.Cu" "In3.Cu" "In4.Cu" "In6.Cu")
		(hatch none 0.5)
		(connect_pads
			(clearance 0)
		)
		(min_thickness 0.25)
		(keepout
			(tracks not_allowed)
			(vias allowed)
			(pads allowed)
			(copperpour not_allowed)
			(footprints allowed)
		)
		(placement
			(enabled no)
			(sheetname "")
		)
		(fill yes
			(thermal_gap 0.5)
			(thermal_bridge_width 0.5)
			(island_removal_mode 0)
		)
		(polygon
			(pts
				(arc
					(start 7.502906 -387.135878)
					(mid 6.992493 -386.625084)
					(end 6.481826 -387.135624)
				)
				(arc
					(start 6.481826 -387.948424)
					(mid 6.992366 -388.458964)
					(end 7.502906 -387.948424)
				)
			)
		)
	)
	(zone
		(layers "In1.Cu" "In3.Cu" "In4.Cu" "In6.Cu")
		(hatch none 0.5)
		(connect_pads
			(clearance 0)
		)
		(min_thickness 0.25)
		(keepout
			(tracks not_allowed)
			(vias allowed)
			(pads allowed)
			(copperpour not_allowed)
			(footprints allowed)
		)
		(placement
			(enabled no)
			(sheetname "")
		)
		(fill yes
			(thermal_gap 0.5)
			(thermal_bridge_width 0.5)
			(island_removal_mode 0)
		)
		(polygon
			(pts
				(arc
					(start 72.90054 -431.139854)
					(mid 72.390127 -430.62906)
					(end 71.87946 -431.1396)
				)
				(arc
					(start 71.87946 -431.9524)
					(mid 72.39 -432.46294)
					(end 72.90054 -431.9524)
				)
			)
		)
	)
	(zone
		(layers "In1.Cu" "In3.Cu" "In4.Cu" "In6.Cu")
		(hatch none 0.5)
		(connect_pads
			(clearance 0)
		)
		(min_thickness 0.25)
		(keepout
			(tracks not_allowed)
			(vias allowed)
			(pads allowed)
			(copperpour not_allowed)
			(footprints allowed)
		)
		(placement
			(enabled no)
			(sheetname "")
		)
		(fill yes
			(thermal_gap 0.5)
			(thermal_bridge_width 0.5)
			(island_removal_mode 0)
		)
		(polygon
			(pts
				(arc
					(start 24.66086 -328.568558)
					(mid 25.272873 -329.180952)
					(end 25.88514 -328.568812)
				)
				(arc
					(start 25.88514 -327.451212)
					(mid 25.273 -326.839072)
					(end 24.66086 -327.451212)
				)
			)
		)
	)
	(zone
		(layers "In1.Cu" "In3.Cu" "In4.Cu" "In6.Cu")
		(hatch none 0.5)
		(connect_pads
			(clearance 0)
		)
		(min_thickness 0.25)
		(keepout
			(tracks not_allowed)
			(vias allowed)
			(pads allowed)
			(copperpour not_allowed)
			(footprints allowed)
		)
		(placement
			(enabled no)
			(sheetname "")
		)
		(fill yes
			(thermal_gap 0.5)
			(thermal_bridge_width 0.5)
			(island_removal_mode 0)
		)
		(polygon
			(pts
				(arc
					(start 7.502906 -204.736192)
					(mid 6.992493 -204.225398)
					(end 6.481826 -204.735938)
				)
				(arc
					(start 6.481826 -205.548738)
					(mid 6.992366 -206.059278)
					(end 7.502906 -205.548738)
				)
			)
		)
	)
	(zone
		(layers "In1.Cu" "In3.Cu" "In4.Cu" "In6.Cu")
		(hatch none 0.5)
		(connect_pads
			(clearance 0)
		)
		(min_thickness 0.25)
		(keepout
			(tracks not_allowed)
			(vias allowed)
			(pads allowed)
			(copperpour not_allowed)
			(footprints allowed)
		)
		(placement
			(enabled no)
			(sheetname "")
		)
		(fill yes
			(thermal_gap 0.5)
			(thermal_bridge_width 0.5)
			(island_removal_mode 0)
		)
		(polygon
			(pts
				(arc
					(start 26.15946 -227.816156)
					(mid 26.669873 -228.32695)
					(end 27.18054 -227.81641)
				)
				(arc
					(start 27.18054 -227.00361)
					(mid 26.67 -226.49307)
					(end 26.15946 -227.00361)
				)
			)
		)
	)
	(zone
		(layers "In1.Cu" "In3.Cu" "In4.Cu" "In6.Cu")
		(hatch none 0.5)
		(connect_pads
			(clearance 0)
		)
		(min_thickness 0.25)
		(keepout
			(tracks not_allowed)
			(vias allowed)
			(pads allowed)
			(copperpour not_allowed)
			(footprints allowed)
		)
		(placement
			(enabled no)
			(sheetname "")
		)
		(fill yes
			(thermal_gap 0.5)
			(thermal_bridge_width 0.5)
			(island_removal_mode 0)
		)
		(polygon
			(pts
				(arc
					(start 4.56946 -407.947622)
					(mid 5.079873 -408.458416)
					(end 5.59054 -407.947876)
				)
				(arc
					(start 5.59054 -407.135076)
					(mid 5.08 -406.624536)
					(end 4.56946 -407.135076)
				)
			)
		)
	)
	(zone
		(layers "In1.Cu" "In3.Cu" "In4.Cu" "In6.Cu")
		(hatch none 0.5)
		(connect_pads
			(clearance 0)
		)
		(min_thickness 0.25)
		(keepout
			(tracks not_allowed)
			(vias allowed)
			(pads allowed)
			(copperpour not_allowed)
			(footprints allowed)
		)
		(placement
			(enabled no)
			(sheetname "")
		)
		(fill yes
			(thermal_gap 0.5)
			(thermal_bridge_width 0.5)
			(island_removal_mode 0)
		)
		(polygon
			(pts
				(arc
					(start 7.502906 -340.386924)
					(mid 6.992493 -339.87613)
					(end 6.481826 -340.38667)
				)
				(arc
					(start 6.481826 -341.19947)
					(mid 6.992366 -341.71001)
					(end 7.502906 -341.19947)
				)
			)
		)
	)
	(zone
		(layers "In1.Cu" "In3.Cu" "In4.Cu" "In6.Cu")
		(hatch none 0.5)
		(connect_pads
			(clearance 0)
		)
		(min_thickness 0.25)
		(keepout
			(tracks not_allowed)
			(vias allowed)
			(pads allowed)
			(copperpour not_allowed)
			(footprints allowed)
		)
		(placement
			(enabled no)
			(sheetname "")
		)
		(fill yes
			(thermal_gap 0.5)
			(thermal_bridge_width 0.5)
			(island_removal_mode 0)
		)
		(polygon
			(pts
				(arc
					(start 48.89754 -266.579604)
					(mid 48.387127 -266.06881)
					(end 47.87646 -266.57935)
				)
				(arc
					(start 47.87646 -267.39215)
					(mid 48.387 -267.90269)
					(end 48.89754 -267.39215)
				)
			)
		)
	)
	(zone
		(layers "In1.Cu" "In3.Cu" "In4.Cu" "In6.Cu")
		(hatch none 0.5)
		(connect_pads
			(clearance 0)
		)
		(min_thickness 0.25)
		(keepout
			(tracks not_allowed)
			(vias allowed)
			(pads allowed)
			(copperpour not_allowed)
			(footprints allowed)
		)
		(placement
			(enabled no)
			(sheetname "")
		)
		(fill yes
			(thermal_gap 0.5)
			(thermal_bridge_width 0.5)
			(island_removal_mode 0)
		)
		(polygon
			(pts
				(arc
					(start 7.502906 -175.186848)
					(mid 6.992493 -174.676054)
					(end 6.481826 -175.186594)
				)
				(arc
					(start 6.481826 -175.999394)
					(mid 6.992366 -176.509934)
					(end 7.502906 -175.999394)
				)
			)
		)
	)
	(zone
		(layers "In1.Cu" "In3.Cu" "In4.Cu" "In6.Cu")
		(hatch none 0.5)
		(connect_pads
			(clearance 0)
		)
		(min_thickness 0.25)
		(keepout
			(tracks not_allowed)
			(vias allowed)
			(pads allowed)
			(copperpour not_allowed)
			(footprints allowed)
		)
		(placement
			(enabled no)
			(sheetname "")
		)
		(fill yes
			(thermal_gap 0.5)
			(thermal_bridge_width 0.5)
			(island_removal_mode 0)
		)
		(polygon
			(pts
				(arc
					(start 48.89754 -60.579508)
					(mid 48.387127 -60.068714)
					(end 47.87646 -60.579254)
				)
				(arc
					(start 47.87646 -61.392054)
					(mid 48.387 -61.902594)
					(end 48.89754 -61.392054)
				)
			)
		)
	)
	(zone
		(layers "In1.Cu" "In3.Cu" "In4.Cu" "In6.Cu")
		(hatch none 0.5)
		(connect_pads
			(clearance 0)
		)
		(min_thickness 0.25)
		(keepout
			(tracks not_allowed)
			(vias allowed)
			(pads allowed)
			(copperpour not_allowed)
			(footprints allowed)
		)
		(placement
			(enabled no)
			(sheetname "")
		)
		(fill yes
			(thermal_gap 0.5)
			(thermal_bridge_width 0.5)
			(island_removal_mode 0)
		)
		(polygon
			(pts
				(arc
					(start 6.481826 -301.948342)
					(mid 6.992239 -302.459136)
					(end 7.502906 -301.948596)
				)
				(arc
					(start 7.502906 -301.135796)
					(mid 6.992366 -300.625256)
					(end 6.481826 -301.135796)
				)
			)
		)
	)
	(zone
		(layers "In1.Cu" "In3.Cu" "In4.Cu" "In6.Cu")
		(hatch none 0.5)
		(connect_pads
			(clearance 0)
		)
		(min_thickness 0.25)
		(keepout
			(tracks not_allowed)
			(vias allowed)
			(pads allowed)
			(copperpour not_allowed)
			(footprints allowed)
		)
		(placement
			(enabled no)
			(sheetname "")
		)
		(fill yes
			(thermal_gap 0.5)
			(thermal_bridge_width 0.5)
			(island_removal_mode 0)
		)
		(polygon
			(pts
				(arc
					(start 222.339154 -481.631498)
					(mid 221.727141 -481.019104)
					(end 221.114874 -481.631244)
				)
				(arc
					(start 221.114874 -482.748844)
					(mid 221.727014 -483.360984)
					(end 222.339154 -482.748844)
				)
			)
		)
	)
	(zone
		(layers "In1.Cu" "In3.Cu" "In4.Cu" "In6.Cu")
		(hatch none 0.5)
		(connect_pads
			(clearance 0)
		)
		(min_thickness 0.25)
		(keepout
			(tracks not_allowed)
			(vias allowed)
			(pads allowed)
			(copperpour not_allowed)
			(footprints allowed)
		)
		(placement
			(enabled no)
			(sheetname "")
		)
		(fill yes
			(thermal_gap 0.5)
			(thermal_bridge_width 0.5)
			(island_removal_mode 0)
		)
		(polygon
			(pts
				(arc
					(start 74.269854 -429.61306)
					(mid 73.75906 -430.123473)
					(end 74.2696 -430.63414)
				)
				(arc
					(start 75.0824 -430.63414)
					(mid 75.59294 -430.1236)
					(end 75.0824 -429.61306)
				)
			)
		)
	)
	(zone
		(layers "In1.Cu" "In3.Cu" "In4.Cu" "In6.Cu")
		(hatch none 0.5)
		(connect_pads
			(clearance 0)
		)
		(min_thickness 0.25)
		(keepout
			(tracks not_allowed)
			(vias allowed)
			(pads allowed)
			(copperpour not_allowed)
			(footprints allowed)
		)
		(placement
			(enabled no)
			(sheetname "")
		)
		(fill yes
			(thermal_gap 0.5)
			(thermal_bridge_width 0.5)
			(island_removal_mode 0)
		)
		(polygon
			(pts
				(arc
					(start 35.84067 -278.183848)
					(mid 35.330257 -277.673054)
					(end 34.81959 -278.183594)
				)
				(arc
					(start 34.81959 -278.996394)
					(mid 35.33013 -279.506934)
					(end 35.84067 -278.996394)
				)
			)
		)
	)
	(zone
		(layers "In1.Cu" "In3.Cu" "In4.Cu" "In6.Cu")
		(hatch none 0.5)
		(connect_pads
			(clearance 0)
		)
		(min_thickness 0.25)
		(keepout
			(tracks not_allowed)
			(vias allowed)
			(pads allowed)
			(copperpour not_allowed)
			(footprints allowed)
		)
		(placement
			(enabled no)
			(sheetname "")
		)
		(fill yes
			(thermal_gap 0.5)
			(thermal_bridge_width 0.5)
			(island_removal_mode 0)
		)
		(polygon
			(pts
				(arc
					(start 48.89754 -472.5797)
					(mid 48.387127 -472.068906)
					(end 47.87646 -472.579446)
				)
				(arc
					(start 47.87646 -473.392246)
					(mid 48.387 -473.902786)
					(end 48.89754 -473.392246)
				)
			)
		)
	)
	(zone
		(layers "In1.Cu" "In3.Cu" "In4.Cu" "In6.Cu")
		(hatch none 0.5)
		(connect_pads
			(clearance 0)
		)
		(min_thickness 0.25)
		(keepout
			(tracks not_allowed)
			(vias allowed)
			(pads allowed)
			(copperpour not_allowed)
			(footprints allowed)
		)
		(placement
			(enabled no)
			(sheetname "")
		)
		(fill yes
			(thermal_gap 0.5)
			(thermal_bridge_width 0.5)
			(island_removal_mode 0)
		)
		(polygon
			(pts
				(arc
					(start 37.33927 -74.431398)
					(mid 36.727257 -73.819004)
					(end 36.11499 -74.431144)
				)
				(arc
					(start 36.11499 -75.548744)
					(mid 36.72713 -76.160884)
					(end 37.33927 -75.548744)
				)
			)
		)
	)
	(zone
		(layers "In1.Cu" "In3.Cu" "In4.Cu" "In6.Cu")
		(hatch none 0.5)
		(connect_pads
			(clearance 0)
		)
		(min_thickness 0.25)
		(keepout
			(tracks not_allowed)
			(vias allowed)
			(pads allowed)
			(copperpour not_allowed)
			(footprints allowed)
		)
		(placement
			(enabled no)
			(sheetname "")
		)
		(fill yes
			(thermal_gap 0.5)
			(thermal_bridge_width 0.5)
			(island_removal_mode 0)
		)
		(polygon
			(pts
				(arc
					(start 6.481826 -221.497652)
					(mid 6.992239 -222.008446)
					(end 7.502906 -221.497906)
				)
				(arc
					(start 7.502906 -220.685106)
					(mid 6.992366 -220.174566)
					(end 6.481826 -220.685106)
				)
			)
		)
	)
	(zone
		(layers "In1.Cu" "In3.Cu" "In4.Cu" "In6.Cu")
		(hatch none 0.5)
		(connect_pads
			(clearance 0)
		)
		(min_thickness 0.25)
		(keepout
			(tracks not_allowed)
			(vias allowed)
			(pads allowed)
			(copperpour not_allowed)
			(footprints allowed)
		)
		(placement
			(enabled no)
			(sheetname "")
		)
		(fill yes
			(thermal_gap 0.5)
			(thermal_bridge_width 0.5)
			(island_removal_mode 0)
		)
		(polygon
			(pts
				(arc
					(start 6.481826 -308.34838)
					(mid 6.992239 -308.859174)
					(end 7.502906 -308.348634)
				)
				(arc
					(start 7.502906 -307.535834)
					(mid 6.992366 -307.025294)
					(end 6.481826 -307.535834)
				)
			)
		)
	)
	(zone
		(layers "In1.Cu" "In3.Cu" "In4.Cu" "In6.Cu")
		(hatch none 0.5)
		(connect_pads
			(clearance 0)
		)
		(min_thickness 0.25)
		(keepout
			(tracks not_allowed)
			(vias allowed)
			(pads allowed)
			(copperpour not_allowed)
			(footprints allowed)
		)
		(placement
			(enabled no)
			(sheetname "")
		)
		(fill yes
			(thermal_gap 0.5)
			(thermal_bridge_width 0.5)
			(island_removal_mode 0)
		)
		(polygon
			(pts
				(arc
					(start 25.88514 -139.051284)
					(mid 25.273127 -138.43889)
					(end 24.66086 -139.05103)
				)
				(arc
					(start 24.66086 -140.16863)
					(mid 25.273 -140.78077)
					(end 25.88514 -140.16863)
				)
			)
		)
	)
	(zone
		(layers "In1.Cu" "In3.Cu" "In4.Cu" "In6.Cu")
		(hatch none 0.5)
		(connect_pads
			(clearance 0)
		)
		(min_thickness 0.25)
		(keepout
			(tracks not_allowed)
			(vias allowed)
			(pads allowed)
			(copperpour not_allowed)
			(footprints allowed)
		)
		(placement
			(enabled no)
			(sheetname "")
		)
		(fill yes
			(thermal_gap 0.5)
			(thermal_bridge_width 0.5)
			(island_removal_mode 0)
		)
		(polygon
			(pts
				(arc
					(start 5.59054 -299.535596)
					(mid 5.080127 -299.024802)
					(end 4.56946 -299.535342)
				)
				(arc
					(start 4.56946 -300.348142)
					(mid 5.08 -300.858682)
					(end 5.59054 -300.348142)
				)
			)
		)
	)
	(zone
		(layers "In1.Cu" "In3.Cu" "In4.Cu" "In6.Cu")
		(hatch none 0.5)
		(connect_pads
			(clearance 0)
		)
		(min_thickness 0.25)
		(keepout
			(tracks not_allowed)
			(vias allowed)
			(pads allowed)
			(copperpour not_allowed)
			(footprints allowed)
		)
		(placement
			(enabled no)
			(sheetname "")
		)
		(fill yes
			(thermal_gap 0.5)
			(thermal_bridge_width 0.5)
			(island_removal_mode 0)
		)
		(polygon
			(pts
				(arc
					(start 26.15946 -335.616042)
					(mid 26.669873 -336.126836)
					(end 27.18054 -335.616296)
				)
				(arc
					(start 27.18054 -334.803496)
					(mid 26.67 -334.292956)
					(end 26.15946 -334.803496)
				)
			)
		)
	)
	(zone
		(layers "In1.Cu" "In3.Cu" "In4.Cu" "In6.Cu")
		(hatch none 0.5)
		(connect_pads
			(clearance 0)
		)
		(min_thickness 0.25)
		(keepout
			(tracks not_allowed)
			(vias allowed)
			(pads allowed)
			(copperpour not_allowed)
			(footprints allowed)
		)
		(placement
			(enabled no)
			(sheetname "")
		)
		(fill yes
			(thermal_gap 0.5)
			(thermal_bridge_width 0.5)
			(island_removal_mode 0)
		)
		(polygon
			(pts
				(arc
					(start 6.481826 -357.148384)
					(mid 6.992239 -357.659178)
					(end 7.502906 -357.148638)
				)
				(arc
					(start 7.502906 -356.335838)
					(mid 6.992366 -355.825298)
					(end 6.481826 -356.335838)
				)
			)
		)
	)
	(zone
		(layers "In1.Cu" "In3.Cu" "In4.Cu" "In6.Cu")
		(hatch none 0.5)
		(connect_pads
			(clearance 0)
		)
		(min_thickness 0.25)
		(keepout
			(tracks not_allowed)
			(vias allowed)
			(pads allowed)
			(copperpour not_allowed)
			(footprints allowed)
		)
		(placement
			(enabled no)
			(sheetname "")
		)
		(fill yes
			(thermal_gap 0.5)
			(thermal_bridge_width 0.5)
			(island_removal_mode 0)
		)
		(polygon
			(pts
				(arc
					(start 233.897424 -60.579254)
					(mid 233.386884 -60.068714)
					(end 232.876344 -60.579254)
				)
				(arc
					(start 232.876344 -61.3918)
					(mid 233.386757 -61.902594)
					(end 233.897424 -61.392054)
				)
			)
		)
	)
	(zone
		(layers "In1.Cu" "In3.Cu" "In4.Cu" "In6.Cu")
		(hatch none 0.5)
		(connect_pads
			(clearance 0)
		)
		(min_thickness 0.25)
		(keepout
			(tracks not_allowed)
			(vias allowed)
			(pads allowed)
			(copperpour not_allowed)
			(footprints allowed)
		)
		(placement
			(enabled no)
			(sheetname "")
		)
		(fill yes
			(thermal_gap 0.5)
			(thermal_bridge_width 0.5)
			(island_removal_mode 0)
		)
		(polygon
			(pts
				(arc
					(start 220.840554 -376.384058)
					(mid 220.330141 -375.873264)
					(end 219.819474 -376.383804)
				)
				(arc
					(start 219.819474 -377.196604)
					(mid 220.330014 -377.707144)
					(end 220.840554 -377.196604)
				)
			)
		)
	)
	(zone
		(layers "In1.Cu" "In3.Cu" "In4.Cu" "In6.Cu")
		(hatch none 0.5)
		(connect_pads
			(clearance 0)
		)
		(min_thickness 0.25)
		(keepout
			(tracks not_allowed)
			(vias allowed)
			(pads allowed)
			(copperpour not_allowed)
			(footprints allowed)
		)
		(placement
			(enabled no)
			(sheetname "")
		)
		(fill yes
			(thermal_gap 0.5)
			(thermal_bridge_width 0.5)
			(island_removal_mode 0)
		)
		(polygon
			(pts
				(arc
					(start 6.481826 -403.148292)
					(mid 6.992239 -403.659086)
					(end 7.502906 -403.148546)
				)
				(arc
					(start 7.502906 -402.335746)
					(mid 6.992366 -401.825206)
					(end 6.481826 -402.335746)
				)
			)
		)
	)
	(zone
		(layers "In1.Cu" "In3.Cu" "In4.Cu" "In6.Cu")
		(hatch none 0.5)
		(connect_pads
			(clearance 0)
		)
		(min_thickness 0.25)
		(keepout
			(tracks not_allowed)
			(vias allowed)
			(pads allowed)
			(copperpour not_allowed)
			(footprints allowed)
		)
		(placement
			(enabled no)
			(sheetname "")
		)
		(fill yes
			(thermal_gap 0.5)
			(thermal_bridge_width 0.5)
			(island_removal_mode 0)
		)
		(polygon
			(pts
				(arc
					(start 6.481826 -322.748402)
					(mid 6.992239 -323.259196)
					(end 7.502906 -322.748656)
				)
				(arc
					(start 7.502906 -321.935856)
					(mid 6.992366 -321.425316)
					(end 6.481826 -321.935856)
				)
			)
		)
	)
	(zone
		(layers "In1.Cu" "In3.Cu" "In4.Cu" "In6.Cu")
		(hatch none 0.5)
		(connect_pads
			(clearance 0)
		)
		(min_thickness 0.25)
		(keepout
			(tracks not_allowed)
			(vias allowed)
			(pads allowed)
			(copperpour not_allowed)
			(footprints allowed)
		)
		(placement
			(enabled no)
			(sheetname "")
		)
		(fill yes
			(thermal_gap 0.5)
			(thermal_bridge_width 0.5)
			(island_removal_mode 0)
		)
		(polygon
			(pts
				(arc
					(start 5.59054 -309.13578)
					(mid 5.080127 -308.624986)
					(end 4.56946 -309.135526)
				)
				(arc
					(start 4.56946 -309.948326)
					(mid 5.08 -310.458866)
					(end 5.59054 -309.948326)
				)
			)
		)
	)
	(zone
		(layers "In1.Cu" "In3.Cu" "In4.Cu" "In6.Cu")
		(hatch none 0.5)
		(connect_pads
			(clearance 0)
		)
		(min_thickness 0.25)
		(keepout
			(tracks not_allowed)
			(vias allowed)
			(pads allowed)
			(copperpour not_allowed)
			(footprints allowed)
		)
		(placement
			(enabled no)
			(sheetname "")
		)
		(fill yes
			(thermal_gap 0.5)
			(thermal_bridge_width 0.5)
			(island_removal_mode 0)
		)
		(polygon
			(pts
				(arc
					(start 35.84067 -363.583982)
					(mid 35.330257 -363.073188)
					(end 34.81959 -363.583728)
				)
				(arc
					(start 34.81959 -364.396528)
					(mid 35.33013 -364.907068)
					(end 35.84067 -364.396528)
				)
			)
		)
	)
	(zone
		(layers "In1.Cu" "In3.Cu" "In4.Cu" "In6.Cu")
		(hatch none 0.5)
		(connect_pads
			(clearance 0)
		)
		(min_thickness 0.25)
		(keepout
			(tracks not_allowed)
			(vias allowed)
			(pads allowed)
			(copperpour not_allowed)
			(footprints allowed)
		)
		(placement
			(enabled no)
			(sheetname "")
		)
		(fill yes
			(thermal_gap 0.5)
			(thermal_bridge_width 0.5)
			(island_removal_mode 0)
		)
		(polygon
			(pts
				(arc
					(start 230.71963 -266.300712)
					(mid 231.230424 -265.790299)
					(end 230.719884 -265.279632)
				)
				(arc
					(start 229.907084 -265.279632)
					(mid 229.396544 -265.790172)
					(end 229.907084 -266.300712)
				)
			)
		)
	)
	(zone
		(layers "In1.Cu" "In3.Cu" "In4.Cu" "In6.Cu")
		(hatch none 0.5)
		(connect_pads
			(clearance 0)
		)
		(min_thickness 0.25)
		(keepout
			(tracks not_allowed)
			(vias allowed)
			(pads allowed)
			(copperpour not_allowed)
			(footprints allowed)
		)
		(placement
			(enabled no)
			(sheetname "")
		)
		(fill yes
			(thermal_gap 0.5)
			(thermal_bridge_width 0.5)
			(island_removal_mode 0)
		)
		(polygon
			(pts
				(arc
					(start 37.33927 -69.631306)
					(mid 36.727257 -69.018912)
					(end 36.11499 -69.631052)
				)
				(arc
					(start 36.11499 -70.748652)
					(mid 36.72713 -71.360792)
					(end 37.33927 -70.748652)
				)
			)
		)
	)
	(zone
		(layers "In1.Cu" "In3.Cu" "In4.Cu" "In6.Cu")
		(hatch none 0.5)
		(connect_pads
			(clearance 0)
		)
		(min_thickness 0.25)
		(keepout
			(tracks not_allowed)
			(vias allowed)
			(pads allowed)
			(copperpour not_allowed)
			(footprints allowed)
		)
		(placement
			(enabled no)
			(sheetname "")
		)
		(fill yes
			(thermal_gap 0.5)
			(thermal_bridge_width 0.5)
			(island_removal_mode 0)
		)
		(polygon
			(pts
				(arc
					(start 222.339154 -275.631402)
					(mid 221.727141 -275.019008)
					(end 221.114874 -275.631148)
				)
				(arc
					(start 221.114874 -276.748748)
					(mid 221.727014 -277.360888)
					(end 222.339154 -276.748748)
				)
			)
		)
	)
	(zone
		(layers "In1.Cu" "In3.Cu" "In4.Cu" "In6.Cu")
		(hatch none 0.5)
		(connect_pads
			(clearance 0)
		)
		(min_thickness 0.25)
		(keepout
			(tracks not_allowed)
			(vias allowed)
			(pads allowed)
			(copperpour not_allowed)
			(footprints allowed)
		)
		(placement
			(enabled no)
			(sheetname "")
		)
		(fill yes
			(thermal_gap 0.5)
			(thermal_bridge_width 0.5)
			(island_removal_mode 0)
		)
		(polygon
			(pts
				(arc
					(start 7.502906 -152.786842)
					(mid 6.992493 -152.276048)
					(end 6.481826 -152.786588)
				)
				(arc
					(start 6.481826 -153.599388)
					(mid 6.992366 -154.109928)
					(end 7.502906 -153.599388)
				)
			)
		)
	)
	(zone
		(layers "In1.Cu" "In3.Cu" "In4.Cu" "In6.Cu")
		(hatch none 0.5)
		(connect_pads
			(clearance 0)
		)
		(min_thickness 0.25)
		(keepout
			(tracks not_allowed)
			(vias allowed)
			(pads allowed)
			(copperpour not_allowed)
			(footprints allowed)
		)
		(placement
			(enabled no)
			(sheetname "")
		)
		(fill yes
			(thermal_gap 0.5)
			(thermal_bridge_width 0.5)
			(island_removal_mode 0)
		)
		(polygon
			(pts
				(arc
					(start 222.339154 -159.831532)
					(mid 221.727141 -159.219138)
					(end 221.114874 -159.831278)
				)
				(arc
					(start 221.114874 -160.948878)
					(mid 221.727014 -161.561018)
					(end 222.339154 -160.948878)
				)
			)
		)
	)
	(zone
		(layers "In1.Cu" "In3.Cu" "In4.Cu" "In6.Cu")
		(hatch none 0.5)
		(connect_pads
			(clearance 0)
		)
		(min_thickness 0.25)
		(keepout
			(tracks not_allowed)
			(vias allowed)
			(pads allowed)
			(copperpour not_allowed)
			(footprints allowed)
		)
		(placement
			(enabled no)
			(sheetname "")
		)
		(fill yes
			(thermal_gap 0.5)
			(thermal_bridge_width 0.5)
			(island_removal_mode 0)
		)
		(polygon
			(pts
				(arc
					(start 37.33927 -275.631402)
					(mid 36.727257 -275.019008)
					(end 36.11499 -275.631148)
				)
				(arc
					(start 36.11499 -276.748748)
					(mid 36.72713 -277.360888)
					(end 37.33927 -276.748748)
				)
			)
		)
	)
	(zone
		(layers "In1.Cu" "In3.Cu" "In4.Cu" "In6.Cu")
		(hatch none 0.5)
		(connect_pads
			(clearance 0)
		)
		(min_thickness 0.25)
		(keepout
			(tracks not_allowed)
			(vias allowed)
			(pads allowed)
			(copperpour not_allowed)
			(footprints allowed)
		)
		(placement
			(enabled no)
			(sheetname "")
		)
		(fill yes
			(thermal_gap 0.5)
			(thermal_bridge_width 0.5)
			(island_removal_mode 0)
		)
		(polygon
			(pts
				(arc
					(start 7.502906 -214.285322)
					(mid 6.992493 -213.774528)
					(end 6.481826 -214.285068)
				)
				(arc
					(start 6.481826 -215.097868)
					(mid 6.992366 -215.608408)
					(end 7.502906 -215.097868)
				)
			)
		)
	)
	(zone
		(layers "In1.Cu" "In3.Cu" "In4.Cu" "In6.Cu")
		(hatch none 0.5)
		(connect_pads
			(clearance 0)
		)
		(min_thickness 0.25)
		(keepout
			(tracks not_allowed)
			(vias allowed)
			(pads allowed)
			(copperpour not_allowed)
			(footprints allowed)
		)
		(placement
			(enabled no)
			(sheetname "")
		)
		(fill yes
			(thermal_gap 0.5)
			(thermal_bridge_width 0.5)
			(island_removal_mode 0)
		)
		(polygon
			(pts
				(arc
					(start 6.481826 -409.54833)
					(mid 6.992239 -410.059124)
					(end 7.502906 -409.548584)
				)
				(arc
					(start 7.502906 -408.735784)
					(mid 6.992366 -408.225244)
					(end 6.481826 -408.735784)
				)
			)
		)
	)
	(zone
		(layers "In1.Cu" "In3.Cu" "In4.Cu" "In6.Cu")
		(hatch none 0.5)
		(connect_pads
			(clearance 0)
		)
		(min_thickness 0.25)
		(keepout
			(tracks not_allowed)
			(vias allowed)
			(pads allowed)
			(copperpour not_allowed)
			(footprints allowed)
		)
		(placement
			(enabled no)
			(sheetname "")
		)
		(fill yes
			(thermal_gap 0.5)
			(thermal_bridge_width 0.5)
			(island_removal_mode 0)
		)
		(polygon
			(pts
				(arc
					(start 5.59054 -338.73567)
					(mid 5.080127 -338.224876)
					(end 4.56946 -338.735416)
				)
				(arc
					(start 4.56946 -339.548216)
					(mid 5.08 -340.058756)
					(end 5.59054 -339.548216)
				)
			)
		)
	)
	(zone
		(layers "In1.Cu" "In3.Cu" "In4.Cu" "In6.Cu")
		(hatch none 0.5)
		(connect_pads
			(clearance 0)
		)
		(min_thickness 0.25)
		(keepout
			(tracks not_allowed)
			(vias allowed)
			(pads allowed)
			(copperpour not_allowed)
			(footprints allowed)
		)
		(placement
			(enabled no)
			(sheetname "")
		)
		(fill yes
			(thermal_gap 0.5)
			(thermal_bridge_width 0.5)
			(island_removal_mode 0)
		)
		(polygon
			(pts
				(arc
					(start 4.56946 -411.147768)
					(mid 5.079873 -411.658562)
					(end 5.59054 -411.148022)
				)
				(arc
					(start 5.59054 -410.335222)
					(mid 5.08 -409.824682)
					(end 4.56946 -410.335222)
				)
			)
		)
	)
	(zone
		(layers "In1.Cu" "In3.Cu" "In4.Cu" "In6.Cu")
		(hatch none 0.5)
		(connect_pads
			(clearance 0)
		)
		(min_thickness 0.25)
		(keepout
			(tracks not_allowed)
			(vias allowed)
			(pads allowed)
			(copperpour not_allowed)
			(footprints allowed)
		)
		(placement
			(enabled no)
			(sheetname "")
		)
		(fill yes
			(thermal_gap 0.5)
			(thermal_bridge_width 0.5)
			(island_removal_mode 0)
		)
		(polygon
			(pts
				(arc
					(start 5.59054 -228.735636)
					(mid 5.080127 -228.224842)
					(end 4.56946 -228.735382)
				)
				(arc
					(start 4.56946 -229.548182)
					(mid 5.08 -230.058722)
					(end 5.59054 -229.548182)
				)
			)
		)
	)
	(zone
		(layers "In1.Cu" "In3.Cu" "In4.Cu" "In6.Cu")
		(hatch none 0.5)
		(connect_pads
			(clearance 0)
		)
		(min_thickness 0.25)
		(keepout
			(tracks not_allowed)
			(vias allowed)
			(pads allowed)
			(copperpour not_allowed)
			(footprints allowed)
		)
		(placement
			(enabled no)
			(sheetname "")
		)
		(fill yes
			(thermal_gap 0.5)
			(thermal_bridge_width 0.5)
			(island_removal_mode 0)
		)
		(polygon
			(pts
				(arc
					(start 7.502906 -159.18688)
					(mid 6.992493 -158.676086)
					(end 6.481826 -159.186626)
				)
				(arc
					(start 6.481826 -159.999426)
					(mid 6.992366 -160.509966)
					(end 7.502906 -159.999426)
				)
			)
		)
	)
	(zone
		(layers "In1.Cu" "In3.Cu" "In4.Cu" "In6.Cu")
		(hatch none 0.5)
		(connect_pads
			(clearance 0)
		)
		(min_thickness 0.25)
		(keepout
			(tracks not_allowed)
			(vias allowed)
			(pads allowed)
			(copperpour not_allowed)
			(footprints allowed)
		)
		(placement
			(enabled no)
			(sheetname "")
		)
		(fill yes
			(thermal_gap 0.5)
			(thermal_bridge_width 0.5)
			(island_removal_mode 0)
		)
		(polygon
			(pts
				(arc
					(start 35.84067 -282.98394)
					(mid 35.330257 -282.473146)
					(end 34.81959 -282.983686)
				)
				(arc
					(start 34.81959 -283.796486)
					(mid 35.33013 -284.307026)
					(end 35.84067 -283.796486)
				)
			)
		)
	)
	(zone
		(layers "In1.Cu" "In3.Cu" "In4.Cu" "In6.Cu")
		(hatch none 0.5)
		(connect_pads
			(clearance 0)
		)
		(min_thickness 0.25)
		(keepout
			(tracks not_allowed)
			(vias allowed)
			(pads allowed)
			(copperpour not_allowed)
			(footprints allowed)
		)
		(placement
			(enabled no)
			(sheetname "")
		)
		(fill yes
			(thermal_gap 0.5)
			(thermal_bridge_width 0.5)
			(island_removal_mode 0)
		)
		(polygon
			(pts
				(arc
					(start 229.907084 -471.279728)
					(mid 229.396544 -471.790268)
					(end 229.907084 -472.300808)
				)
				(arc
					(start 230.71963 -472.300808)
					(mid 231.230424 -471.790395)
					(end 230.719884 -471.279728)
				)
			)
		)
	)
	(zone
		(layers "In1.Cu" "In3.Cu" "In4.Cu" "In6.Cu")
		(hatch none 0.5)
		(connect_pads
			(clearance 0)
		)
		(min_thickness 0.25)
		(keepout
			(tracks not_allowed)
			(vias allowed)
			(pads allowed)
			(copperpour not_allowed)
			(footprints allowed)
		)
		(placement
			(enabled no)
			(sheetname "")
		)
		(fill yes
			(thermal_gap 0.5)
			(thermal_bridge_width 0.5)
			(island_removal_mode 0)
		)
		(polygon
			(pts
				(arc
					(start 5.59054 -183.135778)
					(mid 5.080127 -182.624984)
					(end 4.56946 -183.135524)
				)
				(arc
					(start 4.56946 -183.948324)
					(mid 5.08 -184.458864)
					(end 5.59054 -183.948324)
				)
			)
		)
	)
	(zone
		(layers "In1.Cu" "In3.Cu" "In4.Cu" "In6.Cu")
		(hatch none 0.5)
		(connect_pads
			(clearance 0)
		)
		(min_thickness 0.25)
		(keepout
			(tracks not_allowed)
			(vias allowed)
			(pads allowed)
			(copperpour not_allowed)
			(footprints allowed)
		)
		(placement
			(enabled no)
			(sheetname "")
		)
		(fill yes
			(thermal_gap 0.5)
			(thermal_bridge_width 0.5)
			(island_removal_mode 0)
		)
		(polygon
			(pts
				(arc
					(start 5.59054 -335.535778)
					(mid 5.080127 -335.024984)
					(end 4.56946 -335.535524)
				)
				(arc
					(start 4.56946 -336.348324)
					(mid 5.08 -336.858864)
					(end 5.59054 -336.348324)
				)
			)
		)
	)
	(zone
		(layers "In1.Cu" "In3.Cu" "In4.Cu" "In6.Cu")
		(hatch none 0.5)
		(connect_pads
			(clearance 0)
		)
		(min_thickness 0.25)
		(keepout
			(tracks not_allowed)
			(vias allowed)
			(pads allowed)
			(copperpour not_allowed)
			(footprints allowed)
		)
		(placement
			(enabled no)
			(sheetname "")
		)
		(fill yes
			(thermal_gap 0.5)
			(thermal_bridge_width 0.5)
			(island_removal_mode 0)
		)
		(polygon
			(pts
				(arc
					(start 37.33927 -262.83158)
					(mid 36.727257 -262.219186)
					(end 36.11499 -262.831326)
				)
				(arc
					(start 36.11499 -263.948926)
					(mid 36.72713 -264.561066)
					(end 37.33927 -263.948926)
				)
			)
		)
	)
	(zone
		(layers "In1.Cu" "In3.Cu" "In4.Cu" "In6.Cu")
		(hatch none 0.5)
		(connect_pads
			(clearance 0)
		)
		(min_thickness 0.25)
		(keepout
			(tracks not_allowed)
			(vias allowed)
			(pads allowed)
			(copperpour not_allowed)
			(footprints allowed)
		)
		(placement
			(enabled no)
			(sheetname "")
		)
		(fill yes
			(thermal_gap 0.5)
			(thermal_bridge_width 0.5)
			(island_removal_mode 0)
		)
		(polygon
			(pts
				(arc
					(start 32.00654 -135.603996)
					(mid 31.496127 -135.093202)
					(end 30.98546 -135.603742)
				)
				(arc
					(start 30.98546 -136.416542)
					(mid 31.496 -136.927082)
					(end 32.00654 -136.416542)
				)
			)
		)
	)
	(zone
		(layers "In1.Cu" "In3.Cu" "In4.Cu" "In6.Cu")
		(hatch none 0.5)
		(connect_pads
			(clearance 0)
		)
		(min_thickness 0.25)
		(keepout
			(tracks not_allowed)
			(vias allowed)
			(pads allowed)
			(copperpour not_allowed)
			(footprints allowed)
		)
		(placement
			(enabled no)
			(sheetname "")
		)
		(fill yes
			(thermal_gap 0.5)
			(thermal_bridge_width 0.5)
			(island_removal_mode 0)
		)
		(polygon
			(pts
				(arc
					(start 5.59054 -289.935666)
					(mid 5.080127 -289.424872)
					(end 4.56946 -289.935412)
				)
				(arc
					(start 4.56946 -290.748212)
					(mid 5.08 -291.258752)
					(end 5.59054 -290.748212)
				)
			)
		)
	)
	(zone
		(layers "In1.Cu" "In3.Cu" "In4.Cu" "In6.Cu")
		(hatch none 0.5)
		(connect_pads
			(clearance 0)
		)
		(min_thickness 0.25)
		(keepout
			(tracks not_allowed)
			(vias allowed)
			(pads allowed)
			(copperpour not_allowed)
			(footprints allowed)
		)
		(placement
			(enabled no)
			(sheetname "")
		)
		(fill yes
			(thermal_gap 0.5)
			(thermal_bridge_width 0.5)
			(island_removal_mode 0)
		)
		(polygon
			(pts
				(arc
					(start 5.59054 -416.735514)
					(mid 5.080127 -416.22472)
					(end 4.56946 -416.73526)
				)
				(arc
					(start 4.56946 -417.54806)
					(mid 5.08 -418.0586)
					(end 5.59054 -417.54806)
				)
			)
		)
	)
	(zone
		(layers "In1.Cu" "In3.Cu" "In4.Cu" "In6.Cu")
		(hatch none 0.5)
		(connect_pads
			(clearance 0)
		)
		(min_thickness 0.25)
		(keepout
			(tracks not_allowed)
			(vias allowed)
			(pads allowed)
			(copperpour not_allowed)
			(footprints allowed)
		)
		(placement
			(enabled no)
			(sheetname "")
		)
		(fill yes
			(thermal_gap 0.5)
			(thermal_bridge_width 0.5)
			(island_removal_mode 0)
		)
		(polygon
			(pts
				(arc
					(start 7.502906 -207.936084)
					(mid 6.992493 -207.42529)
					(end 6.481826 -207.93583)
				)
				(arc
					(start 6.481826 -208.74863)
					(mid 6.992366 -209.25917)
					(end 7.502906 -208.74863)
				)
			)
		)
	)
	(zone
		(layers "In1.Cu" "In3.Cu" "In4.Cu" "In6.Cu")
		(hatch none 0.5)
		(connect_pads
			(clearance 0)
		)
		(min_thickness 0.25)
		(keepout
			(tracks not_allowed)
			(vias allowed)
			(pads allowed)
			(copperpour not_allowed)
			(footprints allowed)
		)
		(placement
			(enabled no)
			(sheetname "")
		)
		(fill yes
			(thermal_gap 0.5)
			(thermal_bridge_width 0.5)
			(island_removal_mode 0)
		)
		(polygon
			(pts
				(arc
					(start 27.18054 -21.003514)
					(mid 26.67 -20.492974)
					(end 26.15946 -21.003514)
				)
				(arc
					(start 26.15946 -21.81606)
					(mid 26.669873 -22.326854)
					(end 27.18054 -21.816314)
				)
			)
		)
	)
	(zone
		(layers "In1.Cu" "In3.Cu" "In4.Cu" "In6.Cu")
		(hatch none 0.5)
		(connect_pads
			(clearance 0)
		)
		(min_thickness 0.25)
		(keepout
			(tracks not_allowed)
			(vias allowed)
			(pads allowed)
			(copperpour not_allowed)
			(footprints allowed)
		)
		(placement
			(enabled no)
			(sheetname "")
		)
		(fill yes
			(thermal_gap 0.5)
			(thermal_bridge_width 0.5)
			(island_removal_mode 0)
		)
		(polygon
			(pts
				(arc
					(start 233.897424 -163.579302)
					(mid 233.386884 -163.068762)
					(end 232.876344 -163.579302)
				)
				(arc
					(start 232.876344 -164.391848)
					(mid 233.386757 -164.902642)
					(end 233.897424 -164.392102)
				)
			)
		)
	)
	(zone
		(layers "In1.Cu" "In3.Cu" "In4.Cu" "In6.Cu")
		(hatch none 0.5)
		(connect_pads
			(clearance 0)
		)
		(min_thickness 0.25)
		(keepout
			(tracks not_allowed)
			(vias allowed)
			(pads allowed)
			(copperpour not_allowed)
			(footprints allowed)
		)
		(placement
			(enabled no)
			(sheetname "")
		)
		(fill yes
			(thermal_gap 0.5)
			(thermal_bridge_width 0.5)
			(island_removal_mode 0)
		)
		(polygon
			(pts
				(arc
					(start 5.59054 -176.73574)
					(mid 5.080127 -176.224946)
					(end 4.56946 -176.735486)
				)
				(arc
					(start 4.56946 -177.548286)
					(mid 5.08 -178.058826)
					(end 5.59054 -177.548286)
				)
			)
		)
	)
	(zone
		(layers "In1.Cu" "In3.Cu" "In4.Cu" "In6.Cu")
		(hatch none 0.5)
		(connect_pads
			(clearance 0)
		)
		(min_thickness 0.25)
		(keepout
			(tracks not_allowed)
			(vias allowed)
			(pads allowed)
			(copperpour not_allowed)
			(footprints allowed)
		)
		(placement
			(enabled no)
			(sheetname "")
		)
		(fill yes
			(thermal_gap 0.5)
			(thermal_bridge_width 0.5)
			(island_removal_mode 0)
		)
		(polygon
			(pts
				(arc
					(start 4.56946 -439.147712)
					(mid 5.079873 -439.658506)
					(end 5.59054 -439.147966)
				)
				(arc
					(start 5.59054 -438.335166)
					(mid 5.08 -437.824626)
					(end 4.56946 -438.335166)
				)
			)
		)
	)
	(zone
		(layers "In1.Cu" "In3.Cu" "In4.Cu" "In6.Cu")
		(hatch none 0.5)
		(connect_pads
			(clearance 0)
		)
		(min_thickness 0.25)
		(keepout
			(tracks not_allowed)
			(vias allowed)
			(pads allowed)
			(copperpour not_allowed)
			(footprints allowed)
		)
		(placement
			(enabled no)
			(sheetname "")
		)
		(fill yes
			(thermal_gap 0.5)
			(thermal_bridge_width 0.5)
			(island_removal_mode 0)
		)
		(polygon
			(pts
				(arc
					(start 6.481826 -295.548558)
					(mid 6.992239 -296.059352)
					(end 7.502906 -295.548812)
				)
				(arc
					(start 7.502906 -294.736012)
					(mid 6.992366 -294.225472)
					(end 6.481826 -294.736012)
				)
			)
		)
	)
	(zone
		(layers "In1.Cu" "In3.Cu" "In4.Cu" "In6.Cu")
		(hatch none 0.5)
		(connect_pads
			(clearance 0)
		)
		(min_thickness 0.25)
		(keepout
			(tracks not_allowed)
			(vias allowed)
			(pads allowed)
			(copperpour not_allowed)
			(footprints allowed)
		)
		(placement
			(enabled no)
			(sheetname "")
		)
		(fill yes
			(thermal_gap 0.5)
			(thermal_bridge_width 0.5)
			(island_removal_mode 0)
		)
		(polygon
			(pts
				(arc
					(start 6.481826 -347.548454)
					(mid 6.992239 -348.059248)
					(end 7.502906 -347.548708)
				)
				(arc
					(start 7.502906 -346.735908)
					(mid 6.992366 -346.225368)
					(end 6.481826 -346.735908)
				)
			)
		)
	)
	(zone
		(layers "In1.Cu" "In3.Cu" "In4.Cu" "In6.Cu")
		(hatch none 0.5)
		(connect_pads
			(clearance 0)
		)
		(min_thickness 0.25)
		(keepout
			(tracks not_allowed)
			(vias allowed)
			(pads allowed)
			(copperpour not_allowed)
			(footprints allowed)
		)
		(placement
			(enabled no)
			(sheetname "")
		)
		(fill yes
			(thermal_gap 0.5)
			(thermal_bridge_width 0.5)
			(island_removal_mode 0)
		)
		(polygon
			(pts
				(arc
					(start 7.502906 -217.485468)
					(mid 6.992493 -216.974674)
					(end 6.481826 -217.485214)
				)
				(arc
					(start 6.481826 -218.298014)
					(mid 6.992366 -218.808554)
					(end 7.502906 -218.298014)
				)
			)
		)
	)
	(zone
		(layers "In1.Cu" "In3.Cu" "In4.Cu" "In6.Cu")
		(hatch none 0.5)
		(connect_pads
			(clearance 0)
		)
		(min_thickness 0.25)
		(keepout
			(tracks not_allowed)
			(vias allowed)
			(pads allowed)
			(copperpour not_allowed)
			(footprints allowed)
		)
		(placement
			(enabled no)
			(sheetname "")
		)
		(fill yes
			(thermal_gap 0.5)
			(thermal_bridge_width 0.5)
			(island_removal_mode 0)
		)
		(polygon
			(pts
				(arc
					(start 37.33927 -383.431542)
					(mid 36.727257 -382.819148)
					(end 36.11499 -383.431288)
				)
				(arc
					(start 36.11499 -384.548888)
					(mid 36.72713 -385.161028)
					(end 37.33927 -384.548888)
				)
			)
		)
	)
	(zone
		(layers "In1.Cu" "In3.Cu" "In4.Cu" "In6.Cu")
		(hatch none 0.5)
		(connect_pads
			(clearance 0)
		)
		(min_thickness 0.25)
		(keepout
			(tracks not_allowed)
			(vias allowed)
			(pads allowed)
			(copperpour not_allowed)
			(footprints allowed)
		)
		(placement
			(enabled no)
			(sheetname "")
		)
		(fill yes
			(thermal_gap 0.5)
			(thermal_bridge_width 0.5)
			(island_removal_mode 0)
		)
		(polygon
			(pts
				(arc
					(start 6.481826 -325.948548)
					(mid 6.992239 -326.459342)
					(end 7.502906 -325.948802)
				)
				(arc
					(start 7.502906 -325.136002)
					(mid 6.992366 -324.625462)
					(end 6.481826 -325.136002)
				)
			)
		)
	)
	(zone
		(layers "In1.Cu" "In3.Cu" "In4.Cu" "In6.Cu")
		(hatch none 0.5)
		(connect_pads
			(clearance 0)
		)
		(min_thickness 0.25)
		(keepout
			(tracks not_allowed)
			(vias allowed)
			(pads allowed)
			(copperpour not_allowed)
			(footprints allowed)
		)
		(placement
			(enabled no)
			(sheetname "")
		)
		(fill yes
			(thermal_gap 0.5)
			(thermal_bridge_width 0.5)
			(island_removal_mode 0)
		)
		(polygon
			(pts
				(arc
					(start 5.59054 -215.93556)
					(mid 5.080127 -215.424766)
					(end 4.56946 -215.935306)
				)
				(arc
					(start 4.56946 -216.748106)
					(mid 5.08 -217.258646)
					(end 5.59054 -216.748106)
				)
			)
		)
	)
	(zone
		(layers "In1.Cu" "In3.Cu" "In4.Cu" "In6.Cu")
		(hatch none 0.5)
		(connect_pads
			(clearance 0)
		)
		(min_thickness 0.25)
		(keepout
			(tracks not_allowed)
			(vias allowed)
			(pads allowed)
			(copperpour not_allowed)
			(footprints allowed)
		)
		(placement
			(enabled no)
			(sheetname "")
		)
		(fill yes
			(thermal_gap 0.5)
			(thermal_bridge_width 0.5)
			(island_removal_mode 0)
		)
		(polygon
			(pts
				(arc
					(start 4.56946 -442.347858)
					(mid 5.079873 -442.858652)
					(end 5.59054 -442.348112)
				)
				(arc
					(start 5.59054 -441.535312)
					(mid 5.08 -441.024772)
					(end 4.56946 -441.535312)
				)
			)
		)
	)
	(zone
		(layers "In1.Cu" "In3.Cu" "In4.Cu" "In6.Cu")
		(hatch none 0.5)
		(connect_pads
			(clearance 0)
		)
		(min_thickness 0.25)
		(keepout
			(tracks not_allowed)
			(vias allowed)
			(pads allowed)
			(copperpour not_allowed)
			(footprints allowed)
		)
		(placement
			(enabled no)
			(sheetname "")
		)
		(fill yes
			(thermal_gap 0.5)
			(thermal_bridge_width 0.5)
			(island_removal_mode 0)
		)
		(polygon
			(pts
				(arc
					(start 222.339154 -182.231538)
					(mid 221.727141 -181.619144)
					(end 221.114874 -182.231284)
				)
				(arc
					(start 221.114874 -183.348884)
					(mid 221.727014 -183.961024)
					(end 222.339154 -183.348884)
				)
			)
		)
	)
	(zone
		(layers "In1.Cu" "In3.Cu" "In4.Cu" "In6.Cu")
		(hatch none 0.5)
		(connect_pads
			(clearance 0)
		)
		(min_thickness 0.25)
		(keepout
			(tracks not_allowed)
			(vias allowed)
			(pads allowed)
			(copperpour not_allowed)
			(footprints allowed)
		)
		(placement
			(enabled no)
			(sheetname "")
		)
		(fill yes
			(thermal_gap 0.5)
			(thermal_bridge_width 0.5)
			(island_removal_mode 0)
		)
		(polygon
			(pts
				(arc
					(start 222.339154 -69.631306)
					(mid 221.727141 -69.018912)
					(end 221.114874 -69.631052)
				)
				(arc
					(start 221.114874 -70.748652)
					(mid 221.727014 -71.360792)
					(end 222.339154 -70.748652)
				)
			)
		)
	)
	(zone
		(layers "In1.Cu" "In3.Cu" "In4.Cu" "In6.Cu")
		(hatch none 0.5)
		(connect_pads
			(clearance 0)
		)
		(min_thickness 0.25)
		(keepout
			(tracks not_allowed)
			(vias allowed)
			(pads allowed)
			(copperpour not_allowed)
			(footprints allowed)
		)
		(placement
			(enabled no)
			(sheetname "")
		)
		(fill yes
			(thermal_gap 0.5)
			(thermal_bridge_width 0.5)
			(island_removal_mode 0)
		)
		(polygon
			(pts
				(arc
					(start 7.502906 -230.33609)
					(mid 6.992493 -229.825296)
					(end 6.481826 -230.335836)
				)
				(arc
					(start 6.481826 -231.148636)
					(mid 6.992366 -231.659176)
					(end 7.502906 -231.148636)
				)
			)
		)
	)
	(zone
		(layers "In1.Cu" "In3.Cu" "In4.Cu" "In6.Cu")
		(hatch none 0.5)
		(connect_pads
			(clearance 0)
		)
		(min_thickness 0.25)
		(keepout
			(tracks not_allowed)
			(vias allowed)
			(pads allowed)
			(copperpour not_allowed)
			(footprints allowed)
		)
		(placement
			(enabled no)
			(sheetname "")
		)
		(fill yes
			(thermal_gap 0.5)
			(thermal_bridge_width 0.5)
			(island_removal_mode 0)
		)
		(polygon
			(pts
				(arc
					(start 7.502906 -171.986956)
					(mid 6.992493 -171.476162)
					(end 6.481826 -171.986702)
				)
				(arc
					(start 6.481826 -172.799502)
					(mid 6.992366 -173.310042)
					(end 7.502906 -172.799502)
				)
			)
		)
	)
	(zone
		(layers "In1.Cu" "In3.Cu" "In4.Cu" "In6.Cu")
		(hatch none 0.5)
		(connect_pads
			(clearance 0)
		)
		(min_thickness 0.25)
		(keepout
			(tracks not_allowed)
			(vias allowed)
			(pads allowed)
			(copperpour not_allowed)
			(footprints allowed)
		)
		(placement
			(enabled no)
			(sheetname "")
		)
		(fill yes
			(thermal_gap 0.5)
			(thermal_bridge_width 0.5)
			(island_removal_mode 0)
		)
		(polygon
			(pts
				(arc
					(start 37.33927 -378.63145)
					(mid 36.727257 -378.019056)
					(end 36.11499 -378.631196)
				)
				(arc
					(start 36.11499 -379.748796)
					(mid 36.72713 -380.360936)
					(end 37.33927 -379.748796)
				)
			)
		)
	)
	(zone
		(layers "In1.Cu" "In3.Cu" "In4.Cu" "In6.Cu")
		(hatch none 0.5)
		(connect_pads
			(clearance 0)
		)
		(min_thickness 0.25)
		(keepout
			(tracks not_allowed)
			(vias allowed)
			(pads allowed)
			(copperpour not_allowed)
			(footprints allowed)
		)
		(placement
			(enabled no)
			(sheetname "")
		)
		(fill yes
			(thermal_gap 0.5)
			(thermal_bridge_width 0.5)
			(island_removal_mode 0)
		)
		(polygon
			(pts
				(arc
					(start 220.840554 -273.38401)
					(mid 220.330141 -272.873216)
					(end 219.819474 -273.383756)
				)
				(arc
					(start 219.819474 -274.196556)
					(mid 220.330014 -274.707096)
					(end 220.840554 -274.196556)
				)
			)
		)
	)
	(zone
		(layers "In1.Cu" "In3.Cu" "In4.Cu" "In6.Cu")
		(hatch none 0.5)
		(connect_pads
			(clearance 0)
		)
		(min_thickness 0.25)
		(keepout
			(tracks not_allowed)
			(vias allowed)
			(pads allowed)
			(copperpour not_allowed)
			(footprints allowed)
		)
		(placement
			(enabled no)
			(sheetname "")
		)
		(fill yes
			(thermal_gap 0.5)
			(thermal_bridge_width 0.5)
			(island_removal_mode 0)
		)
		(polygon
			(pts
				(arc
					(start 37.33927 -280.431494)
					(mid 36.727257 -279.8191)
					(end 36.11499 -280.43124)
				)
				(arc
					(start 36.11499 -281.54884)
					(mid 36.72713 -282.16098)
					(end 37.33927 -281.54884)
				)
			)
		)
	)
	(zone
		(layers "In1.Cu" "In3.Cu" "In4.Cu" "In6.Cu")
		(hatch none 0.5)
		(connect_pads
			(clearance 0)
		)
		(min_thickness 0.25)
		(keepout
			(tracks not_allowed)
			(vias allowed)
			(pads allowed)
			(copperpour not_allowed)
			(footprints allowed)
		)
		(placement
			(enabled no)
			(sheetname "")
		)
		(fill yes
			(thermal_gap 0.5)
			(thermal_bridge_width 0.5)
			(island_removal_mode 0)
		)
		(polygon
			(pts
				(arc
					(start 220.840554 -170.383962)
					(mid 220.330141 -169.873168)
					(end 219.819474 -170.383708)
				)
				(arc
					(start 219.819474 -171.196508)
					(mid 220.330014 -171.707048)
					(end 220.840554 -171.196508)
				)
			)
		)
	)
	(zone
		(layers "In1.Cu" "In3.Cu" "In4.Cu" "In6.Cu")
		(hatch none 0.5)
		(connect_pads
			(clearance 0)
		)
		(min_thickness 0.25)
		(keepout
			(tracks not_allowed)
			(vias allowed)
			(pads allowed)
			(copperpour not_allowed)
			(footprints allowed)
		)
		(placement
			(enabled no)
			(sheetname "")
		)
		(fill yes
			(thermal_gap 0.5)
			(thermal_bridge_width 0.5)
			(island_removal_mode 0)
		)
		(polygon
			(pts
				(arc
					(start 4.56946 -404.74773)
					(mid 5.079873 -405.258524)
					(end 5.59054 -404.747984)
				)
				(arc
					(start 5.59054 -403.935184)
					(mid 5.08 -403.424644)
					(end 4.56946 -403.935184)
				)
			)
		)
	)
	(zone
		(layers "In1.Cu" "In3.Cu" "In4.Cu" "In6.Cu")
		(hatch none 0.5)
		(connect_pads
			(clearance 0)
		)
		(min_thickness 0.25)
		(keepout
			(tracks not_allowed)
			(vias allowed)
			(pads allowed)
			(copperpour not_allowed)
			(footprints allowed)
		)
		(placement
			(enabled no)
			(sheetname "")
		)
		(fill yes
			(thermal_gap 0.5)
			(thermal_bridge_width 0.5)
			(island_removal_mode 0)
		)
		(polygon
			(pts
				(arc
					(start 26.15946 -223.016064)
					(mid 26.669873 -223.526858)
					(end 27.18054 -223.016318)
				)
				(arc
					(start 27.18054 -222.203518)
					(mid 26.67 -221.692978)
					(end 26.15946 -222.203518)
				)
			)
		)
	)
	(zone
		(layers "In1.Cu" "In3.Cu" "In4.Cu" "In6.Cu")
		(hatch none 0.5)
		(connect_pads
			(clearance 0)
		)
		(min_thickness 0.25)
		(keepout
			(tracks not_allowed)
			(vias allowed)
			(pads allowed)
			(copperpour not_allowed)
			(footprints allowed)
		)
		(placement
			(enabled no)
			(sheetname "")
		)
		(fill yes
			(thermal_gap 0.5)
			(thermal_bridge_width 0.5)
			(island_removal_mode 0)
		)
		(polygon
			(pts
				(arc
					(start 35.84067 -175.1838)
					(mid 35.330257 -174.673006)
					(end 34.81959 -175.183546)
				)
				(arc
					(start 34.81959 -175.996346)
					(mid 35.33013 -176.506886)
					(end 35.84067 -175.996346)
				)
			)
		)
	)
	(zone
		(layers "In1.Cu" "In3.Cu" "In4.Cu" "In6.Cu")
		(hatch none 0.5)
		(connect_pads
			(clearance 0)
		)
		(min_thickness 0.25)
		(keepout
			(tracks not_allowed)
			(vias allowed)
			(pads allowed)
			(copperpour not_allowed)
			(footprints allowed)
		)
		(placement
			(enabled no)
			(sheetname "")
		)
		(fill yes
			(thermal_gap 0.5)
			(thermal_bridge_width 0.5)
			(island_removal_mode 0)
		)
		(polygon
			(pts
				(arc
					(start 25.88514 -126.251208)
					(mid 25.273 -125.639068)
					(end 24.66086 -126.251208)
				)
				(arc
					(start 24.66086 -127.368554)
					(mid 25.272873 -127.980948)
					(end 25.88514 -127.368808)
				)
			)
		)
	)
	(zone
		(layers "In1.Cu" "In3.Cu" "In4.Cu" "In6.Cu")
		(hatch none 0.5)
		(connect_pads
			(clearance 0)
		)
		(min_thickness 0.25)
		(keepout
			(tracks not_allowed)
			(vias allowed)
			(pads allowed)
			(copperpour not_allowed)
			(footprints allowed)
		)
		(placement
			(enabled no)
			(sheetname "")
		)
		(fill yes
			(thermal_gap 0.5)
			(thermal_bridge_width 0.5)
			(island_removal_mode 0)
		)
		(polygon
			(pts
				(arc
					(start 5.59054 -398.3355)
					(mid 5.080127 -397.824706)
					(end 4.56946 -398.335246)
				)
				(arc
					(start 4.56946 -399.148046)
					(mid 5.08 -399.658586)
					(end 5.59054 -399.148046)
				)
			)
		)
	)
	(zone
		(layers "In1.Cu" "In3.Cu" "In4.Cu" "In6.Cu")
		(hatch none 0.5)
		(connect_pads
			(clearance 0)
		)
		(min_thickness 0.25)
		(keepout
			(tracks not_allowed)
			(vias allowed)
			(pads allowed)
			(copperpour not_allowed)
			(footprints allowed)
		)
		(placement
			(enabled no)
			(sheetname "")
		)
		(fill yes
			(thermal_gap 0.5)
			(thermal_bridge_width 0.5)
			(island_removal_mode 0)
		)
		(polygon
			(pts
				(arc
					(start 7.502906 -155.974288)
					(mid 6.992493 -155.463494)
					(end 6.481826 -155.974034)
				)
				(arc
					(start 6.481826 -156.786834)
					(mid 6.992366 -157.297374)
					(end 7.502906 -156.786834)
				)
			)
		)
	)
	(zone
		(layers "In1.Cu" "In3.Cu" "In4.Cu" "In6.Cu")
		(hatch none 0.5)
		(connect_pads
			(clearance 0)
		)
		(min_thickness 0.25)
		(keepout
			(tracks not_allowed)
			(vias allowed)
			(pads allowed)
			(copperpour not_allowed)
			(footprints allowed)
		)
		(placement
			(enabled no)
			(sheetname "")
		)
		(fill yes
			(thermal_gap 0.5)
			(thermal_bridge_width 0.5)
			(island_removal_mode 0)
		)
		(polygon
			(pts
				(arc
					(start 48.89754 -163.579556)
					(mid 48.387127 -163.068762)
					(end 47.87646 -163.579302)
				)
				(arc
					(start 47.87646 -164.392102)
					(mid 48.387 -164.902642)
					(end 48.89754 -164.392102)
				)
			)
		)
	)
	(zone
		(layers "In1.Cu" "In3.Cu" "In4.Cu" "In6.Cu")
		(hatch none 0.5)
		(connect_pads
			(clearance 0)
		)
		(min_thickness 0.25)
		(keepout
			(tracks not_allowed)
			(vias allowed)
			(pads allowed)
			(copperpour not_allowed)
			(footprints allowed)
		)
		(placement
			(enabled no)
			(sheetname "")
		)
		(fill yes
			(thermal_gap 0.5)
			(thermal_bridge_width 0.5)
			(island_removal_mode 0)
		)
		(polygon
			(pts
				(arc
					(start 44.907454 -59.279536)
					(mid 44.39666 -59.789949)
					(end 44.9072 -60.300616)
				)
				(arc
					(start 45.72 -60.300616)
					(mid 46.23054 -59.790076)
					(end 45.72 -59.279536)
				)
			)
		)
	)
	(zone
		(layers "In1.Cu" "In3.Cu" "In4.Cu" "In6.Cu")
		(hatch none 0.5)
		(connect_pads
			(clearance 0)
		)
		(min_thickness 0.25)
		(keepout
			(tracks not_allowed)
			(vias allowed)
			(pads allowed)
			(copperpour not_allowed)
			(footprints allowed)
		)
		(placement
			(enabled no)
			(sheetname "")
		)
		(fill yes
			(thermal_gap 0.5)
			(thermal_bridge_width 0.5)
			(island_removal_mode 0)
		)
		(polygon
			(pts
				(arc
					(start 7.502906 -192.736216)
					(mid 6.992493 -192.225422)
					(end 6.481826 -192.735962)
				)
				(arc
					(start 6.481826 -193.548762)
					(mid 6.992366 -194.059302)
					(end 7.502906 -193.548762)
				)
			)
		)
	)
	(zone
		(layers "In1.Cu" "In3.Cu" "In4.Cu" "In6.Cu")
		(hatch none 0.5)
		(connect_pads
			(clearance 0)
		)
		(min_thickness 0.25)
		(keepout
			(tracks not_allowed)
			(vias allowed)
			(pads allowed)
			(copperpour not_allowed)
			(footprints allowed)
		)
		(placement
			(enabled no)
			(sheetname "")
		)
		(fill yes
			(thermal_gap 0.5)
			(thermal_bridge_width 0.5)
			(island_removal_mode 0)
		)
		(polygon
			(pts
				(arc
					(start 44.9072 -471.279728)
					(mid 44.39666 -471.790268)
					(end 44.9072 -472.300808)
				)
				(arc
					(start 45.719746 -472.300808)
					(mid 46.23054 -471.790395)
					(end 45.72 -471.279728)
				)
			)
		)
	)
	(zone
		(layers "In1.Cu" "In3.Cu" "In4.Cu" "In6.Cu")
		(hatch none 0.5)
		(connect_pads
			(clearance 0)
		)
		(min_thickness 0.25)
		(keepout
			(tracks not_allowed)
			(vias allowed)
			(pads allowed)
			(copperpour not_allowed)
			(footprints allowed)
		)
		(placement
			(enabled no)
			(sheetname "")
		)
		(fill yes
			(thermal_gap 0.5)
			(thermal_bridge_width 0.5)
			(island_removal_mode 0)
		)
		(polygon
			(pts
				(arc
					(start 5.59054 -212.735668)
					(mid 5.080127 -212.224874)
					(end 4.56946 -212.735414)
				)
				(arc
					(start 4.56946 -213.548214)
					(mid 5.08 -214.058754)
					(end 5.59054 -213.548214)
				)
			)
		)
	)
	(zone
		(layers "In1.Cu" "In3.Cu" "In4.Cu" "In6.Cu")
		(hatch none 0.5)
		(connect_pads
			(clearance 0)
		)
		(min_thickness 0.25)
		(keepout
			(tracks not_allowed)
			(vias allowed)
			(pads allowed)
			(copperpour not_allowed)
			(footprints allowed)
		)
		(placement
			(enabled no)
			(sheetname "")
		)
		(fill yes
			(thermal_gap 0.5)
			(thermal_bridge_width 0.5)
			(island_removal_mode 0)
		)
		(polygon
			(pts
				(arc
					(start 7.502906 -195.936108)
					(mid 6.992493 -195.425314)
					(end 6.481826 -195.935854)
				)
				(arc
					(start 6.481826 -196.748654)
					(mid 6.992366 -197.259194)
					(end 7.502906 -196.748654)
				)
			)
		)
	)
	(zone
		(layers "In1.Cu" "In3.Cu" "In4.Cu" "In6.Cu")
		(hatch none 0.5)
		(connect_pads
			(clearance 0)
		)
		(min_thickness 0.25)
		(keepout
			(tracks not_allowed)
			(vias allowed)
			(pads allowed)
			(copperpour not_allowed)
			(footprints allowed)
		)
		(placement
			(enabled no)
			(sheetname "")
		)
		(fill yes
			(thermal_gap 0.5)
			(thermal_bridge_width 0.5)
			(island_removal_mode 0)
		)
		(polygon
			(pts
				(arc
					(start 5.59054 -388.73557)
					(mid 5.080127 -388.224776)
					(end 4.56946 -388.735316)
				)
				(arc
					(start 4.56946 -389.548116)
					(mid 5.08 -390.058656)
					(end 5.59054 -389.548116)
				)
			)
		)
	)
	(zone
		(layers "In1.Cu" "In3.Cu" "In4.Cu" "In6.Cu")
		(hatch none 0.5)
		(connect_pads
			(clearance 0)
		)
		(min_thickness 0.25)
		(keepout
			(tracks not_allowed)
			(vias allowed)
			(pads allowed)
			(copperpour not_allowed)
			(footprints allowed)
		)
		(placement
			(enabled no)
			(sheetname "")
		)
		(fill yes
			(thermal_gap 0.5)
			(thermal_bridge_width 0.5)
			(island_removal_mode 0)
		)
		(polygon
			(pts
				(arc
					(start 7.502906 -424.78452)
					(mid 6.992493 -424.273726)
					(end 6.481826 -424.784266)
				)
				(arc
					(start 6.481826 -425.597066)
					(mid 6.992366 -426.107606)
					(end 7.502906 -425.597066)
				)
			)
		)
	)
	(zone
		(layers "In1.Cu" "In3.Cu" "In4.Cu" "In6.Cu")
		(hatch none 0.5)
		(connect_pads
			(clearance 0)
		)
		(min_thickness 0.25)
		(keepout
			(tracks not_allowed)
			(vias allowed)
			(pads allowed)
			(copperpour not_allowed)
			(footprints allowed)
		)
		(placement
			(enabled no)
			(sheetname "")
		)
		(fill yes
			(thermal_gap 0.5)
			(thermal_bridge_width 0.5)
			(island_removal_mode 0)
		)
		(polygon
			(pts
				(arc
					(start 220.840554 -484.183944)
					(mid 220.330141 -483.67315)
					(end 219.819474 -484.18369)
				)
				(arc
					(start 219.819474 -484.99649)
					(mid 220.330014 -485.50703)
					(end 220.840554 -484.99649)
				)
			)
		)
	)
	(zone
		(layers "In1.Cu" "In3.Cu" "In4.Cu" "In6.Cu")
		(hatch none 0.5)
		(connect_pads
			(clearance 0)
		)
		(min_thickness 0.25)
		(keepout
			(tracks not_allowed)
			(vias allowed)
			(pads allowed)
			(copperpour not_allowed)
			(footprints allowed)
		)
		(placement
			(enabled no)
			(sheetname "")
		)
		(fill yes
			(thermal_gap 0.5)
			(thermal_bridge_width 0.5)
			(island_removal_mode 0)
		)
		(polygon
			(pts
				(arc
					(start 33.40354 -341.584788)
					(mid 32.893127 -341.073994)
					(end 32.38246 -341.584534)
				)
				(arc
					(start 32.38246 -342.397334)
					(mid 32.893 -342.907874)
					(end 33.40354 -342.397334)
				)
			)
		)
	)
	(zone
		(layers "In1.Cu" "In3.Cu" "In4.Cu" "In6.Cu")
		(hatch none 0.5)
		(connect_pads
			(clearance 0)
		)
		(min_thickness 0.25)
		(keepout
			(tracks not_allowed)
			(vias allowed)
			(pads allowed)
			(copperpour not_allowed)
			(footprints allowed)
		)
		(placement
			(enabled no)
			(sheetname "")
		)
		(fill yes
			(thermal_gap 0.5)
			(thermal_bridge_width 0.5)
			(island_removal_mode 0)
		)
		(polygon
			(pts
				(arc
					(start 5.59054 -426.335444)
					(mid 5.080127 -425.82465)
					(end 4.56946 -426.33519)
				)
				(arc
					(start 4.56946 -427.14799)
					(mid 5.08 -427.65853)
					(end 5.59054 -427.14799)
				)
			)
		)
	)
	(zone
		(layers "In1.Cu" "In3.Cu" "In4.Cu" "In6.Cu")
		(hatch none 0.5)
		(connect_pads
			(clearance 0)
		)
		(min_thickness 0.25)
		(keepout
			(tracks not_allowed)
			(vias allowed)
			(pads allowed)
			(copperpour not_allowed)
			(footprints allowed)
		)
		(placement
			(enabled no)
			(sheetname "")
		)
		(fill yes
			(thermal_gap 0.5)
			(thermal_bridge_width 0.5)
			(island_removal_mode 0)
		)
		(polygon
			(pts
				(arc
					(start 27.18054 -124.003562)
					(mid 26.67 -123.493022)
					(end 26.15946 -124.003562)
				)
				(arc
					(start 26.15946 -124.816108)
					(mid 26.669873 -125.326902)
					(end 27.18054 -124.816362)
				)
			)
		)
	)
	(zone
		(layers "In1.Cu" "In3.Cu" "In4.Cu" "In6.Cu")
		(hatch none 0.5)
		(connect_pads
			(clearance 0)
		)
		(min_thickness 0.25)
		(keepout
			(tracks not_allowed)
			(vias allowed)
			(pads allowed)
			(copperpour not_allowed)
			(footprints allowed)
		)
		(placement
			(enabled no)
			(sheetname "")
		)
		(fill yes
			(thermal_gap 0.5)
			(thermal_bridge_width 0.5)
			(island_removal_mode 0)
		)
		(polygon
			(pts
				(arc
					(start 233.897424 -369.579398)
					(mid 233.386884 -369.068858)
					(end 232.876344 -369.579398)
				)
				(arc
					(start 232.876344 -370.391944)
					(mid 233.386757 -370.902738)
					(end 233.897424 -370.392198)
				)
			)
		)
	)
	(zone
		(layers "In1.Cu" "In3.Cu" "In4.Cu" "In6.Cu")
		(hatch none 0.5)
		(connect_pads
			(clearance 0)
		)
		(min_thickness 0.25)
		(keepout
			(tracks not_allowed)
			(vias allowed)
			(pads allowed)
			(copperpour not_allowed)
			(footprints allowed)
		)
		(placement
			(enabled no)
			(sheetname "")
		)
		(fill yes
			(thermal_gap 0.5)
			(thermal_bridge_width 0.5)
			(island_removal_mode 0)
		)
		(polygon
			(pts
				(arc
					(start 5.59054 -341.935562)
					(mid 5.080127 -341.424768)
					(end 4.56946 -341.935308)
				)
				(arc
					(start 4.56946 -342.748108)
					(mid 5.08 -343.258648)
					(end 5.59054 -342.748108)
				)
			)
		)
	)
	(zone
		(layers "In1.Cu" "In3.Cu" "In4.Cu" "In6.Cu")
		(hatch none 0.5)
		(connect_pads
			(clearance 0)
		)
		(min_thickness 0.25)
		(keepout
			(tracks not_allowed)
			(vias allowed)
			(pads allowed)
			(copperpour not_allowed)
			(footprints allowed)
		)
		(placement
			(enabled no)
			(sheetname "")
		)
		(fill yes
			(thermal_gap 0.5)
			(thermal_bridge_width 0.5)
			(island_removal_mode 0)
		)
		(polygon
			(pts
				(arc
					(start 7.502906 -343.58707)
					(mid 6.992493 -343.076276)
					(end 6.481826 -343.586816)
				)
				(arc
					(start 6.481826 -344.399616)
					(mid 6.992366 -344.910156)
					(end 7.502906 -344.399616)
				)
			)
		)
	)
	(zone
		(layers "In1.Cu" "In3.Cu" "In4.Cu" "In6.Cu")
		(hatch none 0.5)
		(connect_pads
			(clearance 0)
		)
		(min_thickness 0.25)
		(keepout
			(tracks not_allowed)
			(vias allowed)
			(pads allowed)
			(copperpour not_allowed)
			(footprints allowed)
		)
		(placement
			(enabled no)
			(sheetname "")
		)
		(fill yes
			(thermal_gap 0.5)
			(thermal_bridge_width 0.5)
			(island_removal_mode 0)
		)
		(polygon
			(pts
				(arc
					(start 6.481826 -305.148488)
					(mid 6.992239 -305.659282)
					(end 7.502906 -305.148742)
				)
				(arc
					(start 7.502906 -304.335942)
					(mid 6.992366 -303.825402)
					(end 6.481826 -304.335942)
				)
			)
		)
	)
	(zone
		(layers "In1.Cu" "In3.Cu" "In4.Cu" "In6.Cu")
		(hatch none 0.5)
		(connect_pads
			(clearance 0)
		)
		(min_thickness 0.25)
		(keepout
			(tracks not_allowed)
			(vias allowed)
			(pads allowed)
			(copperpour not_allowed)
			(footprints allowed)
		)
		(placement
			(enabled no)
			(sheetname "")
		)
		(fill yes
			(thermal_gap 0.5)
			(thermal_bridge_width 0.5)
			(island_removal_mode 0)
		)
		(polygon
			(pts
				(arc
					(start 37.33927 -56.831484)
					(mid 36.727257 -56.21909)
					(end 36.11499 -56.83123)
				)
				(arc
					(start 36.11499 -57.94883)
					(mid 36.72713 -58.56097)
					(end 37.33927 -57.94883)
				)
			)
		)
	)
	(zone
		(layers "In1.Cu" "In3.Cu" "In4.Cu" "In6.Cu")
		(hatch none 0.5)
		(connect_pads
			(clearance 0)
		)
		(min_thickness 0.25)
		(keepout
			(tracks not_allowed)
			(vias allowed)
			(pads allowed)
			(copperpour not_allowed)
			(footprints allowed)
		)
		(placement
			(enabled no)
			(sheetname "")
		)
		(fill yes
			(thermal_gap 0.5)
			(thermal_bridge_width 0.5)
			(island_removal_mode 0)
		)
		(polygon
			(pts
				(arc
					(start 36.11499 -492.348774)
					(mid 36.727003 -492.961168)
					(end 37.33927 -492.349028)
				)
				(arc
					(start 37.33927 -491.231428)
					(mid 36.72713 -490.619288)
					(end 36.11499 -491.231428)
				)
			)
		)
	)
	(zone
		(layers "In1.Cu" "In3.Cu" "In4.Cu" "In6.Cu")
		(hatch none 0.5)
		(connect_pads
			(clearance 0)
		)
		(min_thickness 0.25)
		(keepout
			(tracks not_allowed)
			(vias allowed)
			(pads allowed)
			(copperpour not_allowed)
			(footprints allowed)
		)
		(placement
			(enabled no)
			(sheetname "")
		)
		(fill yes
			(thermal_gap 0.5)
			(thermal_bridge_width 0.5)
			(island_removal_mode 0)
		)
		(polygon
			(pts
				(arc
					(start 7.502906 -168.787064)
					(mid 6.992493 -168.27627)
					(end 6.481826 -168.78681)
				)
				(arc
					(start 6.481826 -169.59961)
					(mid 6.992366 -170.11015)
					(end 7.502906 -169.59961)
				)
			)
		)
	)
	(zone
		(layers "In1.Cu" "In3.Cu" "In4.Cu" "In6.Cu")
		(hatch none 0.5)
		(connect_pads
			(clearance 0)
		)
		(min_thickness 0.25)
		(keepout
			(tracks not_allowed)
			(vias allowed)
			(pads allowed)
			(copperpour not_allowed)
			(footprints allowed)
		)
		(placement
			(enabled no)
			(sheetname "")
		)
		(fill yes
			(thermal_gap 0.5)
			(thermal_bridge_width 0.5)
			(island_removal_mode 0)
		)
		(polygon
			(pts
				(arc
					(start 220.840554 -179.983892)
					(mid 220.330141 -179.473098)
					(end 219.819474 -179.983638)
				)
				(arc
					(start 219.819474 -180.796438)
					(mid 220.330014 -181.306978)
					(end 220.840554 -180.796438)
				)
			)
		)
	)
	(zone
		(layers "In1.Cu" "In3.Cu" "In4.Cu" "In6.Cu")
		(hatch none 0.5)
		(connect_pads
			(clearance 0)
		)
		(min_thickness 0.25)
		(keepout
			(tracks not_allowed)
			(vias allowed)
			(pads allowed)
			(copperpour not_allowed)
			(footprints allowed)
		)
		(placement
			(enabled no)
			(sheetname "")
		)
		(fill yes
			(thermal_gap 0.5)
			(thermal_bridge_width 0.5)
			(island_removal_mode 0)
		)
		(polygon
			(pts
				(arc
					(start 25.88514 -448.051428)
					(mid 25.273127 -447.439034)
					(end 24.66086 -448.051174)
				)
				(arc
					(start 24.66086 -449.168774)
					(mid 25.273 -449.780914)
					(end 25.88514 -449.168774)
				)
			)
		)
	)
	(zone
		(layers "In1.Cu" "In3.Cu" "In4.Cu" "In6.Cu")
		(hatch none 0.5)
		(connect_pads
			(clearance 0)
		)
		(min_thickness 0.25)
		(keepout
			(tracks not_allowed)
			(vias allowed)
			(pads allowed)
			(copperpour not_allowed)
			(footprints allowed)
		)
		(placement
			(enabled no)
			(sheetname "")
		)
		(fill yes
			(thermal_gap 0.5)
			(thermal_bridge_width 0.5)
			(island_removal_mode 0)
		)
		(polygon
			(pts
				(arc
					(start 26.15946 -142.416022)
					(mid 26.669873 -142.926816)
					(end 27.18054 -142.416276)
				)
				(arc
					(start 27.18054 -141.603476)
					(mid 26.67 -141.092936)
					(end 26.15946 -141.603476)
				)
			)
		)
	)
	(zone
		(layers "In1.Cu" "In3.Cu" "In4.Cu" "In6.Cu")
		(hatch none 0.5)
		(connect_pads
			(clearance 0)
		)
		(min_thickness 0.25)
		(keepout
			(tracks not_allowed)
			(vias allowed)
			(pads allowed)
			(copperpour not_allowed)
			(footprints allowed)
		)
		(placement
			(enabled no)
			(sheetname "")
		)
		(fill yes
			(thermal_gap 0.5)
			(thermal_bridge_width 0.5)
			(island_removal_mode 0)
		)
		(polygon
			(pts
				(arc
					(start 27.18054 -433.00396)
					(mid 26.670127 -432.493166)
					(end 26.15946 -433.003706)
				)
				(arc
					(start 26.15946 -433.816506)
					(mid 26.67 -434.327046)
					(end 27.18054 -433.816506)
				)
			)
		)
	)
	(zone
		(layers "In1.Cu" "In3.Cu" "In4.Cu" "In6.Cu")
		(hatch none 0.5)
		(connect_pads
			(clearance 0)
		)
		(min_thickness 0.25)
		(keepout
			(tracks not_allowed)
			(vias allowed)
			(pads allowed)
			(copperpour not_allowed)
			(footprints allowed)
		)
		(placement
			(enabled no)
			(sheetname "")
		)
		(fill yes
			(thermal_gap 0.5)
			(thermal_bridge_width 0.5)
			(island_removal_mode 0)
		)
		(polygon
			(pts
				(arc
					(start 34.81959 -467.396322)
					(mid 35.330003 -467.907116)
					(end 35.84067 -467.396576)
				)
				(arc
					(start 35.84067 -466.583776)
					(mid 35.33013 -466.073236)
					(end 34.81959 -466.583776)
				)
			)
		)
	)
	(zone
		(layers "In1.Cu" "In3.Cu" "In4.Cu" "In6.Cu")
		(hatch none 0.5)
		(connect_pads
			(clearance 0)
		)
		(min_thickness 0.25)
		(keepout
			(tracks not_allowed)
			(vias allowed)
			(pads allowed)
			(copperpour not_allowed)
			(footprints allowed)
		)
		(placement
			(enabled no)
			(sheetname "")
		)
		(fill yes
			(thermal_gap 0.5)
			(thermal_bridge_width 0.5)
			(island_removal_mode 0)
		)
		(polygon
			(pts
				(arc
					(start 26.15946 -232.615994)
					(mid 26.669873 -233.126788)
					(end 27.18054 -232.616248)
				)
				(arc
					(start 27.18054 -231.803448)
					(mid 26.67 -231.292908)
					(end 26.15946 -231.803448)
				)
			)
		)
	)
	(zone
		(layers "In1.Cu" "In3.Cu" "In4.Cu" "In6.Cu")
		(hatch none 0.5)
		(connect_pads
			(clearance 0)
		)
		(min_thickness 0.25)
		(keepout
			(tracks not_allowed)
			(vias allowed)
			(pads allowed)
			(copperpour not_allowed)
			(footprints allowed)
		)
		(placement
			(enabled no)
			(sheetname "")
		)
		(fill yes
			(thermal_gap 0.5)
			(thermal_bridge_width 0.5)
			(island_removal_mode 0)
		)
		(polygon
			(pts
				(arc
					(start 5.59054 -231.935782)
					(mid 5.080127 -231.424988)
					(end 4.56946 -231.935528)
				)
				(arc
					(start 4.56946 -232.748328)
					(mid 5.08 -233.258868)
					(end 5.59054 -232.748328)
				)
			)
		)
	)
	(zone
		(layers "In1.Cu" "In3.Cu" "In4.Cu" "In6.Cu")
		(hatch none 0.5)
		(connect_pads
			(clearance 0)
		)
		(min_thickness 0.25)
		(keepout
			(tracks not_allowed)
			(vias allowed)
			(pads allowed)
			(copperpour not_allowed)
			(footprints allowed)
		)
		(placement
			(enabled no)
			(sheetname "")
		)
		(fill yes
			(thermal_gap 0.5)
			(thermal_bridge_width 0.5)
			(island_removal_mode 0)
		)
		(polygon
			(pts
				(arc
					(start 7.502906 -178.386994)
					(mid 6.992493 -177.8762)
					(end 6.481826 -178.38674)
				)
				(arc
					(start 6.481826 -179.19954)
					(mid 6.992366 -179.71008)
					(end 7.502906 -179.19954)
				)
			)
		)
	)
	(zone
		(layers "In1.Cu" "In3.Cu" "In4.Cu" "In6.Cu")
		(hatch none 0.5)
		(connect_pads
			(clearance 0)
		)
		(min_thickness 0.25)
		(keepout
			(tracks not_allowed)
			(vias allowed)
			(pads allowed)
			(copperpour not_allowed)
			(footprints allowed)
		)
		(placement
			(enabled no)
			(sheetname "")
		)
		(fill yes
			(thermal_gap 0.5)
			(thermal_bridge_width 0.5)
			(island_removal_mode 0)
		)
		(polygon
			(pts
				(arc
					(start 5.59054 -320.335656)
					(mid 5.080127 -319.824862)
					(end 4.56946 -320.335402)
				)
				(arc
					(start 4.56946 -321.148202)
					(mid 5.08 -321.658742)
					(end 5.59054 -321.148202)
				)
			)
		)
	)
	(zone
		(layers "In1.Cu" "In3.Cu" "In4.Cu" "In6.Cu")
		(hatch none 0.5)
		(connect_pads
			(clearance 0)
		)
		(min_thickness 0.25)
		(keepout
			(tracks not_allowed)
			(vias allowed)
			(pads allowed)
			(copperpour not_allowed)
			(footprints allowed)
		)
		(placement
			(enabled no)
			(sheetname "")
		)
		(fill yes
			(thermal_gap 0.5)
			(thermal_bridge_width 0.5)
			(island_removal_mode 0)
		)
		(polygon
			(pts
				(arc
					(start 25.88514 -430.451514)
					(mid 25.273127 -429.83912)
					(end 24.66086 -430.45126)
				)
				(arc
					(start 24.66086 -431.56886)
					(mid 25.273 -432.181)
					(end 25.88514 -431.56886)
				)
			)
		)
	)
	(zone
		(layers "In1.Cu" "In3.Cu" "In4.Cu" "In6.Cu")
		(hatch none 0.5)
		(connect_pads
			(clearance 0)
		)
		(min_thickness 0.25)
		(keepout
			(tracks not_allowed)
			(vias allowed)
			(pads allowed)
			(copperpour not_allowed)
			(footprints allowed)
		)
		(placement
			(enabled no)
			(sheetname "")
		)
		(fill yes
			(thermal_gap 0.5)
			(thermal_bridge_width 0.5)
			(island_removal_mode 0)
		)
		(polygon
			(pts
				(arc
					(start 32.26054 -444.58509)
					(mid 31.750127 -444.074296)
					(end 31.23946 -444.584836)
				)
				(arc
					(start 31.23946 -445.397636)
					(mid 31.75 -445.908176)
					(end 32.26054 -445.397636)
				)
			)
		)
	)
	(zone
		(layers "In1.Cu" "In3.Cu" "In4.Cu" "In6.Cu")
		(hatch none 0.5)
		(connect_pads
			(clearance 0)
		)
		(min_thickness 0.25)
		(keepout
			(tracks not_allowed)
			(vias allowed)
			(pads allowed)
			(copperpour not_allowed)
			(footprints allowed)
		)
		(placement
			(enabled no)
			(sheetname "")
		)
		(fill yes
			(thermal_gap 0.5)
			(thermal_bridge_width 0.5)
			(island_removal_mode 0)
		)
		(polygon
			(pts
				(arc
					(start 27.18054 -450.603874)
					(mid 26.670127 -450.09308)
					(end 26.15946 -450.60362)
				)
				(arc
					(start 26.15946 -451.41642)
					(mid 26.67 -451.92696)
					(end 27.18054 -451.41642)
				)
			)
		)
	)
	(zone
		(layers "In1.Cu" "In3.Cu" "In4.Cu" "In6.Cu")
		(hatch none 0.5)
		(connect_pads
			(clearance 0)
		)
		(min_thickness 0.25)
		(keepout
			(tracks not_allowed)
			(vias allowed)
			(pads allowed)
			(copperpour not_allowed)
			(footprints allowed)
		)
		(placement
			(enabled no)
			(sheetname "")
		)
		(fill yes
			(thermal_gap 0.5)
			(thermal_bridge_width 0.5)
			(island_removal_mode 0)
		)
		(polygon
			(pts
				(arc
					(start 220.840554 -76.983844)
					(mid 220.330141 -76.47305)
					(end 219.819474 -76.98359)
				)
				(arc
					(start 219.819474 -77.79639)
					(mid 220.330014 -78.30693)
					(end 220.840554 -77.79639)
				)
			)
		)
	)
	(zone
		(layers "In1.Cu" "In3.Cu" "In4.Cu" "In6.Cu")
		(hatch none 0.5)
		(connect_pads
			(clearance 0)
		)
		(min_thickness 0.25)
		(keepout
			(tracks not_allowed)
			(vias allowed)
			(pads allowed)
			(copperpour not_allowed)
			(footprints allowed)
		)
		(placement
			(enabled no)
			(sheetname "")
		)
		(fill yes
			(thermal_gap 0.5)
			(thermal_bridge_width 0.5)
			(island_removal_mode 0)
		)
		(polygon
			(pts
				(arc
					(start 26.15946 -245.41607)
					(mid 26.669873 -245.926864)
					(end 27.18054 -245.416324)
				)
				(arc
					(start 27.18054 -244.603524)
					(mid 26.67 -244.092984)
					(end 26.15946 -244.603524)
				)
			)
		)
	)
	(zone
		(layer "In2.Cu")
		(hatch none 0.5)
		(connect_pads
			(clearance 0)
		)
		(min_thickness 0.25)
		(keepout
			(tracks not_allowed)
			(vias allowed)
			(pads allowed)
			(copperpour not_allowed)
			(footprints allowed)
		)
		(placement
			(enabled no)
			(sheetname "")
		)
		(fill
			(thermal_gap 0.5)
			(thermal_bridge_width 0.5)
			(island_removal_mode 0)
		)
		(polygon
			(pts
				(arc
					(start 5.59054 -403.935184)
					(mid 5.08 -403.424644)
					(end 4.56946 -403.935184)
				)
				(arc
					(start 4.56946 -404.74773)
					(mid 5.079873 -405.258524)
					(end 5.59054 -404.747984)
				)
				(xy 5.59054 -404.614888) (xy 5.347716 -404.614888)
				(arc
					(start 5.323586 -404.639272)
					(mid 4.891383 -404.936601)
					(end 5.188712 -404.504398)
				)
				(xy 5.268976 -404.424388) (xy 5.59054 -404.424388) (xy 5.59054 -404.259288) (xy 5.269484 -404.259288)
				(arc
					(start 5.188712 -404.17877)
					(mid 4.891383 -403.746567)
					(end 5.323586 -404.043896)
				)
				(xy 5.348224 -404.068788) (xy 5.59054 -404.068788)
			)
		)
	)
	(zone
		(net "VDD_IO_4")
		(layer "In2.Cu")
		(hatch none 0.5)
		(connect_pads
			(clearance 0.5)
		)
		(min_thickness 0.25)
		(fill yes
			(thermal_gap 0.5)
			(thermal_bridge_width 0.5)
			(island_removal_mode 0)
		)
		(polygon
			(pts
				(xy 93.599 -109.474) (xy 99.568 -109.474) (xy 103.124 -105.918) (xy 103.124 -97.917) (xy 99.06 -93.853)
				(xy 93.345 -93.853) (xy 92.71 -94.488) (xy 92.71 -108.585)
			)
		)
	)
	(zone
		(layer "In2.Cu")
		(hatch none 0.5)
		(connect_pads
			(clearance 0)
		)
		(min_thickness 0.25)
		(keepout
			(tracks not_allowed)
			(vias allowed)
			(pads allowed)
			(copperpour not_allowed)
			(footprints allowed)
		)
		(placement
			(enabled no)
			(sheetname "")
		)
		(fill
			(thermal_gap 0.5)
			(thermal_bridge_width 0.5)
			(island_removal_mode 0)
		)
		(polygon
			(pts
				(arc
					(start 37.33927 -79.23149)
					(mid 36.727257 -78.619096)
					(end 36.11499 -79.231236)
				)
				(xy 36.11499 -79.516986) (xy 36.30676 -79.516986)
				(arc
					(start 36.483544 -79.339948)
					(mid 36.915747 -79.042619)
					(end 36.618418 -79.474822)
				)
				(xy 36.3855 -79.707486) (xy 36.11499 -79.707486) (xy 36.11499 -79.872586) (xy 36.3855 -79.872586)
				(arc
					(start 36.618418 -80.10525)
					(mid 36.915747 -80.537453)
					(end 36.483544 -80.240124)
				)
				(xy 36.30676 -80.063086) (xy 36.11499 -80.063086)
				(arc
					(start 36.11499 -80.348836)
					(mid 36.72713 -80.960976)
					(end 37.33927 -80.348836)
				)
			)
		)
	)
	(zone
		(layer "In2.Cu")
		(hatch none 0.5)
		(connect_pads
			(clearance 0)
		)
		(min_thickness 0.25)
		(keepout
			(tracks not_allowed)
			(vias allowed)
			(pads allowed)
			(copperpour not_allowed)
			(footprints allowed)
		)
		(placement
			(enabled no)
			(sheetname "")
		)
		(fill
			(thermal_gap 0.5)
			(thermal_bridge_width 0.5)
			(island_removal_mode 0)
		)
		(polygon
			(pts
				(arc
					(start 37.33927 -383.431542)
					(mid 36.727257 -382.819148)
					(end 36.11499 -383.431288)
				)
				(xy 36.11499 -383.717292) (xy 36.306506 -383.717292)
				(arc
					(start 36.483544 -383.54)
					(mid 36.915747 -383.242671)
					(end 36.618418 -383.674874)
				)
				(xy 36.385246 -383.907792) (xy 36.11499 -383.907792) (xy 36.11499 -384.072892) (xy 36.385754 -384.072892)
				(arc
					(start 36.618418 -384.305302)
					(mid 36.915747 -384.737505)
					(end 36.483544 -384.440176)
				)
				(xy 36.307014 -384.263392) (xy 36.11499 -384.263392)
				(arc
					(start 36.11499 -384.548888)
					(mid 36.72713 -385.161028)
					(end 37.33927 -384.548888)
				)
			)
		)
	)
	(zone
		(layer "In2.Cu")
		(hatch none 0.5)
		(connect_pads
			(clearance 0)
		)
		(min_thickness 0.25)
		(keepout
			(tracks not_allowed)
			(vias allowed)
			(pads allowed)
			(copperpour not_allowed)
			(footprints allowed)
		)
		(placement
			(enabled no)
			(sheetname "")
		)
		(fill
			(thermal_gap 0.5)
			(thermal_bridge_width 0.5)
			(island_removal_mode 0)
		)
		(polygon
			(pts
				(arc
					(start 5.59054 -348.3356)
					(mid 5.080127 -347.824806)
					(end 4.56946 -348.335346)
				)
				(arc
					(start 4.56946 -349.148146)
					(mid 5.08 -349.658686)
					(end 5.59054 -349.148146)
				)
				(xy 5.59054 -349.015304) (xy 5.347462 -349.015304)
				(arc
					(start 5.323586 -349.039434)
					(mid 4.891383 -349.336763)
					(end 5.188712 -348.90456)
				)
				(xy 5.268722 -348.824804) (xy 5.59054 -348.824804) (xy 5.59054 -348.659704) (xy 5.269738 -348.659704)
				(arc
					(start 5.188712 -348.578932)
					(mid 4.891383 -348.146729)
					(end 5.323586 -348.444058)
				)
				(xy 5.348478 -348.469204) (xy 5.59054 -348.469204)
			)
		)
	)
	(zone
		(layer "In2.Cu")
		(hatch none 0.5)
		(connect_pads
			(clearance 0)
		)
		(min_thickness 0.25)
		(keepout
			(tracks not_allowed)
			(vias allowed)
			(pads allowed)
			(copperpour not_allowed)
			(footprints allowed)
		)
		(placement
			(enabled no)
			(sheetname "")
		)
		(fill
			(thermal_gap 0.5)
			(thermal_bridge_width 0.5)
			(island_removal_mode 0)
		)
		(polygon
			(pts
				(arc
					(start 5.59054 -410.335222)
					(mid 5.08 -409.824682)
					(end 4.56946 -410.335222)
				)
				(arc
					(start 4.56946 -411.147768)
					(mid 5.079873 -411.658562)
					(end 5.59054 -411.148022)
				)
				(xy 5.59054 -411.014926) (xy 5.347716 -411.014926)
				(arc
					(start 5.323586 -411.03931)
					(mid 4.891383 -411.336639)
					(end 5.188712 -410.904436)
				)
				(xy 5.268976 -410.824426) (xy 5.59054 -410.824426) (xy 5.59054 -410.659326) (xy 5.269484 -410.659326)
				(arc
					(start 5.188712 -410.578808)
					(mid 4.891383 -410.146605)
					(end 5.323586 -410.443934)
				)
				(xy 5.348224 -410.468826) (xy 5.59054 -410.468826)
			)
		)
	)
	(zone
		(layer "In2.Cu")
		(hatch none 0.5)
		(connect_pads
			(clearance 0)
		)
		(min_thickness 0.25)
		(keepout
			(tracks not_allowed)
			(vias allowed)
			(pads allowed)
			(copperpour not_allowed)
			(footprints allowed)
		)
		(placement
			(enabled no)
			(sheetname "")
		)
		(fill
			(thermal_gap 0.5)
			(thermal_bridge_width 0.5)
			(island_removal_mode 0)
		)
		(polygon
			(pts
				(arc
					(start 5.59054 -302.735742)
					(mid 5.080127 -302.224948)
					(end 4.56946 -302.735488)
				)
				(arc
					(start 4.56946 -303.548288)
					(mid 5.08 -304.058828)
					(end 5.59054 -303.548288)
				)
				(xy 5.59054 -303.415192) (xy 5.347716 -303.415192)
				(arc
					(start 5.323586 -303.439576)
					(mid 4.891383 -303.736905)
					(end 5.188712 -303.304702)
				)
				(xy 5.268976 -303.224692) (xy 5.59054 -303.224692) (xy 5.59054 -303.059592) (xy 5.269484 -303.059592)
				(arc
					(start 5.188712 -302.979074)
					(mid 4.891383 -302.546871)
					(end 5.323586 -302.8442)
				)
				(xy 5.348224 -302.869092) (xy 5.59054 -302.869092)
			)
		)
	)
	(zone
		(layer "In2.Cu")
		(hatch none 0.5)
		(connect_pads
			(clearance 0)
		)
		(min_thickness 0.25)
		(keepout
			(tracks not_allowed)
			(vias allowed)
			(pads allowed)
			(copperpour not_allowed)
			(footprints allowed)
		)
		(placement
			(enabled no)
			(sheetname "")
		)
		(fill
			(thermal_gap 0.5)
			(thermal_bridge_width 0.5)
			(island_removal_mode 0)
		)
		(polygon
			(pts
				(arc
					(start 222.339154 -468.831676)
					(mid 221.727141 -468.219282)
					(end 221.114874 -468.831422)
				)
				(xy 221.114874 -469.117172) (xy 221.306644 -469.117172)
				(arc
					(start 221.483428 -468.940134)
					(mid 221.915631 -468.642805)
					(end 221.618302 -469.075008)
				)
				(xy 221.385384 -469.307672) (xy 221.114874 -469.307672) (xy 221.114874 -469.472772) (xy 221.385384 -469.472772)
				(arc
					(start 221.618302 -469.705436)
					(mid 221.915631 -470.137639)
					(end 221.483428 -469.84031)
				)
				(xy 221.306644 -469.663272) (xy 221.114874 -469.663272)
				(arc
					(start 221.114874 -469.949022)
					(mid 221.727014 -470.561162)
					(end 222.339154 -469.949022)
				)
			)
		)
	)
	(zone
		(net "GND")
		(layer "In2.Cu")
		(hatch none 0.5)
		(connect_pads
			(clearance 0.5)
		)
		(min_thickness 0.25)
		(fill yes
			(thermal_gap 0.5)
			(thermal_bridge_width 0.5)
			(island_removal_mode 0)
		)
		(polygon
			(pts
				(xy 236.584998 -384.6576) (xy 248.92 -384.6576) (xy 256.666492 -384.6576) (xy 256.833624 -384.824732)
				(xy 256.833624 -405.694642) (xy 256.572766 -405.9555) (xy 251.12726 -405.9555) (xy 249.034554 -408.048206)
				(xy 236.787436 -408.048206) (xy 236.286548 -407.547318) (xy 236.286548 -384.95605)
			)
		)
	)
	(zone
		(layer "In2.Cu")
		(hatch none 0.5)
		(connect_pads
			(clearance 0)
		)
		(min_thickness 0.25)
		(keepout
			(tracks not_allowed)
			(vias allowed)
			(pads allowed)
			(copperpour not_allowed)
			(footprints allowed)
		)
		(placement
			(enabled no)
			(sheetname "")
		)
		(fill
			(thermal_gap 0.5)
			(thermal_bridge_width 0.5)
			(island_removal_mode 0)
		)
		(polygon
			(pts
				(arc
					(start 5.59054 -326.735694)
					(mid 5.080127 -326.2249)
					(end 4.56946 -326.73544)
				)
				(arc
					(start 4.56946 -327.54824)
					(mid 5.08 -328.05878)
					(end 5.59054 -327.54824)
				)
				(xy 5.59054 -327.415144) (xy 5.347716 -327.415144)
				(arc
					(start 5.323586 -327.439528)
					(mid 4.891383 -327.736857)
					(end 5.188712 -327.304654)
				)
				(xy 5.268976 -327.224644) (xy 5.59054 -327.224644) (xy 5.59054 -327.059544) (xy 5.269484 -327.059544)
				(arc
					(start 5.188712 -326.979026)
					(mid 4.891383 -326.546823)
					(end 5.323586 -326.844152)
				)
				(xy 5.348224 -326.869044) (xy 5.59054 -326.869044)
			)
		)
	)
	(zone
		(layer "In2.Cu")
		(hatch none 0.5)
		(connect_pads
			(clearance 0)
		)
		(min_thickness 0.25)
		(keepout
			(tracks not_allowed)
			(vias allowed)
			(pads allowed)
			(copperpour not_allowed)
			(footprints allowed)
		)
		(placement
			(enabled no)
			(sheetname "")
		)
		(fill
			(thermal_gap 0.5)
			(thermal_bridge_width 0.5)
			(island_removal_mode 0)
		)
		(polygon
			(pts
				(arc
					(start 5.59054 -191.135762)
					(mid 5.080127 -190.624968)
					(end 4.56946 -191.135508)
				)
				(arc
					(start 4.56946 -191.948308)
					(mid 5.08 -192.458848)
					(end 5.59054 -191.948308)
				)
				(xy 5.59054 -191.815212) (xy 5.347716 -191.815212)
				(arc
					(start 5.323586 -191.839596)
					(mid 4.891383 -192.136925)
					(end 5.188712 -191.704722)
				)
				(xy 5.268976 -191.624712) (xy 5.59054 -191.624712) (xy 5.59054 -191.459612) (xy 5.269484 -191.459612)
				(arc
					(start 5.188712 -191.379094)
					(mid 4.891383 -190.946891)
					(end 5.323586 -191.24422)
				)
				(xy 5.348224 -191.269112) (xy 5.59054 -191.269112)
			)
		)
	)
	(zone
		(layer "In2.Cu")
		(hatch none 0.5)
		(connect_pads
			(clearance 0)
		)
		(min_thickness 0.25)
		(keepout
			(tracks not_allowed)
			(vias allowed)
			(pads allowed)
			(copperpour not_allowed)
			(footprints allowed)
		)
		(placement
			(enabled no)
			(sheetname "")
		)
		(fill
			(thermal_gap 0.5)
			(thermal_bridge_width 0.5)
			(island_removal_mode 0)
		)
		(polygon
			(pts
				(arc
					(start 5.59054 -351.535746)
					(mid 5.080127 -351.024952)
					(end 4.56946 -351.535492)
				)
				(arc
					(start 4.56946 -352.348292)
					(mid 5.08 -352.858832)
					(end 5.59054 -352.348292)
				)
				(xy 5.59054 -352.215196) (xy 5.347716 -352.215196)
				(arc
					(start 5.323586 -352.23958)
					(mid 4.891383 -352.536909)
					(end 5.188712 -352.104706)
				)
				(xy 5.268976 -352.024696) (xy 5.59054 -352.024696) (xy 5.59054 -351.859596) (xy 5.269484 -351.859596)
				(arc
					(start 5.188712 -351.779078)
					(mid 4.891383 -351.346875)
					(end 5.323586 -351.644204)
				)
				(xy 5.348224 -351.669096) (xy 5.59054 -351.669096)
			)
		)
	)
	(zone
		(net "VDD_IO_1")
		(layer "In2.Cu")
		(hatch none 0.5)
		(connect_pads
			(clearance 0.5)
		)
		(min_thickness 0.25)
		(fill yes
			(thermal_gap 0.5)
			(thermal_bridge_width 0.5)
			(island_removal_mode 0)
		)
		(polygon
			(pts
				(xy 93.599 -439.674) (xy 97.536 -439.674) (xy 99.949 -437.261) (xy 99.949 -424.942) (xy 99.06 -424.053)
				(xy 93.345 -424.053) (xy 92.71 -424.688) (xy 92.71 -438.785)
			)
		)
	)
	(zone
		(layer "In2.Cu")
		(hatch none 0.5)
		(connect_pads
			(clearance 0)
		)
		(min_thickness 0.25)
		(keepout
			(tracks not_allowed)
			(vias allowed)
			(pads allowed)
			(copperpour not_allowed)
			(footprints allowed)
		)
		(placement
			(enabled no)
			(sheetname "")
		)
		(fill
			(thermal_gap 0.5)
			(thermal_bridge_width 0.5)
			(island_removal_mode 0)
		)
		(polygon
			(pts
				(arc
					(start 5.59054 -296.335704)
					(mid 5.080127 -295.82491)
					(end 4.56946 -296.33545)
				)
				(arc
					(start 4.56946 -297.14825)
					(mid 5.08 -297.65879)
					(end 5.59054 -297.14825)
				)
				(xy 5.59054 -297.015154) (xy 5.347716 -297.015154)
				(arc
					(start 5.323586 -297.039538)
					(mid 4.891383 -297.336867)
					(end 5.188712 -296.904664)
				)
				(xy 5.268976 -296.824654) (xy 5.59054 -296.824654) (xy 5.59054 -296.659554) (xy 5.269484 -296.659554)
				(arc
					(start 5.188712 -296.579036)
					(mid 4.891383 -296.146833)
					(end 5.323586 -296.444162)
				)
				(xy 5.348224 -296.469054) (xy 5.59054 -296.469054)
			)
		)
	)
	(zone
		(layer "In2.Cu")
		(hatch none 0.5)
		(connect_pads
			(clearance 0)
		)
		(min_thickness 0.25)
		(keepout
			(tracks not_allowed)
			(vias allowed)
			(pads allowed)
			(copperpour not_allowed)
			(footprints allowed)
		)
		(placement
			(enabled no)
			(sheetname "")
		)
		(fill
			(thermal_gap 0.5)
			(thermal_bridge_width 0.5)
			(island_removal_mode 0)
		)
		(polygon
			(pts
				(arc
					(start 37.33927 -177.431446)
					(mid 36.727257 -176.819052)
					(end 36.11499 -177.431192)
				)
				(xy 36.11499 -177.717196) (xy 36.306506 -177.717196)
				(arc
					(start 36.483544 -177.539904)
					(mid 36.915747 -177.242575)
					(end 36.618418 -177.674778)
				)
				(xy 36.385246 -177.907696) (xy 36.11499 -177.907696) (xy 36.11499 -178.072796) (xy 36.385754 -178.072796)
				(arc
					(start 36.618418 -178.305206)
					(mid 36.915747 -178.737409)
					(end 36.483544 -178.44008)
				)
				(xy 36.307014 -178.263296) (xy 36.11499 -178.263296)
				(arc
					(start 36.11499 -178.548792)
					(mid 36.72713 -179.160932)
					(end 37.33927 -178.548792)
				)
			)
		)
	)
	(zone
		(layer "In2.Cu")
		(hatch none 0.5)
		(connect_pads
			(clearance 0)
		)
		(min_thickness 0.25)
		(keepout
			(tracks not_allowed)
			(vias allowed)
			(pads allowed)
			(copperpour not_allowed)
			(footprints allowed)
		)
		(placement
			(enabled no)
			(sheetname "")
		)
		(fill
			(thermal_gap 0.5)
			(thermal_bridge_width 0.5)
			(island_removal_mode 0)
		)
		(polygon
			(pts
				(arc
					(start 5.59054 -441.535312)
					(mid 5.08 -441.024772)
					(end 4.56946 -441.535312)
				)
				(arc
					(start 4.56946 -442.347858)
					(mid 5.079873 -442.858652)
					(end 5.59054 -442.348112)
				)
				(xy 5.59054 -442.215016) (xy 5.347716 -442.215016)
				(arc
					(start 5.323586 -442.2394)
					(mid 4.891383 -442.536729)
					(end 5.188712 -442.104526)
				)
				(xy 5.268976 -442.024516) (xy 5.59054 -442.024516) (xy 5.59054 -441.859416) (xy 5.269484 -441.859416)
				(arc
					(start 5.188712 -441.778898)
					(mid 4.891383 -441.346695)
					(end 5.323586 -441.644024)
				)
				(xy 5.348224 -441.668916) (xy 5.59054 -441.668916)
			)
		)
	)
	(zone
		(net "VDD_IO_3")
		(layer "In2.Cu")
		(hatch none 0.5)
		(connect_pads
			(clearance 0.5)
		)
		(min_thickness 0.25)
		(fill yes
			(thermal_gap 0.5)
			(thermal_bridge_width 0.5)
			(island_removal_mode 0)
		)
		(polygon
			(pts
				(xy 93.599 -218.694) (xy 99.06 -218.694) (xy 101.6 -216.154) (xy 101.6 -204.089) (xy 100.584 -203.073)
				(xy 93.345 -203.073) (xy 92.71 -203.708) (xy 92.71 -217.805)
			)
		)
	)
	(zone
		(layer "In2.Cu")
		(hatch none 0.5)
		(connect_pads
			(clearance 0)
		)
		(min_thickness 0.25)
		(keepout
			(tracks not_allowed)
			(vias allowed)
			(pads allowed)
			(copperpour not_allowed)
			(footprints allowed)
		)
		(placement
			(enabled no)
			(sheetname "")
		)
		(fill
			(thermal_gap 0.5)
			(thermal_bridge_width 0.5)
			(island_removal_mode 0)
		)
		(polygon
			(pts
				(arc
					(start 5.59054 -407.135076)
					(mid 5.08 -406.624536)
					(end 4.56946 -407.135076)
				)
				(arc
					(start 4.56946 -407.947622)
					(mid 5.079873 -408.458416)
					(end 5.59054 -407.947876)
				)
				(xy 5.59054 -407.815034) (xy 5.347462 -407.815034)
				(arc
					(start 5.323586 -407.839164)
					(mid 4.891383 -408.136493)
					(end 5.188712 -407.70429)
				)
				(xy 5.268722 -407.624534) (xy 5.59054 -407.624534) (xy 5.59054 -407.459434) (xy 5.269738 -407.459434)
				(arc
					(start 5.188712 -407.378662)
					(mid 4.891383 -406.946459)
					(end 5.323586 -407.243788)
				)
				(xy 5.348478 -407.268934) (xy 5.59054 -407.268934)
			)
		)
	)
	(zone
		(net "P3V3")
		(layer "In2.Cu")
		(hatch none 0.5)
		(connect_pads
			(clearance 0.5)
		)
		(min_thickness 0.25)
		(fill yes
			(thermal_gap 0.5)
			(thermal_bridge_width 0.5)
			(island_removal_mode 0)
		)
		(polygon
			(pts
				(xy 46.736 -351.0788) (xy 46.736 -360.934) (xy 39.243 -368.427) (xy 26.289 -368.427) (xy 23.241 -365.379)
				(xy 21.687282 -365.379) (xy 19.177 -367.889282) (xy 19.177 -374.015) (xy 20.131532 -374.969532)
				(xy 24.322532 -374.969532) (xy 55.941468 -374.969532) (xy 61.341 -369.57) (xy 81.534 -369.57) (xy 84.582 -366.522)
				(xy 84.582 -347.345) (xy 81.915 -344.678) (xy 47.244 -344.678) (xy 45.72 -344.678) (xy 43.107864 -342.065864)
				(xy 37.029136 -342.065864) (xy 34.6964 -344.3986) (xy 34.6964 -349.0722) (xy 34.6964 -351.1296)
				(xy 26.5176 -359.3084) (xy 25.6794 -359.3084) (xy 24.2316 -360.7562) (xy 24.2316 -363.22) (xy 24.9174 -363.9058)
				(xy 27.9908 -363.9058) (xy 39.4462 -352.4504) (xy 42.0878 -349.8088) (xy 45.466 -349.8088)
			)
		)
	)
	(zone
		(layer "In2.Cu")
		(hatch none 0.5)
		(connect_pads
			(clearance 0)
		)
		(min_thickness 0.25)
		(keepout
			(tracks not_allowed)
			(vias allowed)
			(pads allowed)
			(copperpour not_allowed)
			(footprints allowed)
		)
		(placement
			(enabled no)
			(sheetname "")
		)
		(fill
			(thermal_gap 0.5)
			(thermal_bridge_width 0.5)
			(island_removal_mode 0)
		)
		(polygon
			(pts
				(arc
					(start 222.339154 -491.231682)
					(mid 221.727141 -490.619288)
					(end 221.114874 -491.231428)
				)
				(xy 221.114874 -491.517178) (xy 221.306644 -491.517178)
				(arc
					(start 221.483428 -491.34014)
					(mid 221.915631 -491.042811)
					(end 221.618302 -491.475014)
				)
				(xy 221.385384 -491.707678) (xy 221.114874 -491.707678) (xy 221.114874 -491.872778) (xy 221.385384 -491.872778)
				(arc
					(start 221.618302 -492.105442)
					(mid 221.915631 -492.537645)
					(end 221.483428 -492.240316)
				)
				(xy 221.306644 -492.063278) (xy 221.114874 -492.063278)
				(arc
					(start 221.114874 -492.349028)
					(mid 221.727014 -492.961168)
					(end 222.339154 -492.349028)
				)
			)
		)
	)
	(zone
		(layer "In2.Cu")
		(hatch none 0.5)
		(connect_pads
			(clearance 0)
		)
		(min_thickness 0.25)
		(keepout
			(tracks not_allowed)
			(vias allowed)
			(pads allowed)
			(copperpour not_allowed)
			(footprints allowed)
		)
		(placement
			(enabled no)
			(sheetname "")
		)
		(fill
			(thermal_gap 0.5)
			(thermal_bridge_width 0.5)
			(island_removal_mode 0)
		)
		(polygon
			(pts
				(arc
					(start 222.339154 -74.431398)
					(mid 221.727141 -73.819004)
					(end 221.114874 -74.431144)
				)
				(xy 221.114874 -74.717148) (xy 221.30639 -74.717148)
				(arc
					(start 221.483428 -74.539856)
					(mid 221.915631 -74.242527)
					(end 221.618302 -74.67473)
				)
				(xy 221.38513 -74.907648) (xy 221.114874 -74.907648) (xy 221.114874 -75.072748) (xy 221.385638 -75.072748)
				(arc
					(start 221.618302 -75.305158)
					(mid 221.915631 -75.737361)
					(end 221.483428 -75.440032)
				)
				(xy 221.306898 -75.263248) (xy 221.114874 -75.263248)
				(arc
					(start 221.114874 -75.548744)
					(mid 221.727014 -76.160884)
					(end 222.339154 -75.548744)
				)
			)
		)
	)
	(zone
		(layer "In2.Cu")
		(hatch none 0.5)
		(connect_pads
			(clearance 0)
		)
		(min_thickness 0.25)
		(keepout
			(tracks not_allowed)
			(vias allowed)
			(pads allowed)
			(copperpour not_allowed)
			(footprints allowed)
		)
		(placement
			(enabled no)
			(sheetname "")
		)
		(fill
			(thermal_gap 0.5)
			(thermal_bridge_width 0.5)
			(island_removal_mode 0)
		)
		(polygon
			(pts
				(arc
					(start 25.88514 -425.651422)
					(mid 25.273127 -425.039028)
					(end 24.66086 -425.651168)
				)
				(arc
					(start 24.66086 -426.768768)
					(mid 25.273 -427.380908)
					(end 25.88514 -426.768768)
				)
				(xy 25.88514 -426.568616) (xy 25.607772 -426.568616)
				(arc
					(start 25.516586 -426.660056)
					(mid 25.084383 -426.957385)
					(end 25.381712 -426.525182)
				)
				(xy 25.529032 -426.378116) (xy 25.88514 -426.378116) (xy 25.88514 -426.213016) (xy 25.700228 -426.213016)
				(arc
					(start 25.381712 -425.894754)
					(mid 25.084383 -425.462551)
					(end 25.516586 -425.75988)
				)
				(xy 25.778968 -426.022516) (xy 25.88514 -426.022516)
			)
		)
	)
	(zone
		(layer "In2.Cu")
		(hatch none 0.5)
		(connect_pads
			(clearance 0)
		)
		(min_thickness 0.25)
		(keepout
			(tracks not_allowed)
			(vias allowed)
			(pads allowed)
			(copperpour not_allowed)
			(footprints allowed)
		)
		(placement
			(enabled no)
			(sheetname "")
		)
		(fill
			(thermal_gap 0.5)
			(thermal_bridge_width 0.5)
			(island_removal_mode 0)
		)
		(polygon
			(pts
				(arc
					(start 5.59054 -329.935586)
					(mid 5.080127 -329.424792)
					(end 4.56946 -329.935332)
				)
				(arc
					(start 4.56946 -330.748132)
					(mid 5.08 -331.258672)
					(end 5.59054 -330.748132)
				)
				(xy 5.59054 -330.61529) (xy 5.347462 -330.61529)
				(arc
					(start 5.323586 -330.63942)
					(mid 4.891383 -330.936749)
					(end 5.188712 -330.504546)
				)
				(xy 5.268722 -330.42479) (xy 5.59054 -330.42479) (xy 5.59054 -330.25969) (xy 5.269738 -330.25969)
				(arc
					(start 5.188712 -330.178918)
					(mid 4.891383 -329.746715)
					(end 5.323586 -330.044044)
				)
				(xy 5.348478 -330.06919) (xy 5.59054 -330.06919)
			)
		)
	)
	(zone
		(layer "In2.Cu")
		(hatch none 0.5)
		(connect_pads
			(clearance 0)
		)
		(min_thickness 0.25)
		(keepout
			(tracks not_allowed)
			(vias allowed)
			(pads allowed)
			(copperpour not_allowed)
			(footprints allowed)
		)
		(placement
			(enabled no)
			(sheetname "")
		)
		(fill
			(thermal_gap 0.5)
			(thermal_bridge_width 0.5)
			(island_removal_mode 0)
		)
		(polygon
			(pts
				(arc
					(start 222.339154 -481.631498)
					(mid 221.727141 -481.019104)
					(end 221.114874 -481.631244)
				)
				(xy 221.114874 -481.917248) (xy 221.30639 -481.917248)
				(arc
					(start 221.483428 -481.739956)
					(mid 221.915631 -481.442627)
					(end 221.618302 -481.87483)
				)
				(xy 221.38513 -482.107748) (xy 221.114874 -482.107748) (xy 221.114874 -482.272848) (xy 221.385638 -482.272848)
				(arc
					(start 221.618302 -482.505258)
					(mid 221.915631 -482.937461)
					(end 221.483428 -482.640132)
				)
				(xy 221.306898 -482.463348) (xy 221.114874 -482.463348)
				(arc
					(start 221.114874 -482.748844)
					(mid 221.727014 -483.360984)
					(end 222.339154 -482.748844)
				)
			)
		)
	)
	(zone
		(net "P12V")
		(layer "In2.Cu")
		(hatch none 0.5)
		(connect_pads
			(clearance 0.5)
		)
		(min_thickness 0.25)
		(fill yes
			(thermal_gap 0.5)
			(thermal_bridge_width 0.5)
			(island_removal_mode 0)
		)
		(polygon
			(pts
				(xy 256.818892 -362.356146) (xy 255.930146 -361.4674) (xy 253.7206 -361.4674) (xy 253.5682 -361.315)
				(xy 237.363 -361.315) (xy 236.728 -361.95) (xy 236.728 -383.413) (xy 236.9058 -383.5908) (xy 256.678176 -383.5908)
				(xy 256.818892 -383.450084)
			)
		)
	)
	(zone
		(layer "In2.Cu")
		(hatch none 0.5)
		(connect_pads
			(clearance 0)
		)
		(min_thickness 0.25)
		(keepout
			(tracks not_allowed)
			(vias allowed)
			(pads allowed)
			(copperpour not_allowed)
			(footprints allowed)
		)
		(placement
			(enabled no)
			(sheetname "")
		)
		(fill
			(thermal_gap 0.5)
			(thermal_bridge_width 0.5)
			(island_removal_mode 0)
		)
		(polygon
			(pts
				(arc
					(start 37.33927 -481.631244)
					(mid 36.72713 -481.019104)
					(end 36.11499 -481.631244)
				)
				(xy 36.11499 -481.917248) (xy 36.306506 -481.917248)
				(arc
					(start 36.483544 -481.739956)
					(mid 36.915747 -481.442627)
					(end 36.618418 -481.87483)
				)
				(xy 36.385246 -482.107748) (xy 36.11499 -482.107748) (xy 36.11499 -482.272848) (xy 36.385754 -482.272848)
				(arc
					(start 36.618418 -482.505258)
					(mid 36.915747 -482.937461)
					(end 36.483544 -482.640132)
				)
				(xy 36.307014 -482.463348) (xy 36.11499 -482.463348)
				(arc
					(start 36.11499 -482.74859)
					(mid 36.727003 -483.360984)
					(end 37.33927 -482.748844)
				)
			)
		)
	)
	(zone
		(layer "In2.Cu")
		(hatch none 0.5)
		(connect_pads
			(clearance 0)
		)
		(min_thickness 0.25)
		(keepout
			(tracks not_allowed)
			(vias allowed)
			(pads allowed)
			(copperpour not_allowed)
			(footprints allowed)
		)
		(placement
			(enabled no)
			(sheetname "")
		)
		(fill
			(thermal_gap 0.5)
			(thermal_bridge_width 0.5)
			(island_removal_mode 0)
		)
		(polygon
			(pts
				(arc
					(start 222.339154 -69.631306)
					(mid 221.727141 -69.018912)
					(end 221.114874 -69.631052)
				)
				(xy 221.114874 -69.917056) (xy 221.30639 -69.917056)
				(arc
					(start 221.483428 -69.739764)
					(mid 221.915631 -69.442435)
					(end 221.618302 -69.874638)
				)
				(xy 221.38513 -70.107556) (xy 221.114874 -70.107556) (xy 221.114874 -70.272656) (xy 221.385638 -70.272656)
				(arc
					(start 221.618302 -70.505066)
					(mid 221.915631 -70.937269)
					(end 221.483428 -70.63994)
				)
				(xy 221.306898 -70.463156) (xy 221.114874 -70.463156)
				(arc
					(start 221.114874 -70.748652)
					(mid 221.727014 -71.360792)
					(end 222.339154 -70.748652)
				)
			)
		)
	)
	(zone
		(layer "In2.Cu")
		(hatch none 0.5)
		(connect_pads
			(clearance 0)
		)
		(min_thickness 0.25)
		(keepout
			(tracks not_allowed)
			(vias allowed)
			(pads allowed)
			(copperpour not_allowed)
			(footprints allowed)
		)
		(placement
			(enabled no)
			(sheetname "")
		)
		(fill
			(thermal_gap 0.5)
			(thermal_bridge_width 0.5)
			(island_removal_mode 0)
		)
		(polygon
			(pts
				(arc
					(start 37.33927 -262.83158)
					(mid 36.727257 -262.219186)
					(end 36.11499 -262.831326)
				)
				(xy 36.11499 -263.117076) (xy 36.30676 -263.117076)
				(arc
					(start 36.483544 -262.940038)
					(mid 36.915747 -262.642709)
					(end 36.618418 -263.074912)
				)
				(xy 36.3855 -263.307576) (xy 36.11499 -263.307576) (xy 36.11499 -263.472676) (xy 36.3855 -263.472676)
				(arc
					(start 36.618418 -263.70534)
					(mid 36.915747 -264.137543)
					(end 36.483544 -263.840214)
				)
				(xy 36.30676 -263.663176) (xy 36.11499 -263.663176)
				(arc
					(start 36.11499 -263.948926)
					(mid 36.72713 -264.561066)
					(end 37.33927 -263.948926)
				)
			)
		)
	)
	(zone
		(layer "In2.Cu")
		(hatch none 0.5)
		(connect_pads
			(clearance 0)
		)
		(min_thickness 0.25)
		(keepout
			(tracks not_allowed)
			(vias allowed)
			(pads allowed)
			(copperpour not_allowed)
			(footprints allowed)
		)
		(placement
			(enabled no)
			(sheetname "")
		)
		(fill
			(thermal_gap 0.5)
			(thermal_bridge_width 0.5)
			(island_removal_mode 0)
		)
		(polygon
			(pts
				(arc
					(start 25.88514 -322.65112)
					(mid 25.273 -322.03898)
					(end 24.66086 -322.65112)
				)
				(arc
					(start 24.66086 -323.768466)
					(mid 25.272873 -324.38086)
					(end 25.88514 -323.76872)
				)
				(xy 25.88514 -323.460364) (xy 25.715976 -323.460364)
				(arc
					(start 25.516586 -323.660008)
					(mid 25.084383 -323.957337)
					(end 25.381712 -323.525134)
				)
				(xy 25.637236 -323.269864) (xy 25.88514 -323.269864) (xy 25.88514 -323.104764) (xy 25.592024 -323.104764)
				(arc
					(start 25.381712 -322.894706)
					(mid 25.084383 -322.462503)
					(end 25.516586 -322.759832)
				)
				(xy 25.670764 -322.914264) (xy 25.88514 -322.914264)
			)
		)
	)
	(zone
		(layer "In2.Cu")
		(hatch none 0.5)
		(connect_pads
			(clearance 0)
		)
		(min_thickness 0.25)
		(keepout
			(tracks not_allowed)
			(vias allowed)
			(pads allowed)
			(copperpour not_allowed)
			(footprints allowed)
		)
		(placement
			(enabled no)
			(sheetname "")
		)
		(fill
			(thermal_gap 0.5)
			(thermal_bridge_width 0.5)
			(island_removal_mode 0)
		)
		(polygon
			(pts
				(arc
					(start 5.59054 -388.73557)
					(mid 5.080127 -388.224776)
					(end 4.56946 -388.735316)
				)
				(arc
					(start 4.56946 -389.548116)
					(mid 5.08 -390.058656)
					(end 5.59054 -389.548116)
				)
				(xy 5.59054 -389.41502) (xy 5.347716 -389.41502)
				(arc
					(start 5.323586 -389.439404)
					(mid 4.891383 -389.736733)
					(end 5.188712 -389.30453)
				)
				(xy 5.268976 -389.22452) (xy 5.59054 -389.22452) (xy 5.59054 -389.05942) (xy 5.269484 -389.05942)
				(arc
					(start 5.188712 -388.978902)
					(mid 4.891383 -388.546699)
					(end 5.323586 -388.844028)
				)
				(xy 5.348224 -388.86892) (xy 5.59054 -388.86892)
			)
		)
	)
	(zone
		(layer "In2.Cu")
		(hatch none 0.5)
		(connect_pads
			(clearance 0)
		)
		(min_thickness 0.25)
		(keepout
			(tracks not_allowed)
			(vias allowed)
			(pads allowed)
			(copperpour not_allowed)
			(footprints allowed)
		)
		(placement
			(enabled no)
			(sheetname "")
		)
		(fill
			(thermal_gap 0.5)
			(thermal_bridge_width 0.5)
			(island_removal_mode 0)
		)
		(polygon
			(pts
				(arc
					(start 5.59054 -194.335654)
					(mid 5.080127 -193.82486)
					(end 4.56946 -194.3354)
				)
				(arc
					(start 4.56946 -195.1482)
					(mid 5.08 -195.65874)
					(end 5.59054 -195.1482)
				)
				(xy 5.59054 -195.015104) (xy 5.347716 -195.015104)
				(arc
					(start 5.323586 -195.039488)
					(mid 4.891383 -195.336817)
					(end 5.188712 -194.904614)
				)
				(xy 5.268976 -194.824604) (xy 5.59054 -194.824604) (xy 5.59054 -194.659504) (xy 5.269484 -194.659504)
				(arc
					(start 5.188712 -194.578986)
					(mid 4.891383 -194.146783)
					(end 5.323586 -194.444112)
				)
				(xy 5.348224 -194.469004) (xy 5.59054 -194.469004)
			)
		)
	)
	(zone
		(layer "In2.Cu")
		(hatch none 0.5)
		(connect_pads
			(clearance 0)
		)
		(min_thickness 0.25)
		(keepout
			(tracks not_allowed)
			(vias allowed)
			(pads allowed)
			(copperpour not_allowed)
			(footprints allowed)
		)
		(placement
			(enabled no)
			(sheetname "")
		)
		(fill
			(thermal_gap 0.5)
			(thermal_bridge_width 0.5)
			(island_removal_mode 0)
		)
		(polygon
			(pts
				(arc
					(start 222.339154 -56.831484)
					(mid 221.727141 -56.21909)
					(end 221.114874 -56.83123)
				)
				(xy 221.114874 -57.11698) (xy 221.306644 -57.11698)
				(arc
					(start 221.483428 -56.939942)
					(mid 221.915631 -56.642613)
					(end 221.618302 -57.074816)
				)
				(xy 221.385384 -57.30748) (xy 221.114874 -57.30748) (xy 221.114874 -57.47258) (xy 221.385384 -57.47258)
				(arc
					(start 221.618302 -57.705244)
					(mid 221.915631 -58.137447)
					(end 221.483428 -57.840118)
				)
				(xy 221.306644 -57.66308) (xy 221.114874 -57.66308)
				(arc
					(start 221.114874 -57.94883)
					(mid 221.727014 -58.56097)
					(end 222.339154 -57.94883)
				)
			)
		)
	)
	(zone
		(layer "In2.Cu")
		(hatch none 0.5)
		(connect_pads
			(clearance 0)
		)
		(min_thickness 0.25)
		(keepout
			(tracks not_allowed)
			(vias allowed)
			(pads allowed)
			(copperpour not_allowed)
			(footprints allowed)
		)
		(placement
			(enabled no)
			(sheetname "")
		)
		(fill
			(thermal_gap 0.5)
			(thermal_bridge_width 0.5)
			(island_removal_mode 0)
		)
		(polygon
			(pts
				(arc
					(start 25.88514 -229.251256)
					(mid 25.273 -228.639116)
					(end 24.66086 -229.251256)
				)
				(arc
					(start 24.66086 -230.368602)
					(mid 25.272873 -230.980996)
					(end 25.88514 -230.368856)
				)
				(xy 25.88514 -230.082852) (xy 25.693624 -230.082852)
				(arc
					(start 25.516586 -230.260144)
					(mid 25.084383 -230.557473)
					(end 25.381712 -230.12527)
				)
				(xy 25.614884 -229.892352) (xy 25.88514 -229.892352) (xy 25.88514 -229.727252) (xy 25.614376 -229.727252)
				(arc
					(start 25.381712 -229.494842)
					(mid 25.084383 -229.062639)
					(end 25.516586 -229.359968)
				)
				(xy 25.693116 -229.536752) (xy 25.88514 -229.536752)
			)
		)
	)
	(zone
		(layer "In2.Cu")
		(hatch none 0.5)
		(connect_pads
			(clearance 0)
		)
		(min_thickness 0.25)
		(keepout
			(tracks not_allowed)
			(vias allowed)
			(pads allowed)
			(copperpour not_allowed)
			(footprints allowed)
		)
		(placement
			(enabled no)
			(sheetname "")
		)
		(fill
			(thermal_gap 0.5)
			(thermal_bridge_width 0.5)
			(island_removal_mode 0)
		)
		(polygon
			(pts
				(arc
					(start 37.33927 -74.431398)
					(mid 36.727257 -73.819004)
					(end 36.11499 -74.431144)
				)
				(xy 36.11499 -74.717148) (xy 36.306506 -74.717148)
				(arc
					(start 36.483544 -74.539856)
					(mid 36.915747 -74.242527)
					(end 36.618418 -74.67473)
				)
				(xy 36.385246 -74.907648) (xy 36.11499 -74.907648) (xy 36.11499 -75.072748) (xy 36.385754 -75.072748)
				(arc
					(start 36.618418 -75.305158)
					(mid 36.915747 -75.737361)
					(end 36.483544 -75.440032)
				)
				(xy 36.307014 -75.263248) (xy 36.11499 -75.263248)
				(arc
					(start 36.11499 -75.548744)
					(mid 36.72713 -76.160884)
					(end 37.33927 -75.548744)
				)
			)
		)
	)
	(zone
		(layer "In2.Cu")
		(hatch none 0.5)
		(connect_pads
			(clearance 0)
		)
		(min_thickness 0.25)
		(keepout
			(tracks not_allowed)
			(vias allowed)
			(pads allowed)
			(copperpour not_allowed)
			(footprints allowed)
		)
		(placement
			(enabled no)
			(sheetname "")
		)
		(fill
			(thermal_gap 0.5)
			(thermal_bridge_width 0.5)
			(island_removal_mode 0)
		)
		(polygon
			(pts
				(arc
					(start 25.88514 -139.051284)
					(mid 25.273127 -138.43889)
					(end 24.66086 -139.05103)
				)
				(arc
					(start 24.66086 -140.16863)
					(mid 25.273 -140.78077)
					(end 25.88514 -140.16863)
				)
				(xy 25.88514 -139.84605) (xy 25.7302 -139.84605)
				(arc
					(start 25.516586 -140.059918)
					(mid 25.084383 -140.357247)
					(end 25.381712 -139.925044)
				)
				(xy 25.65146 -139.65555) (xy 25.88514 -139.65555) (xy 25.88514 -139.49045) (xy 25.5778 -139.49045)
				(arc
					(start 25.381712 -139.294616)
					(mid 25.084383 -138.862413)
					(end 25.516586 -139.159742)
				)
				(xy 25.65654 -139.29995) (xy 25.88514 -139.29995)
			)
		)
	)
	(zone
		(layer "In2.Cu")
		(hatch none 0.5)
		(connect_pads
			(clearance 0)
		)
		(min_thickness 0.25)
		(keepout
			(tracks not_allowed)
			(vias allowed)
			(pads allowed)
			(copperpour not_allowed)
			(footprints allowed)
		)
		(placement
			(enabled no)
			(sheetname "")
		)
		(fill
			(thermal_gap 0.5)
			(thermal_bridge_width 0.5)
			(island_removal_mode 0)
		)
		(polygon
			(pts
				(arc
					(start 222.339154 -378.63145)
					(mid 221.727141 -378.019056)
					(end 221.114874 -378.631196)
				)
				(xy 221.114874 -378.9172) (xy 221.30639 -378.9172)
				(arc
					(start 221.483428 -378.739908)
					(mid 221.915631 -378.442579)
					(end 221.618302 -378.874782)
				)
				(xy 221.38513 -379.1077) (xy 221.114874 -379.1077) (xy 221.114874 -379.2728) (xy 221.385638 -379.2728)
				(arc
					(start 221.618302 -379.50521)
					(mid 221.915631 -379.937413)
					(end 221.483428 -379.640084)
				)
				(xy 221.306898 -379.4633) (xy 221.114874 -379.4633)
				(arc
					(start 221.114874 -379.748796)
					(mid 221.727014 -380.360936)
					(end 222.339154 -379.748796)
				)
			)
		)
	)
	(zone
		(layer "In2.Cu")
		(hatch none 0.5)
		(connect_pads
			(clearance 0)
		)
		(min_thickness 0.25)
		(keepout
			(tracks not_allowed)
			(vias allowed)
			(pads allowed)
			(copperpour not_allowed)
			(footprints allowed)
		)
		(placement
			(enabled no)
			(sheetname "")
		)
		(fill
			(thermal_gap 0.5)
			(thermal_bridge_width 0.5)
			(island_removal_mode 0)
		)
		(polygon
			(pts
				(arc
					(start 25.88514 -116.651278)
					(mid 25.273127 -116.038884)
					(end 24.66086 -116.651024)
				)
				(arc
					(start 24.66086 -117.768624)
					(mid 25.273 -118.380764)
					(end 25.88514 -117.768624)
				)
				(xy 25.88514 -117.482874) (xy 25.69337 -117.482874)
				(arc
					(start 25.516586 -117.659912)
					(mid 25.084383 -117.957241)
					(end 25.381712 -117.525038)
				)
				(xy 25.61463 -117.292374) (xy 25.88514 -117.292374) (xy 25.88514 -117.127274) (xy 25.61463 -117.127274)
				(arc
					(start 25.381712 -116.89461)
					(mid 25.084383 -116.462407)
					(end 25.516586 -116.759736)
				)
				(xy 25.69337 -116.936774) (xy 25.88514 -116.936774)
			)
		)
	)
	(zone
		(layer "In2.Cu")
		(hatch none 0.5)
		(connect_pads
			(clearance 0)
		)
		(min_thickness 0.25)
		(keepout
			(tracks not_allowed)
			(vias allowed)
			(pads allowed)
			(copperpour not_allowed)
			(footprints allowed)
		)
		(placement
			(enabled no)
			(sheetname "")
		)
		(fill
			(thermal_gap 0.5)
			(thermal_bridge_width 0.5)
			(island_removal_mode 0)
		)
		(polygon
			(pts
				(arc
					(start 37.33927 -275.631402)
					(mid 36.727257 -275.019008)
					(end 36.11499 -275.631148)
				)
				(xy 36.11499 -275.917152) (xy 36.306506 -275.917152)
				(arc
					(start 36.483544 -275.73986)
					(mid 36.915747 -275.442531)
					(end 36.618418 -275.874734)
				)
				(xy 36.385246 -276.107652) (xy 36.11499 -276.107652) (xy 36.11499 -276.272752) (xy 36.385754 -276.272752)
				(arc
					(start 36.618418 -276.505162)
					(mid 36.915747 -276.937365)
					(end 36.483544 -276.640036)
				)
				(xy 36.307014 -276.463252) (xy 36.11499 -276.463252)
				(arc
					(start 36.11499 -276.748748)
					(mid 36.72713 -277.360888)
					(end 37.33927 -276.748748)
				)
			)
		)
	)
	(zone
		(layer "In2.Cu")
		(hatch none 0.5)
		(connect_pads
			(clearance 0)
		)
		(min_thickness 0.25)
		(keepout
			(tracks not_allowed)
			(vias allowed)
			(pads allowed)
			(copperpour not_allowed)
			(footprints allowed)
		)
		(placement
			(enabled no)
			(sheetname "")
		)
		(fill
			(thermal_gap 0.5)
			(thermal_bridge_width 0.5)
			(island_removal_mode 0)
		)
		(polygon
			(pts
				(arc
					(start 5.59054 -305.935634)
					(mid 5.080127 -305.42484)
					(end 4.56946 -305.93538)
				)
				(arc
					(start 4.56946 -306.74818)
					(mid 5.08 -307.25872)
					(end 5.59054 -306.74818)
				)
				(xy 5.59054 -306.615084) (xy 5.347716 -306.615084)
				(arc
					(start 5.323586 -306.639468)
					(mid 4.891383 -306.936797)
					(end 5.188712 -306.504594)
				)
				(xy 5.268976 -306.424584) (xy 5.59054 -306.424584) (xy 5.59054 -306.259484) (xy 5.269484 -306.259484)
				(arc
					(start 5.188712 -306.178966)
					(mid 4.891383 -305.746763)
					(end 5.323586 -306.044092)
				)
				(xy 5.348224 -306.068984) (xy 5.59054 -306.068984)
			)
		)
	)
	(zone
		(layer "In2.Cu")
		(hatch none 0.5)
		(connect_pads
			(clearance 0)
		)
		(min_thickness 0.25)
		(keepout
			(tracks not_allowed)
			(vias allowed)
			(pads allowed)
			(copperpour not_allowed)
			(footprints allowed)
		)
		(placement
			(enabled no)
			(sheetname "")
		)
		(fill
			(thermal_gap 0.5)
			(thermal_bridge_width 0.5)
			(island_removal_mode 0)
		)
		(polygon
			(pts
				(arc
					(start 222.339154 -159.831532)
					(mid 221.727141 -159.219138)
					(end 221.114874 -159.831278)
				)
				(xy 221.114874 -160.117028) (xy 221.306644 -160.117028)
				(arc
					(start 221.483428 -159.93999)
					(mid 221.915631 -159.642661)
					(end 221.618302 -160.074864)
				)
				(xy 221.385384 -160.307528) (xy 221.114874 -160.307528) (xy 221.114874 -160.472628) (xy 221.385384 -160.472628)
				(arc
					(start 221.618302 -160.705292)
					(mid 221.915631 -161.137495)
					(end 221.483428 -160.840166)
				)
				(xy 221.306644 -160.663128) (xy 221.114874 -160.663128)
				(arc
					(start 221.114874 -160.948878)
					(mid 221.727014 -161.561018)
					(end 222.339154 -160.948878)
				)
			)
		)
	)
	(zone
		(layer "In2.Cu")
		(hatch none 0.5)
		(connect_pads
			(clearance 0)
		)
		(min_thickness 0.25)
		(keepout
			(tracks not_allowed)
			(vias allowed)
			(pads allowed)
			(copperpour not_allowed)
			(footprints allowed)
		)
		(placement
			(enabled no)
			(sheetname "")
		)
		(fill
			(thermal_gap 0.5)
			(thermal_bridge_width 0.5)
			(island_removal_mode 0)
		)
		(polygon
			(pts
				(arc
					(start 5.59054 -154.335734)
					(mid 5.080127 -153.82494)
					(end 4.56946 -154.33548)
				)
				(arc
					(start 4.56946 -155.14828)
					(mid 5.08 -155.65882)
					(end 5.59054 -155.14828)
				)
				(xy 5.59054 -155.015184) (xy 5.347716 -155.015184)
				(arc
					(start 5.323586 -155.039568)
					(mid 4.891383 -155.336897)
					(end 5.188712 -154.904694)
				)
				(xy 5.268976 -154.824684) (xy 5.59054 -154.824684) (xy 5.59054 -154.659584) (xy 5.269484 -154.659584)
				(arc
					(start 5.188712 -154.579066)
					(mid 4.891383 -154.146863)
					(end 5.323586 -154.444192)
				)
				(xy 5.348224 -154.469084) (xy 5.59054 -154.469084)
			)
		)
	)
	(zone
		(net "P3V3")
		(layer "In2.Cu")
		(hatch none 0.5)
		(connect_pads
			(clearance 0.5)
		)
		(min_thickness 0.25)
		(fill yes
			(thermal_gap 0.5)
			(thermal_bridge_width 0.5)
			(island_removal_mode 0)
		)
		(polygon
			(pts
				(xy 52.197 -455.041) (xy 54.483 -452.755) (xy 54.483 -449.199) (xy 52.324 -447.04) (xy 47.752 -447.04)
				(xy 47.117 -447.675) (xy 47.117 -448.623944) (xy 44.849034 -450.89191) (xy 44.849034 -454.393554)
				(xy 45.639228 -455.183748) (xy 52.054252 -455.183748)
			)
		)
	)
	(zone
		(net "P3V3")
		(layer "In2.Cu")
		(hatch none 0.5)
		(connect_pads
			(clearance 0.5)
		)
		(min_thickness 0.25)
		(fill yes
			(thermal_gap 0.5)
			(thermal_bridge_width 0.5)
			(island_removal_mode 0)
		)
		(polygon
			(pts
				(xy 43.18 -121.031) (xy 42.799 -121.412) (xy 42.799 -134.370826) (xy 39.768272 -137.401554) (xy 39.768272 -141.536928)
				(xy 38.3286 -142.9766) (xy 38.3286 -152.6286) (xy 40.513 -154.813) (xy 40.513 -161.29) (xy 39.37 -162.433)
				(xy 37.084 -162.433) (xy 36.322 -163.195) (xy 36.322 -165.735) (xy 37.338 -166.751) (xy 49.403 -166.751)
				(xy 59.055 -157.099) (xy 81.026 -157.099) (xy 85.852 -152.273) (xy 85.852 -143.51) (xy 63.373 -121.031)
			)
		)
	)
	(zone
		(layer "In2.Cu")
		(hatch none 0.5)
		(connect_pads
			(clearance 0)
		)
		(min_thickness 0.25)
		(keepout
			(tracks not_allowed)
			(vias allowed)
			(pads allowed)
			(copperpour not_allowed)
			(footprints allowed)
		)
		(placement
			(enabled no)
			(sheetname "")
		)
		(fill
			(thermal_gap 0.5)
			(thermal_bridge_width 0.5)
			(island_removal_mode 0)
		)
		(polygon
			(pts
				(arc
					(start 5.59054 -423.135552)
					(mid 5.080127 -422.624758)
					(end 4.56946 -423.135298)
				)
				(arc
					(start 4.56946 -423.948098)
					(mid 5.08 -424.458638)
					(end 5.59054 -423.948098)
				)
				(xy 5.59054 -423.815256) (xy 5.347462 -423.815256)
				(arc
					(start 5.323586 -423.839386)
					(mid 4.891383 -424.136715)
					(end 5.188712 -423.704512)
				)
				(xy 5.268722 -423.624756) (xy 5.59054 -423.624756) (xy 5.59054 -423.459656) (xy 5.269738 -423.459656)
				(arc
					(start 5.188712 -423.378884)
					(mid 4.891383 -422.946681)
					(end 5.323586 -423.24401)
				)
				(xy 5.348478 -423.269156) (xy 5.59054 -423.269156)
			)
		)
	)
	(zone
		(net "P3V3")
		(layer "In2.Cu")
		(hatch none 0.5)
		(connect_pads
			(clearance 0.5)
		)
		(min_thickness 0.25)
		(fill yes
			(thermal_gap 0.5)
			(thermal_bridge_width 0.5)
			(island_removal_mode 0)
		)
		(polygon
			(pts
				(xy 52.705 -15.367) (xy 37.900356 -30.171644) (xy 37.900356 -48.060356) (xy 40.767 -50.927) (xy 44.577 -50.927)
				(xy 46.482 -52.832) (xy 46.482 -59.944) (xy 45.974 -60.452) (xy 44.958 -60.452) (xy 43.434 -61.976)
				(xy 41.402 -61.976) (xy 40.259 -60.833) (xy 36.703 -60.833) (xy 36.449 -61.087) (xy 36.449 -62.9158)
				(xy 38.5572 -65.024) (xy 61.468 -65.024) (xy 66.421 -60.071) (xy 75.184 -60.071) (xy 93.345 -78.232)
				(xy 100.711 -78.232) (xy 104.013 -74.93) (xy 104.013 -53.975) (xy 109.22 -48.768) (xy 214.757 -48.768)
				(xy 220.091 -43.434) (xy 235.204 -43.434) (xy 238.252 -40.386) (xy 238.252 -32.004) (xy 219.456 -13.208)
				(xy 215.9 -13.208) (xy 213.741 -15.367)
			)
		)
	)
	(zone
		(layer "In2.Cu")
		(hatch none 0.5)
		(connect_pads
			(clearance 0)
		)
		(min_thickness 0.25)
		(keepout
			(tracks not_allowed)
			(vias allowed)
			(pads allowed)
			(copperpour not_allowed)
			(footprints allowed)
		)
		(placement
			(enabled no)
			(sheetname "")
		)
		(fill
			(thermal_gap 0.5)
			(thermal_bridge_width 0.5)
			(island_removal_mode 0)
		)
		(polygon
			(pts
				(arc
					(start 5.59054 -209.535776)
					(mid 5.080127 -209.024982)
					(end 4.56946 -209.535522)
				)
				(arc
					(start 4.56946 -210.348322)
					(mid 5.08 -210.858862)
					(end 5.59054 -210.348322)
				)
				(xy 5.59054 -210.215226) (xy 5.347716 -210.215226)
				(arc
					(start 5.323586 -210.23961)
					(mid 4.891383 -210.536939)
					(end 5.188712 -210.104736)
				)
				(xy 5.268976 -210.024726) (xy 5.59054 -210.024726) (xy 5.59054 -209.859626) (xy 5.269484 -209.859626)
				(arc
					(start 5.188712 -209.779108)
					(mid 4.891383 -209.346905)
					(end 5.323586 -209.644234)
				)
				(xy 5.348224 -209.669126) (xy 5.59054 -209.669126)
			)
		)
	)
	(zone
		(layer "In2.Cu")
		(hatch none 0.5)
		(connect_pads
			(clearance 0)
		)
		(min_thickness 0.25)
		(keepout
			(tracks not_allowed)
			(vias allowed)
			(pads allowed)
			(copperpour not_allowed)
			(footprints allowed)
		)
		(placement
			(enabled no)
			(sheetname "")
		)
		(fill
			(thermal_gap 0.5)
			(thermal_bridge_width 0.5)
			(island_removal_mode 0)
		)
		(polygon
			(pts
				(arc
					(start 222.339154 -388.231634)
					(mid 221.727141 -387.61924)
					(end 221.114874 -388.23138)
				)
				(xy 221.114874 -388.51713) (xy 221.306644 -388.51713)
				(arc
					(start 221.483428 -388.340092)
					(mid 221.915631 -388.042763)
					(end 221.618302 -388.474966)
				)
				(xy 221.385384 -388.70763) (xy 221.114874 -388.70763) (xy 221.114874 -388.87273) (xy 221.385384 -388.87273)
				(arc
					(start 221.618302 -389.105394)
					(mid 221.915631 -389.537597)
					(end 221.483428 -389.240268)
				)
				(xy 221.306644 -389.06323) (xy 221.114874 -389.06323)
				(arc
					(start 221.114874 -389.34898)
					(mid 221.727014 -389.96112)
					(end 222.339154 -389.34898)
				)
			)
		)
	)
	(zone
		(layer "In2.Cu")
		(hatch none 0.5)
		(connect_pads
			(clearance 0)
		)
		(min_thickness 0.25)
		(keepout
			(tracks not_allowed)
			(vias allowed)
			(pads allowed)
			(copperpour not_allowed)
			(footprints allowed)
		)
		(placement
			(enabled no)
			(sheetname "")
		)
		(fill
			(thermal_gap 0.5)
			(thermal_bridge_width 0.5)
			(island_removal_mode 0)
		)
		(polygon
			(pts
				(arc
					(start 222.339154 -262.83158)
					(mid 221.727141 -262.219186)
					(end 221.114874 -262.831326)
				)
				(xy 221.114874 -263.117076) (xy 221.306644 -263.117076)
				(arc
					(start 221.483428 -262.940038)
					(mid 221.915631 -262.642709)
					(end 221.618302 -263.074912)
				)
				(xy 221.385384 -263.307576) (xy 221.114874 -263.307576) (xy 221.114874 -263.472676) (xy 221.385384 -263.472676)
				(arc
					(start 221.618302 -263.70534)
					(mid 221.915631 -264.137543)
					(end 221.483428 -263.840214)
				)
				(xy 221.306644 -263.663176) (xy 221.114874 -263.663176)
				(arc
					(start 221.114874 -263.948926)
					(mid 221.727014 -264.561066)
					(end 222.339154 -263.948926)
				)
			)
		)
	)
	(zone
		(layer "In2.Cu")
		(hatch none 0.5)
		(connect_pads
			(clearance 0)
		)
		(min_thickness 0.25)
		(keepout
			(tracks not_allowed)
			(vias allowed)
			(pads allowed)
			(copperpour not_allowed)
			(footprints allowed)
		)
		(placement
			(enabled no)
			(sheetname "")
		)
		(fill
			(thermal_gap 0.5)
			(thermal_bridge_width 0.5)
			(island_removal_mode 0)
		)
		(polygon
			(pts
				(arc
					(start 222.339154 -172.631354)
					(mid 221.727141 -172.01896)
					(end 221.114874 -172.6311)
				)
				(xy 221.114874 -172.917104) (xy 221.30639 -172.917104)
				(arc
					(start 221.483428 -172.739812)
					(mid 221.915631 -172.442483)
					(end 221.618302 -172.874686)
				)
				(xy 221.38513 -173.107604) (xy 221.114874 -173.107604) (xy 221.114874 -173.272704) (xy 221.385638 -173.272704)
				(arc
					(start 221.618302 -173.505114)
					(mid 221.915631 -173.937317)
					(end 221.483428 -173.639988)
				)
				(xy 221.306898 -173.463204) (xy 221.114874 -173.463204)
				(arc
					(start 221.114874 -173.7487)
					(mid 221.727014 -174.36084)
					(end 222.339154 -173.7487)
				)
			)
		)
	)
	(zone
		(layer "In2.Cu")
		(hatch none 0.5)
		(connect_pads
			(clearance 0)
		)
		(min_thickness 0.25)
		(keepout
			(tracks not_allowed)
			(vias allowed)
			(pads allowed)
			(copperpour not_allowed)
			(footprints allowed)
		)
		(placement
			(enabled no)
			(sheetname "")
		)
		(fill
			(thermal_gap 0.5)
			(thermal_bridge_width 0.5)
			(island_removal_mode 0)
		)
		(polygon
			(pts
				(arc
					(start 5.59054 -179.935632)
					(mid 5.080127 -179.424838)
					(end 4.56946 -179.935378)
				)
				(arc
					(start 4.56946 -180.748178)
					(mid 5.08 -181.258718)
					(end 5.59054 -180.748178)
				)
				(xy 5.59054 -180.615082) (xy 5.347716 -180.615082)
				(arc
					(start 5.323586 -180.639466)
					(mid 4.891383 -180.936795)
					(end 5.188712 -180.504592)
				)
				(xy 5.268976 -180.424582) (xy 5.59054 -180.424582) (xy 5.59054 -180.259482) (xy 5.269484 -180.259482)
				(arc
					(start 5.188712 -180.178964)
					(mid 4.891383 -179.746761)
					(end 5.323586 -180.04409)
				)
				(xy 5.348224 -180.068982) (xy 5.59054 -180.068982)
			)
		)
	)
	(zone
		(layer "In2.Cu")
		(hatch none 0.5)
		(connect_pads
			(clearance 0)
		)
		(min_thickness 0.25)
		(keepout
			(tracks not_allowed)
			(vias allowed)
			(pads allowed)
			(copperpour not_allowed)
			(footprints allowed)
		)
		(placement
			(enabled no)
			(sheetname "")
		)
		(fill
			(thermal_gap 0.5)
			(thermal_bridge_width 0.5)
			(island_removal_mode 0)
		)
		(polygon
			(pts
				(arc
					(start 37.33927 -182.231538)
					(mid 36.727257 -181.619144)
					(end 36.11499 -182.231284)
				)
				(xy 36.11499 -182.517034) (xy 36.30676 -182.517034)
				(arc
					(start 36.483544 -182.339996)
					(mid 36.915747 -182.042667)
					(end 36.618418 -182.47487)
				)
				(xy 36.3855 -182.707534) (xy 36.11499 -182.707534) (xy 36.11499 -182.872634) (xy 36.3855 -182.872634)
				(arc
					(start 36.618418 -183.105298)
					(mid 36.915747 -183.537501)
					(end 36.483544 -183.240172)
				)
				(xy 36.30676 -183.063134) (xy 36.11499 -183.063134)
				(arc
					(start 36.11499 -183.348884)
					(mid 36.72713 -183.961024)
					(end 37.33927 -183.348884)
				)
			)
		)
	)
	(zone
		(layer "In2.Cu")
		(hatch none 0.5)
		(connect_pads
			(clearance 0)
		)
		(min_thickness 0.25)
		(keepout
			(tracks not_allowed)
			(vias allowed)
			(pads allowed)
			(copperpour not_allowed)
			(footprints allowed)
		)
		(placement
			(enabled no)
			(sheetname "")
		)
		(fill
			(thermal_gap 0.5)
			(thermal_bridge_width 0.5)
			(island_removal_mode 0)
		)
		(polygon
			(pts
				(arc
					(start 37.33927 -159.831532)
					(mid 36.727257 -159.219138)
					(end 36.11499 -159.831278)
				)
				(xy 36.11499 -160.117028) (xy 36.30676 -160.117028)
				(arc
					(start 36.483544 -159.93999)
					(mid 36.915747 -159.642661)
					(end 36.618418 -160.074864)
				)
				(xy 36.3855 -160.307528) (xy 36.11499 -160.307528) (xy 36.11499 -160.472628) (xy 36.3855 -160.472628)
				(arc
					(start 36.618418 -160.705292)
					(mid 36.915747 -161.137495)
					(end 36.483544 -160.840166)
				)
				(xy 36.30676 -160.663128) (xy 36.11499 -160.663128)
				(arc
					(start 36.11499 -160.948878)
					(mid 36.72713 -161.561018)
					(end 37.33927 -160.948878)
				)
			)
		)
	)
	(zone
		(layer "In2.Cu")
		(hatch none 0.5)
		(connect_pads
			(clearance 0)
		)
		(min_thickness 0.25)
		(keepout
			(tracks not_allowed)
			(vias allowed)
			(pads allowed)
			(copperpour not_allowed)
			(footprints allowed)
		)
		(placement
			(enabled no)
			(sheetname "")
		)
		(fill
			(thermal_gap 0.5)
			(thermal_bridge_width 0.5)
			(island_removal_mode 0)
		)
		(polygon
			(pts
				(arc
					(start 25.88514 -327.451212)
					(mid 25.273 -326.839072)
					(end 24.66086 -327.451212)
				)
				(arc
					(start 24.66086 -328.568558)
					(mid 25.272873 -329.180952)
					(end 25.88514 -328.568812)
				)
				(xy 25.88514 -328.258932) (xy 25.7175 -328.258932)
				(arc
					(start 25.516586 -328.4601)
					(mid 25.084383 -328.757429)
					(end 25.381712 -328.325226)
				)
				(xy 25.63876 -328.068432) (xy 25.88514 -328.068432) (xy 25.88514 -327.903332) (xy 25.5905 -327.903332)
				(arc
					(start 25.381712 -327.694798)
					(mid 25.084383 -327.262595)
					(end 25.516586 -327.559924)
				)
				(xy 25.66924 -327.712832) (xy 25.88514 -327.712832)
			)
		)
	)
	(zone
		(layer "In2.Cu")
		(hatch none 0.5)
		(connect_pads
			(clearance 0)
		)
		(min_thickness 0.25)
		(keepout
			(tracks not_allowed)
			(vias allowed)
			(pads allowed)
			(copperpour not_allowed)
			(footprints allowed)
		)
		(placement
			(enabled no)
			(sheetname "")
		)
		(fill
			(thermal_gap 0.5)
			(thermal_bridge_width 0.5)
			(island_removal_mode 0)
		)
		(polygon
			(pts
				(arc
					(start 25.88514 -219.651326)
					(mid 25.273127 -219.038932)
					(end 24.66086 -219.651072)
				)
				(arc
					(start 24.66086 -220.768672)
					(mid 25.273 -221.380812)
					(end 25.88514 -220.768672)
				)
				(xy 25.88514 -220.54185) (xy 25.634442 -220.54185)
				(arc
					(start 25.516586 -220.65996)
					(mid 25.084383 -220.957289)
					(end 25.381712 -220.525086)
				)
				(xy 25.555702 -220.35135) (xy 25.88514 -220.35135) (xy 25.88514 -220.18625) (xy 25.673558 -220.18625)
				(arc
					(start 25.381712 -219.894658)
					(mid 25.084383 -219.462455)
					(end 25.516586 -219.759784)
				)
				(xy 25.752298 -219.99575) (xy 25.88514 -219.99575)
			)
		)
	)
	(zone
		(layer "In2.Cu")
		(hatch none 0.5)
		(connect_pads
			(clearance 0)
		)
		(min_thickness 0.25)
		(keepout
			(tracks not_allowed)
			(vias allowed)
			(pads allowed)
			(copperpour not_allowed)
			(footprints allowed)
		)
		(placement
			(enabled no)
			(sheetname "")
		)
		(fill
			(thermal_gap 0.5)
			(thermal_bridge_width 0.5)
			(island_removal_mode 0)
		)
		(polygon
			(pts
				(arc
					(start 222.339154 -365.831628)
					(mid 221.727141 -365.219234)
					(end 221.114874 -365.831374)
				)
				(xy 221.114874 -366.117124) (xy 221.306644 -366.117124)
				(arc
					(start 221.483428 -365.940086)
					(mid 221.915631 -365.642757)
					(end 221.618302 -366.07496)
				)
				(xy 221.385384 -366.307624) (xy 221.114874 -366.307624) (xy 221.114874 -366.472724) (xy 221.385384 -366.472724)
				(arc
					(start 221.618302 -366.705388)
					(mid 221.915631 -367.137591)
					(end 221.483428 -366.840262)
				)
				(xy 221.306644 -366.663224) (xy 221.114874 -366.663224)
				(arc
					(start 221.114874 -366.948974)
					(mid 221.727014 -367.561114)
					(end 222.339154 -366.948974)
				)
			)
		)
	)
	(zone
		(layer "In2.Cu")
		(hatch none 0.5)
		(connect_pads
			(clearance 0)
		)
		(min_thickness 0.25)
		(keepout
			(tracks not_allowed)
			(vias allowed)
			(pads allowed)
			(copperpour not_allowed)
			(footprints allowed)
		)
		(placement
			(enabled no)
			(sheetname "")
		)
		(fill
			(thermal_gap 0.5)
			(thermal_bridge_width 0.5)
			(island_removal_mode 0)
		)
		(polygon
			(pts
				(arc
					(start 5.59054 -206.33563)
					(mid 5.080127 -205.824836)
					(end 4.56946 -206.335376)
				)
				(arc
					(start 4.56946 -207.148176)
					(mid 5.08 -207.658716)
					(end 5.59054 -207.148176)
				)
				(xy 5.59054 -207.015334) (xy 5.347462 -207.015334)
				(arc
					(start 5.323586 -207.039464)
					(mid 4.891383 -207.336793)
					(end 5.188712 -206.90459)
				)
				(xy 5.268722 -206.824834) (xy 5.59054 -206.824834) (xy 5.59054 -206.659734) (xy 5.269738 -206.659734)
				(arc
					(start 5.188712 -206.578962)
					(mid 4.891383 -206.146759)
					(end 5.323586 -206.444088)
				)
				(xy 5.348478 -206.469234) (xy 5.59054 -206.469234)
			)
		)
	)
	(zone
		(layer "In2.Cu")
		(hatch none 0.5)
		(connect_pads
			(clearance 0)
		)
		(min_thickness 0.25)
		(keepout
			(tracks not_allowed)
			(vias allowed)
			(pads allowed)
			(copperpour not_allowed)
			(footprints allowed)
		)
		(placement
			(enabled no)
			(sheetname "")
		)
		(fill
			(thermal_gap 0.5)
			(thermal_bridge_width 0.5)
			(island_removal_mode 0)
		)
		(polygon
			(pts
				(arc
					(start 5.59054 -293.135558)
					(mid 5.080127 -292.624764)
					(end 4.56946 -293.135304)
				)
				(arc
					(start 4.56946 -293.948104)
					(mid 5.08 -294.458644)
					(end 5.59054 -293.948104)
				)
				(xy 5.59054 -293.815262) (xy 5.347462 -293.815262)
				(arc
					(start 5.323586 -293.839392)
					(mid 4.891383 -294.136721)
					(end 5.188712 -293.704518)
				)
				(xy 5.268722 -293.624762) (xy 5.59054 -293.624762) (xy 5.59054 -293.459662) (xy 5.269738 -293.459662)
				(arc
					(start 5.188712 -293.37889)
					(mid 4.891383 -292.946687)
					(end 5.323586 -293.244016)
				)
				(xy 5.348478 -293.269162) (xy 5.59054 -293.269162)
			)
		)
	)
	(zone
		(layer "In2.Cu")
		(hatch none 0.5)
		(connect_pads
			(clearance 0)
		)
		(min_thickness 0.25)
		(keepout
			(tracks not_allowed)
			(vias allowed)
			(pads allowed)
			(copperpour not_allowed)
			(footprints allowed)
		)
		(placement
			(enabled no)
			(sheetname "")
		)
		(fill
			(thermal_gap 0.5)
			(thermal_bridge_width 0.5)
			(island_removal_mode 0)
		)
		(polygon
			(pts
				(arc
					(start 5.59054 -219.135706)
					(mid 5.080127 -218.624912)
					(end 4.56946 -219.135452)
				)
				(arc
					(start 4.56946 -219.948252)
					(mid 5.08 -220.458792)
					(end 5.59054 -219.948252)
				)
				(xy 5.59054 -219.815156) (xy 5.347716 -219.815156)
				(arc
					(start 5.323586 -219.83954)
					(mid 4.891383 -220.136869)
					(end 5.188712 -219.704666)
				)
				(xy 5.268976 -219.624656) (xy 5.59054 -219.624656) (xy 5.59054 -219.459556) (xy 5.269484 -219.459556)
				(arc
					(start 5.188712 -219.379038)
					(mid 4.891383 -218.946835)
					(end 5.323586 -219.244164)
				)
				(xy 5.348224 -219.269056) (xy 5.59054 -219.269056)
			)
		)
	)
	(zone
		(layer "In2.Cu")
		(hatch none 0.5)
		(connect_pads
			(clearance 0)
		)
		(min_thickness 0.25)
		(keepout
			(tracks not_allowed)
			(vias allowed)
			(pads allowed)
			(copperpour not_allowed)
			(footprints allowed)
		)
		(placement
			(enabled no)
			(sheetname "")
		)
		(fill
			(thermal_gap 0.5)
			(thermal_bridge_width 0.5)
			(island_removal_mode 0)
		)
		(polygon
			(pts
				(arc
					(start 5.59054 -199.935592)
					(mid 5.080127 -199.424798)
					(end 4.56946 -199.935338)
				)
				(arc
					(start 4.56946 -200.748138)
					(mid 5.08 -201.258678)
					(end 5.59054 -200.748138)
				)
				(xy 5.59054 -200.615296) (xy 5.347462 -200.615296)
				(arc
					(start 5.323586 -200.639426)
					(mid 4.891383 -200.936755)
					(end 5.188712 -200.504552)
				)
				(xy 5.268722 -200.424796) (xy 5.59054 -200.424796) (xy 5.59054 -200.259696) (xy 5.269738 -200.259696)
				(arc
					(start 5.188712 -200.178924)
					(mid 4.891383 -199.746721)
					(end 5.323586 -200.04405)
				)
				(xy 5.348478 -200.069196) (xy 5.59054 -200.069196)
			)
		)
	)
	(zone
		(layer "In2.Cu")
		(hatch none 0.5)
		(connect_pads
			(clearance 0)
		)
		(min_thickness 0.25)
		(keepout
			(tracks not_allowed)
			(vias allowed)
			(pads allowed)
			(copperpour not_allowed)
			(footprints allowed)
		)
		(placement
			(enabled no)
			(sheetname "")
		)
		(fill
			(thermal_gap 0.5)
			(thermal_bridge_width 0.5)
			(island_removal_mode 0)
		)
		(polygon
			(pts
				(arc
					(start 37.33927 -280.431494)
					(mid 36.727257 -279.8191)
					(end 36.11499 -280.43124)
				)
				(xy 36.11499 -280.717244) (xy 36.306506 -280.717244)
				(arc
					(start 36.483544 -280.539952)
					(mid 36.915747 -280.242623)
					(end 36.618418 -280.674826)
				)
				(xy 36.385246 -280.907744) (xy 36.11499 -280.907744) (xy 36.11499 -281.072844) (xy 36.385754 -281.072844)
				(arc
					(start 36.618418 -281.305254)
					(mid 36.915747 -281.737457)
					(end 36.483544 -281.440128)
				)
				(xy 36.307014 -281.263344) (xy 36.11499 -281.263344)
				(arc
					(start 36.11499 -281.54884)
					(mid 36.72713 -282.16098)
					(end 37.33927 -281.54884)
				)
			)
		)
	)
	(zone
		(layer "In2.Cu")
		(hatch none 0.5)
		(connect_pads
			(clearance 0)
		)
		(min_thickness 0.25)
		(keepout
			(tracks not_allowed)
			(vias allowed)
			(pads allowed)
			(copperpour not_allowed)
			(footprints allowed)
		)
		(placement
			(enabled no)
			(sheetname "")
		)
		(fill
			(thermal_gap 0.5)
			(thermal_bridge_width 0.5)
			(island_removal_mode 0)
		)
		(polygon
			(pts
				(arc
					(start 5.59054 -203.135738)
					(mid 5.080127 -202.624944)
					(end 4.56946 -203.135484)
				)
				(arc
					(start 4.56946 -203.948284)
					(mid 5.08 -204.458824)
					(end 5.59054 -203.948284)
				)
				(xy 5.59054 -203.815188) (xy 5.347716 -203.815188)
				(arc
					(start 5.323586 -203.839572)
					(mid 4.891383 -204.136901)
					(end 5.188712 -203.704698)
				)
				(xy 5.268976 -203.624688) (xy 5.59054 -203.624688) (xy 5.59054 -203.459588) (xy 5.269484 -203.459588)
				(arc
					(start 5.188712 -203.37907)
					(mid 4.891383 -202.946867)
					(end 5.323586 -203.244196)
				)
				(xy 5.348224 -203.269088) (xy 5.59054 -203.269088)
			)
		)
	)
	(zone
		(layer "In2.Cu")
		(hatch none 0.5)
		(connect_pads
			(clearance 0)
		)
		(min_thickness 0.25)
		(keepout
			(tracks not_allowed)
			(vias allowed)
			(pads allowed)
			(copperpour not_allowed)
			(footprints allowed)
		)
		(placement
			(enabled no)
			(sheetname "")
		)
		(fill
			(thermal_gap 0.5)
			(thermal_bridge_width 0.5)
			(island_removal_mode 0)
		)
		(polygon
			(pts
				(arc
					(start 222.339154 -79.23149)
					(mid 221.727141 -78.619096)
					(end 221.114874 -79.231236)
				)
				(xy 221.114874 -79.516986) (xy 221.306644 -79.516986)
				(arc
					(start 221.483428 -79.339948)
					(mid 221.915631 -79.042619)
					(end 221.618302 -79.474822)
				)
				(xy 221.385384 -79.707486) (xy 221.114874 -79.707486) (xy 221.114874 -79.872586) (xy 221.385384 -79.872586)
				(arc
					(start 221.618302 -80.10525)
					(mid 221.915631 -80.537453)
					(end 221.483428 -80.240124)
				)
				(xy 221.306644 -80.063086) (xy 221.114874 -80.063086)
				(arc
					(start 221.114874 -80.348836)
					(mid 221.727014 -80.960976)
					(end 222.339154 -80.348836)
				)
			)
		)
	)
	(zone
		(layer "In2.Cu")
		(hatch none 0.5)
		(connect_pads
			(clearance 0)
		)
		(min_thickness 0.25)
		(keepout
			(tracks not_allowed)
			(vias allowed)
			(pads allowed)
			(copperpour not_allowed)
			(footprints allowed)
		)
		(placement
			(enabled no)
			(sheetname "")
		)
		(fill
			(thermal_gap 0.5)
			(thermal_bridge_width 0.5)
			(island_removal_mode 0)
		)
		(polygon
			(pts
				(arc
					(start 5.59054 -398.3355)
					(mid 5.080127 -397.824706)
					(end 4.56946 -398.335246)
				)
				(arc
					(start 4.56946 -399.148046)
					(mid 5.08 -399.658586)
					(end 5.59054 -399.148046)
				)
				(xy 5.59054 -399.01495) (xy 5.347716 -399.01495)
				(arc
					(start 5.323586 -399.039334)
					(mid 4.891383 -399.336663)
					(end 5.188712 -398.90446)
				)
				(xy 5.268976 -398.82445) (xy 5.59054 -398.82445) (xy 5.59054 -398.65935) (xy 5.269484 -398.65935)
				(arc
					(start 5.188712 -398.578832)
					(mid 4.891383 -398.146629)
					(end 5.323586 -398.443958)
				)
				(xy 5.348224 -398.46885) (xy 5.59054 -398.46885)
			)
		)
	)
	(zone
		(layer "In2.Cu")
		(hatch none 0.5)
		(connect_pads
			(clearance 0)
		)
		(min_thickness 0.25)
		(keepout
			(tracks not_allowed)
			(vias allowed)
			(pads allowed)
			(copperpour not_allowed)
			(footprints allowed)
		)
		(placement
			(enabled no)
			(sheetname "")
		)
		(fill
			(thermal_gap 0.5)
			(thermal_bridge_width 0.5)
			(island_removal_mode 0)
		)
		(polygon
			(pts
				(arc
					(start 5.59054 -354.735638)
					(mid 5.080127 -354.224844)
					(end 4.56946 -354.735384)
				)
				(arc
					(start 4.56946 -355.548184)
					(mid 5.08 -356.058724)
					(end 5.59054 -355.548184)
				)
				(xy 5.59054 -355.415088) (xy 5.347716 -355.415088)
				(arc
					(start 5.323586 -355.439472)
					(mid 4.891383 -355.736801)
					(end 5.188712 -355.304598)
				)
				(xy 5.268976 -355.224588) (xy 5.59054 -355.224588) (xy 5.59054 -355.059488) (xy 5.269484 -355.059488)
				(arc
					(start 5.188712 -354.97897)
					(mid 4.891383 -354.546767)
					(end 5.323586 -354.844096)
				)
				(xy 5.348224 -354.868988) (xy 5.59054 -354.868988)
			)
		)
	)
	(zone
		(layer "In2.Cu")
		(hatch none 0.5)
		(connect_pads
			(clearance 0)
		)
		(min_thickness 0.25)
		(keepout
			(tracks not_allowed)
			(vias allowed)
			(pads allowed)
			(copperpour not_allowed)
			(footprints allowed)
		)
		(placement
			(enabled no)
			(sheetname "")
		)
		(fill
			(thermal_gap 0.5)
			(thermal_bridge_width 0.5)
			(island_removal_mode 0)
		)
		(polygon
			(pts
				(arc
					(start 25.88514 -224.451164)
					(mid 25.273 -223.839024)
					(end 24.66086 -224.451164)
				)
				(arc
					(start 24.66086 -225.56851)
					(mid 25.272873 -226.180904)
					(end 25.88514 -225.568764)
				)
				(xy 25.88514 -225.28276) (xy 25.693624 -225.28276)
				(arc
					(start 25.516586 -225.460052)
					(mid 25.084383 -225.757381)
					(end 25.381712 -225.325178)
				)
				(xy 25.614884 -225.09226) (xy 25.88514 -225.09226) (xy 25.88514 -224.92716) (xy 25.614376 -224.92716)
				(arc
					(start 25.381712 -224.69475)
					(mid 25.084383 -224.262547)
					(end 25.516586 -224.559876)
				)
				(xy 25.693116 -224.73666) (xy 25.88514 -224.73666)
			)
		)
	)
	(zone
		(layer "In2.Cu")
		(hatch none 0.5)
		(connect_pads
			(clearance 0)
		)
		(min_thickness 0.25)
		(keepout
			(tracks not_allowed)
			(vias allowed)
			(pads allowed)
			(copperpour not_allowed)
			(footprints allowed)
		)
		(placement
			(enabled no)
			(sheetname "")
		)
		(fill
			(thermal_gap 0.5)
			(thermal_bridge_width 0.5)
			(island_removal_mode 0)
		)
		(polygon
			(pts
				(arc
					(start 5.59054 -309.13578)
					(mid 5.080127 -308.624986)
					(end 4.56946 -309.135526)
				)
				(arc
					(start 4.56946 -309.948326)
					(mid 5.08 -310.458866)
					(end 5.59054 -309.948326)
				)
				(xy 5.59054 -309.81523) (xy 5.347716 -309.81523)
				(arc
					(start 5.323586 -309.839614)
					(mid 4.891383 -310.136943)
					(end 5.188712 -309.70474)
				)
				(xy 5.268976 -309.62473) (xy 5.59054 -309.62473) (xy 5.59054 -309.45963) (xy 5.269484 -309.45963)
				(arc
					(start 5.188712 -309.379112)
					(mid 4.891383 -308.946909)
					(end 5.323586 -309.244238)
				)
				(xy 5.348224 -309.26913) (xy 5.59054 -309.26913)
			)
		)
	)
	(zone
		(layer "In2.Cu")
		(hatch none 0.5)
		(connect_pads
			(clearance 0)
		)
		(min_thickness 0.25)
		(keepout
			(tracks not_allowed)
			(vias allowed)
			(pads allowed)
			(copperpour not_allowed)
			(footprints allowed)
		)
		(placement
			(enabled no)
			(sheetname "")
		)
		(fill
			(thermal_gap 0.5)
			(thermal_bridge_width 0.5)
			(island_removal_mode 0)
		)
		(polygon
			(pts
				(arc
					(start 222.339154 -177.431446)
					(mid 221.727141 -176.819052)
					(end 221.114874 -177.431192)
				)
				(xy 221.114874 -177.717196) (xy 221.30639 -177.717196)
				(arc
					(start 221.483428 -177.539904)
					(mid 221.915631 -177.242575)
					(end 221.618302 -177.674778)
				)
				(xy 221.38513 -177.907696) (xy 221.114874 -177.907696) (xy 221.114874 -178.072796) (xy 221.385638 -178.072796)
				(arc
					(start 221.618302 -178.305206)
					(mid 221.915631 -178.737409)
					(end 221.483428 -178.44008)
				)
				(xy 221.306898 -178.263296) (xy 221.114874 -178.263296)
				(arc
					(start 221.114874 -178.548792)
					(mid 221.727014 -179.160932)
					(end 222.339154 -178.548792)
				)
			)
		)
	)
	(zone
		(layer "In2.Cu")
		(hatch none 0.5)
		(connect_pads
			(clearance 0)
		)
		(min_thickness 0.25)
		(keepout
			(tracks not_allowed)
			(vias allowed)
			(pads allowed)
			(copperpour not_allowed)
			(footprints allowed)
		)
		(placement
			(enabled no)
			(sheetname "")
		)
		(fill
			(thermal_gap 0.5)
			(thermal_bridge_width 0.5)
			(island_removal_mode 0)
		)
		(polygon
			(pts
				(arc
					(start 25.88514 -242.051078)
					(mid 25.273 -241.438938)
					(end 24.66086 -242.051078)
				)
				(arc
					(start 24.66086 -243.168424)
					(mid 25.272873 -243.780818)
					(end 25.88514 -243.168678)
				)
				(xy 25.88514 -242.882928) (xy 25.69337 -242.882928)
				(arc
					(start 25.516586 -243.059966)
					(mid 25.084383 -243.357295)
					(end 25.381712 -242.925092)
				)
				(xy 25.61463 -242.692428) (xy 25.88514 -242.692428) (xy 25.88514 -242.527328) (xy 25.61463 -242.527328)
				(arc
					(start 25.381712 -242.294664)
					(mid 25.084383 -241.862461)
					(end 25.516586 -242.15979)
				)
				(xy 25.69337 -242.336828) (xy 25.88514 -242.336828)
			)
		)
	)
	(zone
		(layer "In2.Cu")
		(hatch none 0.5)
		(connect_pads
			(clearance 0)
		)
		(min_thickness 0.25)
		(keepout
			(tracks not_allowed)
			(vias allowed)
			(pads allowed)
			(copperpour not_allowed)
			(footprints allowed)
		)
		(placement
			(enabled no)
			(sheetname "")
		)
		(fill
			(thermal_gap 0.5)
			(thermal_bridge_width 0.5)
			(island_removal_mode 0)
		)
		(polygon
			(pts
				(arc
					(start 25.88514 -18.451068)
					(mid 25.273 -17.838928)
					(end 24.66086 -18.451068)
				)
				(arc
					(start 24.66086 -19.568414)
					(mid 25.272873 -20.180808)
					(end 25.88514 -19.568668)
				)
				(xy 25.88514 -19.241262) (xy 25.735026 -19.241262)
				(arc
					(start 25.516586 -19.459956)
					(mid 25.084383 -19.757285)
					(end 25.381712 -19.325082)
				)
				(xy 25.656286 -19.050762) (xy 25.88514 -19.050762) (xy 25.88514 -18.885662) (xy 25.572974 -18.885662)
				(arc
					(start 25.381712 -18.694654)
					(mid 25.084383 -18.262451)
					(end 25.516586 -18.55978)
				)
				(xy 25.651714 -18.695162) (xy 25.88514 -18.695162)
			)
		)
	)
	(zone
		(layer "In2.Cu")
		(hatch none 0.5)
		(connect_pads
			(clearance 0)
		)
		(min_thickness 0.25)
		(keepout
			(tracks not_allowed)
			(vias allowed)
			(pads allowed)
			(copperpour not_allowed)
			(footprints allowed)
		)
		(placement
			(enabled no)
			(sheetname "")
		)
		(fill
			(thermal_gap 0.5)
			(thermal_bridge_width 0.5)
			(island_removal_mode 0)
		)
		(polygon
			(pts
				(arc
					(start 25.88514 -332.251304)
					(mid 25.273 -331.639164)
					(end 24.66086 -332.251304)
				)
				(arc
					(start 24.66086 -333.36865)
					(mid 25.272873 -333.981044)
					(end 25.88514 -333.368904)
				)
				(xy 25.88514 -333.0829) (xy 25.693624 -333.0829)
				(arc
					(start 25.516586 -333.260192)
					(mid 25.084383 -333.557521)
					(end 25.381712 -333.125318)
				)
				(xy 25.614884 -332.8924) (xy 25.88514 -332.8924) (xy 25.88514 -332.7273) (xy 25.614376 -332.7273)
				(arc
					(start 25.381712 -332.49489)
					(mid 25.084383 -332.062687)
					(end 25.516586 -332.360016)
				)
				(xy 25.693116 -332.5368) (xy 25.88514 -332.5368)
			)
		)
	)
	(zone
		(layer "In2.Cu")
		(hatch none 0.5)
		(connect_pads
			(clearance 0)
		)
		(min_thickness 0.25)
		(keepout
			(tracks not_allowed)
			(vias allowed)
			(pads allowed)
			(copperpour not_allowed)
			(footprints allowed)
		)
		(placement
			(enabled no)
			(sheetname "")
		)
		(fill
			(thermal_gap 0.5)
			(thermal_bridge_width 0.5)
			(island_removal_mode 0)
		)
		(polygon
			(pts
				(arc
					(start 222.339154 -383.431542)
					(mid 221.727141 -382.819148)
					(end 221.114874 -383.431288)
				)
				(xy 221.114874 -383.717292) (xy 221.30639 -383.717292)
				(arc
					(start 221.483428 -383.54)
					(mid 221.915631 -383.242671)
					(end 221.618302 -383.674874)
				)
				(xy 221.38513 -383.907792) (xy 221.114874 -383.907792) (xy 221.114874 -384.072892) (xy 221.385638 -384.072892)
				(arc
					(start 221.618302 -384.305302)
					(mid 221.915631 -384.737505)
					(end 221.483428 -384.440176)
				)
				(xy 221.306898 -384.263392) (xy 221.114874 -384.263392)
				(arc
					(start 221.114874 -384.548888)
					(mid 221.727014 -385.161028)
					(end 222.339154 -384.548888)
				)
			)
		)
	)
	(zone
		(layer "In2.Cu")
		(hatch none 0.5)
		(connect_pads
			(clearance 0)
		)
		(min_thickness 0.25)
		(keepout
			(tracks not_allowed)
			(vias allowed)
			(pads allowed)
			(copperpour not_allowed)
			(footprints allowed)
		)
		(placement
			(enabled no)
			(sheetname "")
		)
		(fill
			(thermal_gap 0.5)
			(thermal_bridge_width 0.5)
			(island_removal_mode 0)
		)
		(polygon
			(pts
				(arc
					(start 25.88514 -121.451116)
					(mid 25.273 -120.838976)
					(end 24.66086 -121.451116)
				)
				(arc
					(start 24.66086 -122.568462)
					(mid 25.272873 -123.180856)
					(end 25.88514 -122.568716)
				)
				(xy 25.88514 -122.282712) (xy 25.693624 -122.282712)
				(arc
					(start 25.516586 -122.460004)
					(mid 25.084383 -122.757333)
					(end 25.381712 -122.32513)
				)
				(xy 25.614884 -122.092212) (xy 25.88514 -122.092212) (xy 25.88514 -121.927112) (xy 25.614376 -121.927112)
				(arc
					(start 25.381712 -121.694702)
					(mid 25.084383 -121.262499)
					(end 25.516586 -121.559828)
				)
				(xy 25.693116 -121.736612) (xy 25.88514 -121.736612)
			)
		)
	)
	(zone
		(layer "In2.Cu")
		(hatch none 0.5)
		(connect_pads
			(clearance 0)
		)
		(min_thickness 0.25)
		(keepout
			(tracks not_allowed)
			(vias allowed)
			(pads allowed)
			(copperpour not_allowed)
			(footprints allowed)
		)
		(placement
			(enabled no)
			(sheetname "")
		)
		(fill
			(thermal_gap 0.5)
			(thermal_bridge_width 0.5)
			(island_removal_mode 0)
		)
		(polygon
			(pts
				(arc
					(start 5.59054 -215.93556)
					(mid 5.080127 -215.424766)
					(end 4.56946 -215.935306)
				)
				(arc
					(start 4.56946 -216.748106)
					(mid 5.08 -217.258646)
					(end 5.59054 -216.748106)
				)
				(xy 5.59054 -216.615264) (xy 5.347462 -216.615264)
				(arc
					(start 5.323586 -216.639394)
					(mid 4.891383 -216.936723)
					(end 5.188712 -216.50452)
				)
				(xy 5.268722 -216.424764) (xy 5.59054 -216.424764) (xy 5.59054 -216.259664) (xy 5.269738 -216.259664)
				(arc
					(start 5.188712 -216.178892)
					(mid 4.891383 -215.746689)
					(end 5.323586 -216.044018)
				)
				(xy 5.348478 -216.069164) (xy 5.59054 -216.069164)
			)
		)
	)
	(zone
		(layer "In2.Cu")
		(hatch none 0.5)
		(connect_pads
			(clearance 0)
		)
		(min_thickness 0.25)
		(keepout
			(tracks not_allowed)
			(vias allowed)
			(pads allowed)
			(copperpour not_allowed)
			(footprints allowed)
		)
		(placement
			(enabled no)
			(sheetname "")
		)
		(fill
			(thermal_gap 0.5)
			(thermal_bridge_width 0.5)
			(island_removal_mode 0)
		)
		(polygon
			(pts
				(arc
					(start 5.59054 -317.135764)
					(mid 5.080127 -316.62497)
					(end 4.56946 -317.13551)
				)
				(arc
					(start 4.56946 -317.94831)
					(mid 5.08 -318.45885)
					(end 5.59054 -317.94831)
				)
				(xy 5.59054 -317.815214) (xy 5.347716 -317.815214)
				(arc
					(start 5.323586 -317.839598)
					(mid 4.891383 -318.136927)
					(end 5.188712 -317.704724)
				)
				(xy 5.268976 -317.624714) (xy 5.59054 -317.624714) (xy 5.59054 -317.459614) (xy 5.269484 -317.459614)
				(arc
					(start 5.188712 -317.379096)
					(mid 4.891383 -316.946893)
					(end 5.323586 -317.244222)
				)
				(xy 5.348224 -317.269114) (xy 5.59054 -317.269114)
			)
		)
	)
	(zone
		(layer "In2.Cu")
		(hatch none 0.5)
		(connect_pads
			(clearance 0)
		)
		(min_thickness 0.25)
		(keepout
			(tracks not_allowed)
			(vias allowed)
			(pads allowed)
			(copperpour not_allowed)
			(footprints allowed)
		)
		(placement
			(enabled no)
			(sheetname "")
		)
		(fill
			(thermal_gap 0.5)
			(thermal_bridge_width 0.5)
			(island_removal_mode 0)
		)
		(polygon
			(pts
				(arc
					(start 5.59054 -163.935664)
					(mid 5.080127 -163.42487)
					(end 4.56946 -163.93541)
				)
				(arc
					(start 4.56946 -164.74821)
					(mid 5.08 -165.25875)
					(end 5.59054 -164.74821)
				)
				(xy 5.59054 -164.615114) (xy 5.347716 -164.615114)
				(arc
					(start 5.323586 -164.639498)
					(mid 4.891383 -164.936827)
					(end 5.188712 -164.504624)
				)
				(xy 5.268976 -164.424614) (xy 5.59054 -164.424614) (xy 5.59054 -164.259514) (xy 5.269484 -164.259514)
				(arc
					(start 5.188712 -164.178996)
					(mid 4.891383 -163.746793)
					(end 5.323586 -164.044122)
				)
				(xy 5.348224 -164.069014) (xy 5.59054 -164.069014)
			)
		)
	)
	(zone
		(net "GND")
		(layer "In2.Cu")
		(hatch none 0.5)
		(connect_pads
			(clearance 0.5)
		)
		(min_thickness 0.25)
		(fill yes
			(thermal_gap 0.5)
			(thermal_bridge_width 0.5)
			(island_removal_mode 0)
		)
		(polygon
			(pts
				(arc
					(start 0.999998 -0.763016)
					(mid 0.832426 -0.832426)
					(end 0.763016 -0.999998)
				)
				(xy 0.763016 -186.379104)
				(arc
					(start 4.299966 -186.379104)
					(mid 6.262878 -188.342016)
					(end 4.299966 -190.304928)
				)
				(xy 0.763016 -190.304928) (xy 0.763016 -312.379106)
				(arc
					(start 4.299966 -312.379106)
					(mid 6.262878 -314.342018)
					(end 4.299966 -316.30493)
				)
				(xy 0.763016 -316.30493) (xy 0.763016 -418.378894)
				(arc
					(start 4.299966 -418.378894)
					(mid 6.263132 -420.34206)
					(end 4.299966 -422.304972)
				)
				(xy 0.763016 -422.304972)
				(arc
					(start 0.763016 -505.000006)
					(mid 0.832426 -505.167578)
					(end 0.999998 -505.236988)
				)
				(arc
					(start 262.50011 -505.236988)
					(mid 262.667682 -505.167578)
					(end 262.737092 -505.000006)
				)
				(xy 262.737092 -428.396146) (xy 262.18388 -427.842934)
				(arc
					(start 261.2898 -427.842934)
					(mid 259.704685 -427.275145)
					(end 259.136896 -425.69003)
				)
				(xy 259.136896 -411.80131) (xy 258.583684 -411.248098)
				(arc
					(start 252.394974 -411.248098)
					(mid 251.097034 -409.950158)
					(end 252.394974 -408.651964)
				)
				(xy 258.583684 -408.651964) (xy 259.136896 -408.098752)
				(arc
					(start 259.136896 -364.309914)
					(mid 259.726596 -362.74671)
					(end 261.2898 -362.15701)
				)
				(xy 262.18388 -362.15701) (xy 262.737092 -361.603798) (xy 262.737092 -185.17362) (xy 261.468108 -185.17362)
				(xy 261.468108 -360.888026)
				(arc
					(start 261.2898 -360.888026)
					(mid 258.870234 -361.890348)
					(end 257.867912 -364.309914)
				)
				(xy 257.867912 -407.38298)
				(arc
					(start 252.394974 -407.38298)
					(mid 249.827796 -409.950158)
					(end 252.394974 -412.517082)
				)
				(xy 257.867912 -412.517082)
				(arc
					(start 257.867912 -425.69003)
					(mid 258.87016 -428.10967)
					(end 261.2898 -429.111918)
				)
				(xy 261.468108 -429.111918) (xy 261.468108 -503.968004) (xy 2.032 -503.968004) (xy 2.032 -477.969834)
				(xy 1.48336 -477.421194) (xy 1.48336 -477.158812) (xy 2.032 -476.610172) (xy 2.032 -472.23807) (xy 1.361186 -471.567256)
				(xy 1.361186 -463.904838) (xy 1.361186 -463.434938) (xy 3.1496 -461.646524) (xy 3.443732 -461.646524)
				(xy 3.569208 -461.772) (xy 6.59638 -461.772) (xy 7.507732 -460.860648) (xy 9.877298 -460.860648)
				(xy 10.217658 -460.520288) (xy 10.217658 -458.325728) (xy 4.445 -452.55307)
				(arc
					(start 4.445 -423.570654)
					(mid 7.531443 -420.405446)
					(end 4.572 -417.12134)
				)
				(arc
					(start 4.572 -317.562484)
					(mid 7.532134 -314.342018)
					(end 4.572 -311.121552)
				)
				(xy 4.572 -251.079) (xy 5.715 -249.936) (xy 5.715 -237.236) (xy 4.572 -236.093)
				(arc
					(start 4.572 -191.562482)
					(mid 7.526625 -188.526615)
					(end 4.937506 -185.17362)
				)
				(xy 4.572 -185.17362) (xy 4.572 -150.368) (xy 2.032 -147.828) (xy 2.032 -2.032) (xy 261.468108 -2.032)
				(xy 261.468108 -185.04662) (xy 262.737092 -185.04662)
				(arc
					(start 262.737092 -0.999998)
					(mid 262.667682 -0.832426)
					(end 262.50011 -0.763016)
				)
			)
		)
	)
	(zone
		(net "P3V3")
		(layer "In2.Cu")
		(hatch none 0.5)
		(connect_pads
			(clearance 0.5)
		)
		(min_thickness 0.25)
		(fill yes
			(thermal_gap 0.5)
			(thermal_bridge_width 0.5)
			(island_removal_mode 0)
		)
		(polygon
			(pts
				(xy 17.8308 -341.0458) (xy 24.8412 -341.0458) (xy 25.4 -340.487) (xy 25.4 -338.709) (xy 25.273 -338.582)
				(xy 24.13 -338.582) (xy 21.59 -336.042) (xy 21.59 -322.326) (xy 24.003 -319.913) (xy 75.057 -319.913)
				(xy 75.692 -319.278) (xy 75.692 -314.579) (xy 74.168 -313.055) (xy 45.72 -313.055) (xy 41.148 -308.483)
				(xy 39.751 -308.483) (xy 35.179 -313.055) (xy 21.844 -313.055) (xy 16.637 -318.262) (xy 16.637 -339.852)
			)
		)
	)
	(zone
		(layer "In2.Cu")
		(hatch none 0.5)
		(connect_pads
			(clearance 0)
		)
		(min_thickness 0.25)
		(keepout
			(tracks not_allowed)
			(vias allowed)
			(pads allowed)
			(copperpour not_allowed)
			(footprints allowed)
		)
		(placement
			(enabled no)
			(sheetname "")
		)
		(fill
			(thermal_gap 0.5)
			(thermal_bridge_width 0.5)
			(island_removal_mode 0)
		)
		(polygon
			(pts
				(arc
					(start 25.88514 -13.67663)
					(mid 25.273127 -13.064236)
					(end 24.66086 -13.676376)
				)
				(arc
					(start 24.66086 -14.793976)
					(mid 25.273 -15.406116)
					(end 25.88514 -14.793976)
				)
				(xy 25.88514 -14.508226) (xy 25.69337 -14.508226)
				(arc
					(start 25.516586 -14.685264)
					(mid 25.084383 -14.982593)
					(end 25.381712 -14.55039)
				)
				(xy 25.61463 -14.317726) (xy 25.88514 -14.317726) (xy 25.88514 -14.152626) (xy 25.61463 -14.152626)
				(arc
					(start 25.381712 -13.919962)
					(mid 25.084383 -13.487759)
					(end 25.516586 -13.785088)
				)
				(xy 25.69337 -13.962126) (xy 25.88514 -13.962126)
			)
		)
	)
	(zone
		(layer "In2.Cu")
		(hatch none 0.5)
		(connect_pads
			(clearance 0)
		)
		(min_thickness 0.25)
		(keepout
			(tracks not_allowed)
			(vias allowed)
			(pads allowed)
			(copperpour not_allowed)
			(footprints allowed)
		)
		(placement
			(enabled no)
			(sheetname "")
		)
		(fill
			(thermal_gap 0.5)
			(thermal_bridge_width 0.5)
			(island_removal_mode 0)
		)
		(polygon
			(pts
				(arc
					(start 5.59054 -231.935782)
					(mid 5.080127 -231.424988)
					(end 4.56946 -231.935528)
				)
				(arc
					(start 4.56946 -232.748328)
					(mid 5.08 -233.258868)
					(end 5.59054 -232.748328)
				)
				(xy 5.59054 -232.615232) (xy 5.347716 -232.615232)
				(arc
					(start 5.323586 -232.639616)
					(mid 4.891383 -232.936945)
					(end 5.188712 -232.504742)
				)
				(xy 5.268976 -232.424732) (xy 5.59054 -232.424732) (xy 5.59054 -232.259632) (xy 5.269484 -232.259632)
				(arc
					(start 5.188712 -232.179114)
					(mid 4.891383 -231.746911)
					(end 5.323586 -232.04424)
				)
				(xy 5.348224 -232.069132) (xy 5.59054 -232.069132)
			)
		)
	)
	(zone
		(layer "In2.Cu")
		(hatch none 0.5)
		(connect_pads
			(clearance 0)
		)
		(min_thickness 0.25)
		(keepout
			(tracks not_allowed)
			(vias allowed)
			(pads allowed)
			(copperpour not_allowed)
			(footprints allowed)
		)
		(placement
			(enabled no)
			(sheetname "")
		)
		(fill
			(thermal_gap 0.5)
			(thermal_bridge_width 0.5)
			(island_removal_mode 0)
		)
		(polygon
			(pts
				(arc
					(start 5.59054 -320.335656)
					(mid 5.080127 -319.824862)
					(end 4.56946 -320.335402)
				)
				(arc
					(start 4.56946 -321.148202)
					(mid 5.08 -321.658742)
					(end 5.59054 -321.148202)
				)
				(xy 5.59054 -321.015106) (xy 5.347716 -321.015106)
				(arc
					(start 5.323586 -321.03949)
					(mid 4.891383 -321.336819)
					(end 5.188712 -320.904616)
				)
				(xy 5.268976 -320.824606) (xy 5.59054 -320.824606) (xy 5.59054 -320.659506) (xy 5.269484 -320.659506)
				(arc
					(start 5.188712 -320.578988)
					(mid 4.891383 -320.146785)
					(end 5.323586 -320.444114)
				)
				(xy 5.348224 -320.469006) (xy 5.59054 -320.469006)
			)
		)
	)
	(zone
		(layer "In2.Cu")
		(hatch none 0.5)
		(connect_pads
			(clearance 0)
		)
		(min_thickness 0.25)
		(keepout
			(tracks not_allowed)
			(vias allowed)
			(pads allowed)
			(copperpour not_allowed)
			(footprints allowed)
		)
		(placement
			(enabled no)
			(sheetname "")
		)
		(fill
			(thermal_gap 0.5)
			(thermal_bridge_width 0.5)
			(island_removal_mode 0)
		)
		(polygon
			(pts
				(arc
					(start 37.33927 -486.43159)
					(mid 36.727257 -485.819196)
					(end 36.11499 -486.431336)
				)
				(xy 36.11499 -486.71734) (xy 36.306506 -486.71734)
				(arc
					(start 36.483544 -486.540048)
					(mid 36.915747 -486.242719)
					(end 36.618418 -486.674922)
				)
				(xy 36.385246 -486.90784) (xy 36.11499 -486.90784) (xy 36.11499 -487.07294) (xy 36.385754 -487.07294)
				(arc
					(start 36.618418 -487.30535)
					(mid 36.915747 -487.737553)
					(end 36.483544 -487.440224)
				)
				(xy 36.307014 -487.26344) (xy 36.11499 -487.26344)
				(arc
					(start 36.11499 -487.548936)
					(mid 36.72713 -488.161076)
					(end 37.33927 -487.548936)
				)
			)
		)
	)
	(zone
		(layer "In2.Cu")
		(hatch none 0.5)
		(connect_pads
			(clearance 0)
		)
		(min_thickness 0.25)
		(keepout
			(tracks not_allowed)
			(vias allowed)
			(pads allowed)
			(copperpour not_allowed)
			(footprints allowed)
		)
		(placement
			(enabled no)
			(sheetname "")
		)
		(fill
			(thermal_gap 0.5)
			(thermal_bridge_width 0.5)
			(island_removal_mode 0)
		)
		(polygon
			(pts
				(arc
					(start 5.59054 -416.735514)
					(mid 5.080127 -416.22472)
					(end 4.56946 -416.73526)
				)
				(arc
					(start 4.56946 -417.54806)
					(mid 5.08 -418.0586)
					(end 5.59054 -417.54806)
				)
				(xy 5.59054 -417.414964) (xy 5.347716 -417.414964)
				(arc
					(start 5.323586 -417.439348)
					(mid 4.891383 -417.736677)
					(end 5.188712 -417.304474)
				)
				(xy 5.268976 -417.224464) (xy 5.59054 -417.224464) (xy 5.59054 -417.059364) (xy 5.269484 -417.059364)
				(arc
					(start 5.188712 -416.978846)
					(mid 4.891383 -416.546643)
					(end 5.323586 -416.843972)
				)
				(xy 5.348224 -416.868864) (xy 5.59054 -416.868864)
			)
		)
	)
	(zone
		(layer "In2.Cu")
		(hatch none 0.5)
		(connect_pads
			(clearance 0)
		)
		(min_thickness 0.25)
		(keepout
			(tracks not_allowed)
			(vias allowed)
			(pads allowed)
			(copperpour not_allowed)
			(footprints allowed)
		)
		(placement
			(enabled no)
			(sheetname "")
		)
		(fill
			(thermal_gap 0.5)
			(thermal_bridge_width 0.5)
			(island_removal_mode 0)
		)
		(polygon
			(pts
				(arc
					(start 5.59054 -335.535778)
					(mid 5.080127 -335.024984)
					(end 4.56946 -335.535524)
				)
				(arc
					(start 4.56946 -336.348324)
					(mid 5.08 -336.858864)
					(end 5.59054 -336.348324)
				)
				(xy 5.59054 -336.215228) (xy 5.347716 -336.215228)
				(arc
					(start 5.323586 -336.239612)
					(mid 4.891383 -336.536941)
					(end 5.188712 -336.104738)
				)
				(xy 5.268976 -336.024728) (xy 5.59054 -336.024728) (xy 5.59054 -335.859628) (xy 5.269484 -335.859628)
				(arc
					(start 5.188712 -335.77911)
					(mid 4.891383 -335.346907)
					(end 5.323586 -335.644236)
				)
				(xy 5.348224 -335.669128) (xy 5.59054 -335.669128)
			)
		)
	)
	(zone
		(layer "In2.Cu")
		(hatch none 0.5)
		(connect_pads
			(clearance 0)
		)
		(min_thickness 0.25)
		(keepout
			(tracks not_allowed)
			(vias allowed)
			(pads allowed)
			(copperpour not_allowed)
			(footprints allowed)
		)
		(placement
			(enabled no)
			(sheetname "")
		)
		(fill
			(thermal_gap 0.5)
			(thermal_bridge_width 0.5)
			(island_removal_mode 0)
		)
		(polygon
			(pts
				(arc
					(start 5.59054 -426.335444)
					(mid 5.080127 -425.82465)
					(end 4.56946 -426.33519)
				)
				(arc
					(start 4.56946 -427.14799)
					(mid 5.08 -427.65853)
					(end 5.59054 -427.14799)
				)
				(xy 5.59054 -427.014894) (xy 5.347716 -427.014894)
				(arc
					(start 5.323586 -427.039278)
					(mid 4.891383 -427.336607)
					(end 5.188712 -426.904404)
				)
				(xy 5.268976 -426.824394) (xy 5.59054 -426.824394) (xy 5.59054 -426.659294) (xy 5.269484 -426.659294)
				(arc
					(start 5.188712 -426.578776)
					(mid 4.891383 -426.146573)
					(end 5.323586 -426.443902)
				)
				(xy 5.348224 -426.468794) (xy 5.59054 -426.468794)
			)
		)
	)
	(zone
		(layer "In2.Cu")
		(hatch none 0.5)
		(connect_pads
			(clearance 0)
		)
		(min_thickness 0.25)
		(keepout
			(tracks not_allowed)
			(vias allowed)
			(pads allowed)
			(copperpour not_allowed)
			(footprints allowed)
		)
		(placement
			(enabled no)
			(sheetname "")
		)
		(fill
			(thermal_gap 0.5)
			(thermal_bridge_width 0.5)
			(island_removal_mode 0)
		)
		(polygon
			(pts
				(arc
					(start 5.59054 -228.735636)
					(mid 5.080127 -228.224842)
					(end 4.56946 -228.735382)
				)
				(arc
					(start 4.56946 -229.548182)
					(mid 5.08 -230.058722)
					(end 5.59054 -229.548182)
				)
				(xy 5.59054 -229.415086) (xy 5.347716 -229.415086)
				(arc
					(start 5.323586 -229.43947)
					(mid 4.891383 -229.736799)
					(end 5.188712 -229.304596)
				)
				(xy 5.268976 -229.224586) (xy 5.59054 -229.224586) (xy 5.59054 -229.059486) (xy 5.269484 -229.059486)
				(arc
					(start 5.188712 -228.978968)
					(mid 4.891383 -228.546765)
					(end 5.323586 -228.844094)
				)
				(xy 5.348224 -228.868986) (xy 5.59054 -228.868986)
			)
		)
	)
	(zone
		(layer "In2.Cu")
		(hatch none 0.5)
		(connect_pads
			(clearance 0)
		)
		(min_thickness 0.25)
		(keepout
			(tracks not_allowed)
			(vias allowed)
			(pads allowed)
			(copperpour not_allowed)
			(footprints allowed)
		)
		(placement
			(enabled no)
			(sheetname "")
		)
		(fill
			(thermal_gap 0.5)
			(thermal_bridge_width 0.5)
			(island_removal_mode 0)
		)
		(polygon
			(pts
				(arc
					(start 5.59054 -444.735204)
					(mid 5.08 -444.224664)
					(end 4.56946 -444.735204)
				)
				(arc
					(start 4.56946 -445.54775)
					(mid 5.079873 -446.058544)
					(end 5.59054 -445.548004)
				)
				(xy 5.59054 -445.414908) (xy 5.347716 -445.414908)
				(arc
					(start 5.323586 -445.439292)
					(mid 4.891383 -445.736621)
					(end 5.188712 -445.304418)
				)
				(xy 5.268976 -445.224408) (xy 5.59054 -445.224408) (xy 5.59054 -445.059308) (xy 5.269484 -445.059308)
				(arc
					(start 5.188712 -444.97879)
					(mid 4.891383 -444.546587)
					(end 5.323586 -444.843916)
				)
				(xy 5.348224 -444.868808) (xy 5.59054 -444.868808)
			)
		)
	)
	(zone
		(layer "In2.Cu")
		(hatch none 0.5)
		(connect_pads
			(clearance 0)
		)
		(min_thickness 0.25)
		(keepout
			(tracks not_allowed)
			(vias allowed)
			(pads allowed)
			(copperpour not_allowed)
			(footprints allowed)
		)
		(placement
			(enabled no)
			(sheetname "")
		)
		(fill
			(thermal_gap 0.5)
			(thermal_bridge_width 0.5)
			(island_removal_mode 0)
		)
		(polygon
			(pts
				(arc
					(start 25.88514 -23.25116)
					(mid 25.273 -22.63902)
					(end 24.66086 -23.25116)
				)
				(arc
					(start 24.66086 -24.368506)
					(mid 25.272873 -24.9809)
					(end 25.88514 -24.36876)
				)
				(xy 25.88514 -24.082756) (xy 25.693624 -24.082756)
				(arc
					(start 25.516586 -24.260048)
					(mid 25.084383 -24.557377)
					(end 25.381712 -24.125174)
				)
				(xy 25.614884 -23.892256) (xy 25.88514 -23.892256) (xy 25.88514 -23.727156) (xy 25.614376 -23.727156)
				(arc
					(start 25.381712 -23.494746)
					(mid 25.084383 -23.062543)
					(end 25.516586 -23.359872)
				)
				(xy 25.693116 -23.536656) (xy 25.88514 -23.536656)
			)
		)
	)
	(zone
		(layer "In2.Cu")
		(hatch none 0.5)
		(connect_pads
			(clearance 0)
		)
		(min_thickness 0.25)
		(keepout
			(tracks not_allowed)
			(vias allowed)
			(pads allowed)
			(copperpour not_allowed)
			(footprints allowed)
		)
		(placement
			(enabled no)
			(sheetname "")
		)
		(fill
			(thermal_gap 0.5)
			(thermal_bridge_width 0.5)
			(island_removal_mode 0)
		)
		(polygon
			(pts
				(arc
					(start 5.59054 -170.335702)
					(mid 5.080127 -169.824908)
					(end 4.56946 -170.335448)
				)
				(arc
					(start 4.56946 -171.148248)
					(mid 5.08 -171.658788)
					(end 5.59054 -171.148248)
				)
				(xy 5.59054 -171.015152) (xy 5.347716 -171.015152)
				(arc
					(start 5.323586 -171.039536)
					(mid 4.891383 -171.336865)
					(end 5.188712 -170.904662)
				)
				(xy 5.268976 -170.824652) (xy 5.59054 -170.824652) (xy 5.59054 -170.659552) (xy 5.269484 -170.659552)
				(arc
					(start 5.188712 -170.579034)
					(mid 4.891383 -170.146831)
					(end 5.323586 -170.44416)
				)
				(xy 5.348224 -170.469052) (xy 5.59054 -170.469052)
			)
		)
	)
	(zone
		(layer "In2.Cu")
		(hatch none 0.5)
		(connect_pads
			(clearance 0)
		)
		(min_thickness 0.25)
		(keepout
			(tracks not_allowed)
			(vias allowed)
			(pads allowed)
			(copperpour not_allowed)
			(footprints allowed)
		)
		(placement
			(enabled no)
			(sheetname "")
		)
		(fill
			(thermal_gap 0.5)
			(thermal_bridge_width 0.5)
			(island_removal_mode 0)
		)
		(polygon
			(pts
				(arc
					(start 222.339154 -285.231586)
					(mid 221.727141 -284.619192)
					(end 221.114874 -285.231332)
				)
				(xy 221.114874 -285.517082) (xy 221.306644 -285.517082)
				(arc
					(start 221.483428 -285.340044)
					(mid 221.915631 -285.042715)
					(end 221.618302 -285.474918)
				)
				(xy 221.385384 -285.707582) (xy 221.114874 -285.707582) (xy 221.114874 -285.872682) (xy 221.385384 -285.872682)
				(arc
					(start 221.618302 -286.105346)
					(mid 221.915631 -286.537549)
					(end 221.483428 -286.24022)
				)
				(xy 221.306644 -286.063182) (xy 221.114874 -286.063182)
				(arc
					(start 221.114874 -286.348932)
					(mid 221.727014 -286.961072)
					(end 222.339154 -286.348932)
				)
			)
		)
	)
	(zone
		(layer "In2.Cu")
		(hatch none 0.5)
		(connect_pads
			(clearance 0)
		)
		(min_thickness 0.25)
		(keepout
			(tracks not_allowed)
			(vias allowed)
			(pads allowed)
			(copperpour not_allowed)
			(footprints allowed)
		)
		(placement
			(enabled no)
			(sheetname "")
		)
		(fill
			(thermal_gap 0.5)
			(thermal_bridge_width 0.5)
			(island_removal_mode 0)
		)
		(polygon
			(pts
				(arc
					(start 25.88514 -345.05138)
					(mid 25.273127 -344.438986)
					(end 24.66086 -345.051126)
				)
				(arc
					(start 24.66086 -346.168726)
					(mid 25.273 -346.780866)
					(end 25.88514 -346.168726)
				)
				(xy 25.88514 -345.94165) (xy 25.634696 -345.94165)
				(arc
					(start 25.516586 -346.060014)
					(mid 25.084383 -346.357343)
					(end 25.381712 -345.92514)
				)
				(xy 25.555956 -345.75115) (xy 25.88514 -345.75115) (xy 25.88514 -345.58605) (xy 25.673304 -345.58605)
				(arc
					(start 25.381712 -345.294712)
					(mid 25.084383 -344.862509)
					(end 25.516586 -345.159838)
				)
				(xy 25.752044 -345.39555) (xy 25.88514 -345.39555)
			)
		)
	)
	(zone
		(layer "In2.Cu")
		(hatch none 0.5)
		(connect_pads
			(clearance 0)
		)
		(min_thickness 0.25)
		(keepout
			(tracks not_allowed)
			(vias allowed)
			(pads allowed)
			(copperpour not_allowed)
			(footprints allowed)
		)
		(placement
			(enabled no)
			(sheetname "")
		)
		(fill
			(thermal_gap 0.5)
			(thermal_bridge_width 0.5)
			(island_removal_mode 0)
		)
		(polygon
			(pts
				(arc
					(start 37.33927 -388.231634)
					(mid 36.727257 -387.61924)
					(end 36.11499 -388.23138)
				)
				(xy 36.11499 -388.51713) (xy 36.30676 -388.51713)
				(arc
					(start 36.483544 -388.340092)
					(mid 36.915747 -388.042763)
					(end 36.618418 -388.474966)
				)
				(xy 36.3855 -388.70763) (xy 36.11499 -388.70763) (xy 36.11499 -388.87273) (xy 36.3855 -388.87273)
				(arc
					(start 36.618418 -389.105394)
					(mid 36.915747 -389.537597)
					(end 36.483544 -389.240268)
				)
				(xy 36.30676 -389.06323) (xy 36.11499 -389.06323)
				(arc
					(start 36.11499 -389.34898)
					(mid 36.72713 -389.96112)
					(end 37.33927 -389.34898)
				)
			)
		)
	)
	(zone
		(layer "In2.Cu")
		(hatch none 0.5)
		(connect_pads
			(clearance 0)
		)
		(min_thickness 0.25)
		(keepout
			(tracks not_allowed)
			(vias allowed)
			(pads allowed)
			(copperpour not_allowed)
			(footprints allowed)
		)
		(placement
			(enabled no)
			(sheetname "")
		)
		(fill
			(thermal_gap 0.5)
			(thermal_bridge_width 0.5)
			(island_removal_mode 0)
		)
		(polygon
			(pts
				(arc
					(start 222.339154 -486.43159)
					(mid 221.727141 -485.819196)
					(end 221.114874 -486.431336)
				)
				(xy 221.114874 -486.71734) (xy 221.30639 -486.71734)
				(arc
					(start 221.483428 -486.540048)
					(mid 221.915631 -486.242719)
					(end 221.618302 -486.674922)
				)
				(xy 221.38513 -486.90784) (xy 221.114874 -486.90784) (xy 221.114874 -487.07294) (xy 221.385638 -487.07294)
				(arc
					(start 221.618302 -487.30535)
					(mid 221.915631 -487.737553)
					(end 221.483428 -487.440224)
				)
				(xy 221.306898 -487.26344) (xy 221.114874 -487.26344)
				(arc
					(start 221.114874 -487.548936)
					(mid 221.727014 -488.161076)
					(end 222.339154 -487.548936)
				)
			)
		)
	)
	(zone
		(layer "In2.Cu")
		(hatch none 0.5)
		(connect_pads
			(clearance 0)
		)
		(min_thickness 0.25)
		(keepout
			(tracks not_allowed)
			(vias allowed)
			(pads allowed)
			(copperpour not_allowed)
			(footprints allowed)
		)
		(placement
			(enabled no)
			(sheetname "")
		)
		(fill
			(thermal_gap 0.5)
			(thermal_bridge_width 0.5)
			(island_removal_mode 0)
		)
		(polygon
			(pts
				(arc
					(start 25.88514 -126.251208)
					(mid 25.273 -125.639068)
					(end 24.66086 -126.251208)
				)
				(arc
					(start 24.66086 -127.368554)
					(mid 25.272873 -127.980948)
					(end 25.88514 -127.368808)
				)
				(xy 25.88514 -127.082804) (xy 25.693624 -127.082804)
				(arc
					(start 25.516586 -127.260096)
					(mid 25.084383 -127.557425)
					(end 25.381712 -127.125222)
				)
				(xy 25.614884 -126.892304) (xy 25.88514 -126.892304) (xy 25.88514 -126.727204) (xy 25.614376 -126.727204)
				(arc
					(start 25.381712 -126.494794)
					(mid 25.084383 -126.062591)
					(end 25.516586 -126.35992)
				)
				(xy 25.693116 -126.536704) (xy 25.88514 -126.536704)
			)
		)
	)
	(zone
		(layer "In2.Cu")
		(hatch none 0.5)
		(connect_pads
			(clearance 0)
		)
		(min_thickness 0.25)
		(keepout
			(tracks not_allowed)
			(vias allowed)
			(pads allowed)
			(copperpour not_allowed)
			(footprints allowed)
		)
		(placement
			(enabled no)
			(sheetname "")
		)
		(fill
			(thermal_gap 0.5)
			(thermal_bridge_width 0.5)
			(island_removal_mode 0)
		)
		(polygon
			(pts
				(arc
					(start 5.59054 -212.735668)
					(mid 5.080127 -212.224874)
					(end 4.56946 -212.735414)
				)
				(arc
					(start 4.56946 -213.548214)
					(mid 5.08 -214.058754)
					(end 5.59054 -213.548214)
				)
				(xy 5.59054 -213.415118) (xy 5.347716 -213.415118)
				(arc
					(start 5.323586 -213.439502)
					(mid 4.891383 -213.736831)
					(end 5.188712 -213.304628)
				)
				(xy 5.268976 -213.224618) (xy 5.59054 -213.224618) (xy 5.59054 -213.059518) (xy 5.269484 -213.059518)
				(arc
					(start 5.188712 -212.979)
					(mid 4.891383 -212.546797)
					(end 5.323586 -212.844126)
				)
				(xy 5.348224 -212.869018) (xy 5.59054 -212.869018)
			)
		)
	)
	(zone
		(layer "In2.Cu")
		(hatch none 0.5)
		(connect_pads
			(clearance 0)
		)
		(min_thickness 0.25)
		(keepout
			(tracks not_allowed)
			(vias allowed)
			(pads allowed)
			(copperpour not_allowed)
			(footprints allowed)
		)
		(placement
			(enabled no)
			(sheetname "")
		)
		(fill
			(thermal_gap 0.5)
			(thermal_bridge_width 0.5)
			(island_removal_mode 0)
		)
		(polygon
			(pts
				(arc
					(start 25.88514 -36.050982)
					(mid 25.273 -35.438842)
					(end 24.66086 -36.050982)
				)
				(arc
					(start 24.66086 -37.168328)
					(mid 25.272873 -37.780722)
					(end 25.88514 -37.168582)
				)
				(xy 25.88514 -36.882832) (xy 25.69337 -36.882832)
				(arc
					(start 25.516586 -37.05987)
					(mid 25.084383 -37.357199)
					(end 25.381712 -36.924996)
				)
				(xy 25.61463 -36.692332) (xy 25.88514 -36.692332) (xy 25.88514 -36.527232) (xy 25.61463 -36.527232)
				(arc
					(start 25.381712 -36.294568)
					(mid 25.084383 -35.862365)
					(end 25.516586 -36.159694)
				)
				(xy 25.69337 -36.336732) (xy 25.88514 -36.336732)
			)
		)
	)
	(zone
		(layer "In2.Cu")
		(hatch none 0.5)
		(connect_pads
			(clearance 0)
		)
		(min_thickness 0.25)
		(keepout
			(tracks not_allowed)
			(vias allowed)
			(pads allowed)
			(copperpour not_allowed)
			(footprints allowed)
		)
		(placement
			(enabled no)
			(sheetname "")
		)
		(fill
			(thermal_gap 0.5)
			(thermal_bridge_width 0.5)
			(island_removal_mode 0)
		)
		(polygon
			(pts
				(arc
					(start 5.59054 -280.335736)
					(mid 5.080127 -279.824942)
					(end 4.56946 -280.335482)
				)
				(arc
					(start 4.56946 -281.148282)
					(mid 5.08 -281.658822)
					(end 5.59054 -281.148282)
				)
				(xy 5.59054 -281.015186) (xy 5.347716 -281.015186)
				(arc
					(start 5.323586 -281.03957)
					(mid 4.891383 -281.336899)
					(end 5.188712 -280.904696)
				)
				(xy 5.268976 -280.824686) (xy 5.59054 -280.824686) (xy 5.59054 -280.659586) (xy 5.269484 -280.659586)
				(arc
					(start 5.188712 -280.579068)
					(mid 4.891383 -280.146865)
					(end 5.323586 -280.444194)
				)
				(xy 5.348224 -280.469086) (xy 5.59054 -280.469086)
			)
		)
	)
	(zone
		(layer "In2.Cu")
		(hatch none 0.5)
		(connect_pads
			(clearance 0)
		)
		(min_thickness 0.25)
		(keepout
			(tracks not_allowed)
			(vias allowed)
			(pads allowed)
			(copperpour not_allowed)
			(footprints allowed)
		)
		(placement
			(enabled no)
			(sheetname "")
		)
		(fill
			(thermal_gap 0.5)
			(thermal_bridge_width 0.5)
			(island_removal_mode 0)
		)
		(polygon
			(pts
				(arc
					(start 37.33927 -56.831484)
					(mid 36.727257 -56.21909)
					(end 36.11499 -56.83123)
				)
				(xy 36.11499 -57.11698) (xy 36.30676 -57.11698)
				(arc
					(start 36.483544 -56.939942)
					(mid 36.915747 -56.642613)
					(end 36.618418 -57.074816)
				)
				(xy 36.3855 -57.30748) (xy 36.11499 -57.30748) (xy 36.11499 -57.47258) (xy 36.3855 -57.47258)
				(arc
					(start 36.618418 -57.705244)
					(mid 36.915747 -58.137447)
					(end 36.483544 -57.840118)
				)
				(xy 36.30676 -57.66308) (xy 36.11499 -57.66308)
				(arc
					(start 36.11499 -57.94883)
					(mid 36.72713 -58.56097)
					(end 37.33927 -57.94883)
				)
			)
		)
	)
	(zone
		(layer "In2.Cu")
		(hatch none 0.5)
		(connect_pads
			(clearance 0)
		)
		(min_thickness 0.25)
		(keepout
			(tracks not_allowed)
			(vias allowed)
			(pads allowed)
			(copperpour not_allowed)
			(footprints allowed)
		)
		(placement
			(enabled no)
			(sheetname "")
		)
		(fill
			(thermal_gap 0.5)
			(thermal_bridge_width 0.5)
			(island_removal_mode 0)
		)
		(polygon
			(pts
				(arc
					(start 5.59054 -173.535594)
					(mid 5.080127 -173.0248)
					(end 4.56946 -173.53534)
				)
				(arc
					(start 4.56946 -174.34814)
					(mid 5.08 -174.85868)
					(end 5.59054 -174.34814)
				)
				(xy 5.59054 -174.215298) (xy 5.347462 -174.215298)
				(arc
					(start 5.323586 -174.239428)
					(mid 4.891383 -174.536757)
					(end 5.188712 -174.104554)
				)
				(xy 5.268722 -174.024798) (xy 5.59054 -174.024798) (xy 5.59054 -173.859698) (xy 5.269738 -173.859698)
				(arc
					(start 5.188712 -173.778926)
					(mid 4.891383 -173.346723)
					(end 5.323586 -173.644052)
				)
				(xy 5.348478 -173.669198) (xy 5.59054 -173.669198)
			)
		)
	)
	(zone
		(layer "In2.Cu")
		(hatch none 0.5)
		(connect_pads
			(clearance 0)
		)
		(min_thickness 0.25)
		(keepout
			(tracks not_allowed)
			(vias allowed)
			(pads allowed)
			(copperpour not_allowed)
			(footprints allowed)
		)
		(placement
			(enabled no)
			(sheetname "")
		)
		(fill
			(thermal_gap 0.5)
			(thermal_bridge_width 0.5)
			(island_removal_mode 0)
		)
		(polygon
			(pts
				(arc
					(start 222.339154 -280.431494)
					(mid 221.727141 -279.8191)
					(end 221.114874 -280.43124)
				)
				(xy 221.114874 -280.717244) (xy 221.30639 -280.717244)
				(arc
					(start 221.483428 -280.539952)
					(mid 221.915631 -280.242623)
					(end 221.618302 -280.674826)
				)
				(xy 221.38513 -280.907744) (xy 221.114874 -280.907744) (xy 221.114874 -281.072844) (xy 221.385638 -281.072844)
				(arc
					(start 221.618302 -281.305254)
					(mid 221.915631 -281.737457)
					(end 221.483428 -281.440128)
				)
				(xy 221.306898 -281.263344) (xy 221.114874 -281.263344)
				(arc
					(start 221.114874 -281.54884)
					(mid 221.727014 -282.16098)
					(end 222.339154 -281.54884)
				)
			)
		)
	)
	(zone
		(layer "In2.Cu")
		(hatch none 0.5)
		(connect_pads
			(clearance 0)
		)
		(min_thickness 0.25)
		(keepout
			(tracks not_allowed)
			(vias allowed)
			(pads allowed)
			(copperpour not_allowed)
			(footprints allowed)
		)
		(placement
			(enabled no)
			(sheetname "")
		)
		(fill
			(thermal_gap 0.5)
			(thermal_bridge_width 0.5)
			(island_removal_mode 0)
		)
		(polygon
			(pts
				(arc
					(start 5.59054 -323.535548)
					(mid 5.080127 -323.024754)
					(end 4.56946 -323.535294)
				)
				(arc
					(start 4.56946 -324.348094)
					(mid 5.08 -324.858634)
					(end 5.59054 -324.348094)
				)
				(xy 5.59054 -324.215252) (xy 5.347462 -324.215252)
				(arc
					(start 5.323586 -324.239382)
					(mid 4.891383 -324.536711)
					(end 5.188712 -324.104508)
				)
				(xy 5.268722 -324.024752) (xy 5.59054 -324.024752) (xy 5.59054 -323.859652) (xy 5.269738 -323.859652)
				(arc
					(start 5.188712 -323.77888)
					(mid 4.891383 -323.346677)
					(end 5.323586 -323.644006)
				)
				(xy 5.348478 -323.669152) (xy 5.59054 -323.669152)
			)
		)
	)
	(zone
		(layer "In2.Cu")
		(hatch none 0.5)
		(connect_pads
			(clearance 0)
		)
		(min_thickness 0.25)
		(keepout
			(tracks not_allowed)
			(vias allowed)
			(pads allowed)
			(copperpour not_allowed)
			(footprints allowed)
		)
		(placement
			(enabled no)
			(sheetname "")
		)
		(fill
			(thermal_gap 0.5)
			(thermal_bridge_width 0.5)
			(island_removal_mode 0)
		)
		(polygon
			(pts
				(arc
					(start 5.59054 -299.535596)
					(mid 5.080127 -299.024802)
					(end 4.56946 -299.535342)
				)
				(arc
					(start 4.56946 -300.348142)
					(mid 5.08 -300.858682)
					(end 5.59054 -300.348142)
				)
				(xy 5.59054 -300.2153) (xy 5.347462 -300.2153)
				(arc
					(start 5.323586 -300.23943)
					(mid 4.891383 -300.536759)
					(end 5.188712 -300.104556)
				)
				(xy 5.268722 -300.0248) (xy 5.59054 -300.0248) (xy 5.59054 -299.8597) (xy 5.269738 -299.8597)
				(arc
					(start 5.188712 -299.778928)
					(mid 4.891383 -299.346725)
					(end 5.323586 -299.644054)
				)
				(xy 5.348478 -299.6692) (xy 5.59054 -299.6692)
			)
		)
	)
	(zone
		(layer "In2.Cu")
		(hatch none 0.5)
		(connect_pads
			(clearance 0)
		)
		(min_thickness 0.25)
		(keepout
			(tracks not_allowed)
			(vias allowed)
			(pads allowed)
			(copperpour not_allowed)
			(footprints allowed)
		)
		(placement
			(enabled no)
			(sheetname "")
		)
		(fill
			(thermal_gap 0.5)
			(thermal_bridge_width 0.5)
			(island_removal_mode 0)
		)
		(polygon
			(pts
				(arc
					(start 5.59054 -283.535628)
					(mid 5.080127 -283.024834)
					(end 4.56946 -283.535374)
				)
				(arc
					(start 4.56946 -284.348174)
					(mid 5.08 -284.858714)
					(end 5.59054 -284.348174)
				)
				(xy 5.59054 -284.215332) (xy 5.347462 -284.215332)
				(arc
					(start 5.323586 -284.239462)
					(mid 4.891383 -284.536791)
					(end 5.188712 -284.104588)
				)
				(xy 5.268722 -284.024832) (xy 5.59054 -284.024832) (xy 5.59054 -283.859732) (xy 5.269738 -283.859732)
				(arc
					(start 5.188712 -283.77896)
					(mid 4.891383 -283.346757)
					(end 5.323586 -283.644086)
				)
				(xy 5.348478 -283.669232) (xy 5.59054 -283.669232)
			)
		)
	)
	(zone
		(layer "In2.Cu")
		(hatch none 0.5)
		(connect_pads
			(clearance 0)
		)
		(min_thickness 0.25)
		(keepout
			(tracks not_allowed)
			(vias allowed)
			(pads allowed)
			(copperpour not_allowed)
			(footprints allowed)
		)
		(placement
			(enabled no)
			(sheetname "")
		)
		(fill
			(thermal_gap 0.5)
			(thermal_bridge_width 0.5)
			(island_removal_mode 0)
		)
		(polygon
			(pts
				(arc
					(start 5.59054 -183.135778)
					(mid 5.080127 -182.624984)
					(end 4.56946 -183.135524)
				)
				(arc
					(start 4.56946 -183.948324)
					(mid 5.08 -184.458864)
					(end 5.59054 -183.948324)
				)
				(xy 5.59054 -183.815228) (xy 5.347716 -183.815228)
				(arc
					(start 5.323586 -183.839612)
					(mid 4.891383 -184.136941)
					(end 5.188712 -183.704738)
				)
				(xy 5.268976 -183.624728) (xy 5.59054 -183.624728) (xy 5.59054 -183.459628) (xy 5.269484 -183.459628)
				(arc
					(start 5.188712 -183.37911)
					(mid 4.891383 -182.946907)
					(end 5.323586 -183.244236)
				)
				(xy 5.348224 -183.269128) (xy 5.59054 -183.269128)
			)
		)
	)
	(zone
		(layer "In2.Cu")
		(hatch none 0.5)
		(connect_pads
			(clearance 0)
		)
		(min_thickness 0.25)
		(keepout
			(tracks not_allowed)
			(vias allowed)
			(pads allowed)
			(copperpour not_allowed)
			(footprints allowed)
		)
		(placement
			(enabled no)
			(sheetname "")
		)
		(fill
			(thermal_gap 0.5)
			(thermal_bridge_width 0.5)
			(island_removal_mode 0)
		)
		(polygon
			(pts
				(arc
					(start 25.88514 -430.451514)
					(mid 25.273127 -429.83912)
					(end 24.66086 -430.45126)
				)
				(arc
					(start 24.66086 -431.56886)
					(mid 25.273 -432.181)
					(end 25.88514 -431.56886)
				)
				(xy 25.88514 -431.282856) (xy 25.693624 -431.282856)
				(arc
					(start 25.516586 -431.460148)
					(mid 25.084383 -431.757477)
					(end 25.381712 -431.325274)
				)
				(xy 25.614884 -431.092356) (xy 25.88514 -431.092356) (xy 25.88514 -430.927256) (xy 25.614376 -430.927256)
				(arc
					(start 25.381712 -430.694846)
					(mid 25.084383 -430.262643)
					(end 25.516586 -430.559972)
				)
				(xy 25.693116 -430.736756) (xy 25.88514 -430.736756)
			)
		)
	)
	(zone
		(layer "In2.Cu")
		(hatch none 0.5)
		(connect_pads
			(clearance 0)
		)
		(min_thickness 0.25)
		(keepout
			(tracks not_allowed)
			(vias allowed)
			(pads allowed)
			(copperpour not_allowed)
			(footprints allowed)
		)
		(placement
			(enabled no)
			(sheetname "")
		)
		(fill
			(thermal_gap 0.5)
			(thermal_bridge_width 0.5)
			(island_removal_mode 0)
		)
		(polygon
			(pts
				(arc
					(start 37.33927 -172.631354)
					(mid 36.727257 -172.01896)
					(end 36.11499 -172.6311)
				)
				(xy 36.11499 -172.917104) (xy 36.306506 -172.917104)
				(arc
					(start 36.483544 -172.739812)
					(mid 36.915747 -172.442483)
					(end 36.618418 -172.874686)
				)
				(xy 36.385246 -173.107604) (xy 36.11499 -173.107604) (xy 36.11499 -173.272704) (xy 36.385754 -173.272704)
				(arc
					(start 36.618418 -173.505114)
					(mid 36.915747 -173.937317)
					(end 36.483544 -173.639988)
				)
				(xy 36.307014 -173.463204) (xy 36.11499 -173.463204)
				(arc
					(start 36.11499 -173.7487)
					(mid 36.72713 -174.36084)
					(end 37.33927 -173.7487)
				)
			)
		)
	)
	(zone
		(layer "In2.Cu")
		(hatch none 0.5)
		(connect_pads
			(clearance 0)
		)
		(min_thickness 0.25)
		(keepout
			(tracks not_allowed)
			(vias allowed)
			(pads allowed)
			(copperpour not_allowed)
			(footprints allowed)
		)
		(placement
			(enabled no)
			(sheetname "")
		)
		(fill
			(thermal_gap 0.5)
			(thermal_bridge_width 0.5)
			(island_removal_mode 0)
		)
		(polygon
			(pts
				(arc
					(start 5.59054 -395.135354)
					(mid 5.080127 -394.62456)
					(end 4.56946 -395.1351)
				)
				(arc
					(start 4.56946 -395.9479)
					(mid 5.08 -396.45844)
					(end 5.59054 -395.9479)
				)
				(xy 5.59054 -395.815058) (xy 5.347462 -395.815058)
				(arc
					(start 5.323586 -395.839188)
					(mid 4.891383 -396.136517)
					(end 5.188712 -395.704314)
				)
				(xy 5.268722 -395.624558) (xy 5.59054 -395.624558) (xy 5.59054 -395.459458) (xy 5.269738 -395.459458)
				(arc
					(start 5.188712 -395.378686)
					(mid 4.891383 -394.946483)
					(end 5.323586 -395.243812)
				)
				(xy 5.348478 -395.268958) (xy 5.59054 -395.268958)
			)
		)
	)
	(zone
		(layer "In2.Cu")
		(hatch none 0.5)
		(connect_pads
			(clearance 0)
		)
		(min_thickness 0.25)
		(keepout
			(tracks not_allowed)
			(vias allowed)
			(pads allowed)
			(copperpour not_allowed)
			(footprints allowed)
		)
		(placement
			(enabled no)
			(sheetname "")
		)
		(fill
			(thermal_gap 0.5)
			(thermal_bridge_width 0.5)
			(island_removal_mode 0)
		)
		(polygon
			(pts
				(arc
					(start 37.33927 -285.231586)
					(mid 36.727257 -284.619192)
					(end 36.11499 -285.231332)
				)
				(xy 36.11499 -285.517082) (xy 36.30676 -285.517082)
				(arc
					(start 36.483544 -285.340044)
					(mid 36.915747 -285.042715)
					(end 36.618418 -285.474918)
				)
				(xy 36.3855 -285.707582) (xy 36.11499 -285.707582) (xy 36.11499 -285.872682) (xy 36.3855 -285.872682)
				(arc
					(start 36.618418 -286.105346)
					(mid 36.915747 -286.537549)
					(end 36.483544 -286.24022)
				)
				(xy 36.30676 -286.063182) (xy 36.11499 -286.063182)
				(arc
					(start 36.11499 -286.348932)
					(mid 36.72713 -286.961072)
					(end 37.33927 -286.348932)
				)
			)
		)
	)
	(zone
		(layer "In2.Cu")
		(hatch none 0.5)
		(connect_pads
			(clearance 0)
		)
		(min_thickness 0.25)
		(keepout
			(tracks not_allowed)
			(vias allowed)
			(pads allowed)
			(copperpour not_allowed)
			(footprints allowed)
		)
		(placement
			(enabled no)
			(sheetname "")
		)
		(fill
			(thermal_gap 0.5)
			(thermal_bridge_width 0.5)
			(island_removal_mode 0)
		)
		(polygon
			(pts
				(arc
					(start 37.33927 -69.631306)
					(mid 36.727257 -69.018912)
					(end 36.11499 -69.631052)
				)
				(xy 36.11499 -69.917056) (xy 36.306506 -69.917056)
				(arc
					(start 36.483544 -69.739764)
					(mid 36.915747 -69.442435)
					(end 36.618418 -69.874638)
				)
				(xy 36.385246 -70.107556) (xy 36.11499 -70.107556) (xy 36.11499 -70.272656) (xy 36.385754 -70.272656)
				(arc
					(start 36.618418 -70.505066)
					(mid 36.915747 -70.937269)
					(end 36.483544 -70.63994)
				)
				(xy 36.307014 -70.463156) (xy 36.11499 -70.463156)
				(arc
					(start 36.11499 -70.748652)
					(mid 36.72713 -71.360792)
					(end 37.33927 -70.748652)
				)
			)
		)
	)
	(zone
		(layer "In2.Cu")
		(hatch none 0.5)
		(connect_pads
			(clearance 0)
		)
		(min_thickness 0.25)
		(keepout
			(tracks not_allowed)
			(vias allowed)
			(pads allowed)
			(copperpour not_allowed)
			(footprints allowed)
		)
		(placement
			(enabled no)
			(sheetname "")
		)
		(fill
			(thermal_gap 0.5)
			(thermal_bridge_width 0.5)
			(island_removal_mode 0)
		)
		(polygon
			(pts
				(xy 0.763016 -466.852508) (xy 1.534668 -466.852508) (xy 1.534668 -471.434414) (xy 1.68783 -471.587576)
				(xy 1.969262 -471.587576) (xy 2.032 -471.650314) (xy 2.032 -477.427036) (xy 0.763016 -477.427036)
			)
		)
	)
	(zone
		(net "P3V3")
		(layer "In2.Cu")
		(hatch none 0.5)
		(connect_pads
			(clearance 0.5)
		)
		(min_thickness 0.25)
		(fill yes
			(thermal_gap 0.5)
			(thermal_bridge_width 0.5)
			(island_removal_mode 0)
		)
		(polygon
			(pts
				(xy 131.280662 -395.478) (xy 122.846846 -403.911816) (xy 86.308184 -403.911816) (xy 66.929 -423.291)
				(xy 66.929 -437.515) (xy 74.93 -445.516) (xy 82.423 -445.516) (xy 83.947 -447.04) (xy 96.139 -447.04)
				(xy 97.917 -445.262) (xy 97.917 -440.817) (xy 97.409 -440.309) (xy 95.885 -440.309) (xy 94.361 -441.833)
				(xy 81.915 -441.833) (xy 76.708 -436.626) (xy 76.708 -423.418) (xy 81.788 -418.338) (xy 166.37 -418.338)
				(xy 174.117 -426.085) (xy 205.867 -426.085) (xy 212.217 -419.735) (xy 212.217 -407.162) (xy 205.994 -400.939)
				(xy 200.533 -395.478)
			)
		)
	)
	(zone
		(layer "In2.Cu")
		(hatch none 0.5)
		(connect_pads
			(clearance 0)
		)
		(min_thickness 0.25)
		(keepout
			(tracks not_allowed)
			(vias allowed)
			(pads allowed)
			(copperpour not_allowed)
			(footprints allowed)
		)
		(placement
			(enabled no)
			(sheetname "")
		)
		(fill
			(thermal_gap 0.5)
			(thermal_bridge_width 0.5)
			(island_removal_mode 0)
		)
		(polygon
			(pts
				(arc
					(start 5.59054 -345.135708)
					(mid 5.080127 -344.624914)
					(end 4.56946 -345.135454)
				)
				(arc
					(start 4.56946 -345.948254)
					(mid 5.08 -346.458794)
					(end 5.59054 -345.948254)
				)
				(xy 5.59054 -345.815158) (xy 5.347716 -345.815158)
				(arc
					(start 5.323586 -345.839542)
					(mid 4.891383 -346.136871)
					(end 5.188712 -345.704668)
				)
				(xy 5.268976 -345.624658) (xy 5.59054 -345.624658) (xy 5.59054 -345.459558) (xy 5.269484 -345.459558)
				(arc
					(start 5.188712 -345.37904)
					(mid 4.891383 -344.946837)
					(end 5.323586 -345.244166)
				)
				(xy 5.348224 -345.269058) (xy 5.59054 -345.269058)
			)
		)
	)
	(zone
		(layer "In2.Cu")
		(hatch none 0.5)
		(connect_pads
			(clearance 0)
		)
		(min_thickness 0.25)
		(keepout
			(tracks not_allowed)
			(vias allowed)
			(pads allowed)
			(copperpour not_allowed)
			(footprints allowed)
		)
		(placement
			(enabled no)
			(sheetname "")
		)
		(fill
			(thermal_gap 0.5)
			(thermal_bridge_width 0.5)
			(island_removal_mode 0)
		)
		(polygon
			(pts
				(arc
					(start 25.88514 -435.251606)
					(mid 25.273127 -434.639212)
					(end 24.66086 -435.251352)
				)
				(arc
					(start 24.66086 -436.368952)
					(mid 25.273 -436.981092)
					(end 25.88514 -436.368952)
				)
				(xy 25.88514 -436.082948) (xy 25.693624 -436.082948)
				(arc
					(start 25.516586 -436.26024)
					(mid 25.084383 -436.557569)
					(end 25.381712 -436.125366)
				)
				(xy 25.614884 -435.892448) (xy 25.88514 -435.892448) (xy 25.88514 -435.727348) (xy 25.614376 -435.727348)
				(arc
					(start 25.381712 -435.494938)
					(mid 25.084383 -435.062735)
					(end 25.516586 -435.360064)
				)
				(xy 25.693116 -435.536848) (xy 25.88514 -435.536848)
			)
		)
	)
	(zone
		(layer "In2.Cu")
		(hatch none 0.5)
		(connect_pads
			(clearance 0)
		)
		(min_thickness 0.25)
		(keepout
			(tracks not_allowed)
			(vias allowed)
			(pads allowed)
			(copperpour not_allowed)
			(footprints allowed)
		)
		(placement
			(enabled no)
			(sheetname "")
		)
		(fill
			(thermal_gap 0.5)
			(thermal_bridge_width 0.5)
			(island_removal_mode 0)
		)
		(polygon
			(pts
				(arc
					(start 5.59054 -167.135556)
					(mid 5.080127 -166.624762)
					(end 4.56946 -167.135302)
				)
				(arc
					(start 4.56946 -167.948102)
					(mid 5.08 -168.458642)
					(end 5.59054 -167.948102)
				)
				(xy 5.59054 -167.81526) (xy 5.347462 -167.81526)
				(arc
					(start 5.323586 -167.83939)
					(mid 4.891383 -168.136719)
					(end 5.188712 -167.704516)
				)
				(xy 5.268722 -167.62476) (xy 5.59054 -167.62476) (xy 5.59054 -167.45966) (xy 5.269738 -167.45966)
				(arc
					(start 5.188712 -167.378888)
					(mid 4.891383 -166.946685)
					(end 5.323586 -167.244014)
				)
				(xy 5.348478 -167.26916) (xy 5.59054 -167.26916)
			)
		)
	)
	(zone
		(layer "In2.Cu")
		(hatch none 0.5)
		(connect_pads
			(clearance 0)
		)
		(min_thickness 0.25)
		(keepout
			(tracks not_allowed)
			(vias allowed)
			(pads allowed)
			(copperpour not_allowed)
			(footprints allowed)
		)
		(placement
			(enabled no)
			(sheetname "")
		)
		(fill
			(thermal_gap 0.5)
			(thermal_bridge_width 0.5)
			(island_removal_mode 0)
		)
		(polygon
			(pts
				(arc
					(start 37.33927 -491.231428)
					(mid 36.72713 -490.619288)
					(end 36.11499 -491.231428)
				)
				(xy 36.11499 -491.517178) (xy 36.30676 -491.517178)
				(arc
					(start 36.483544 -491.34014)
					(mid 36.915747 -491.042811)
					(end 36.618418 -491.475014)
				)
				(xy 36.3855 -491.707678) (xy 36.11499 -491.707678) (xy 36.11499 -491.872778) (xy 36.3855 -491.872778)
				(arc
					(start 36.618418 -492.105442)
					(mid 36.915747 -492.537645)
					(end 36.483544 -492.240316)
				)
				(xy 36.30676 -492.063278) (xy 36.11499 -492.063278)
				(arc
					(start 36.11499 -492.348774)
					(mid 36.727003 -492.961168)
					(end 37.33927 -492.349028)
				)
			)
		)
	)
	(zone
		(layer "In2.Cu")
		(hatch none 0.5)
		(connect_pads
			(clearance 0)
		)
		(min_thickness 0.25)
		(keepout
			(tracks not_allowed)
			(vias allowed)
			(pads allowed)
			(copperpour not_allowed)
			(footprints allowed)
		)
		(placement
			(enabled no)
			(sheetname "")
		)
		(fill
			(thermal_gap 0.5)
			(thermal_bridge_width 0.5)
			(island_removal_mode 0)
		)
		(polygon
			(pts
				(arc
					(start 5.59054 -357.935784)
					(mid 5.080127 -357.42499)
					(end 4.56946 -357.93553)
				)
				(arc
					(start 4.56946 -358.74833)
					(mid 5.08 -359.25887)
					(end 5.59054 -358.74833)
				)
				(xy 5.59054 -358.615234) (xy 5.347716 -358.615234)
				(arc
					(start 5.323586 -358.639618)
					(mid 4.891383 -358.936947)
					(end 5.188712 -358.504744)
				)
				(xy 5.268976 -358.424734) (xy 5.59054 -358.424734) (xy 5.59054 -358.259634) (xy 5.269484 -358.259634)
				(arc
					(start 5.188712 -358.179116)
					(mid 4.891383 -357.746913)
					(end 5.323586 -358.044242)
				)
				(xy 5.348224 -358.069134) (xy 5.59054 -358.069134)
			)
		)
	)
	(zone
		(layer "In2.Cu")
		(hatch none 0.5)
		(connect_pads
			(clearance 0)
		)
		(min_thickness 0.25)
		(keepout
			(tracks not_allowed)
			(vias allowed)
			(pads allowed)
			(copperpour not_allowed)
			(footprints allowed)
		)
		(placement
			(enabled no)
			(sheetname "")
		)
		(fill
			(thermal_gap 0.5)
			(thermal_bridge_width 0.5)
			(island_removal_mode 0)
		)
		(polygon
			(pts
				(arc
					(start 5.59054 -413.535114)
					(mid 5.08 -413.024574)
					(end 4.56946 -413.535114)
				)
				(arc
					(start 4.56946 -414.34766)
					(mid 5.079873 -414.858454)
					(end 5.59054 -414.347914)
				)
				(xy 5.59054 -414.215072) (xy 5.347462 -414.215072)
				(arc
					(start 5.323586 -414.239202)
					(mid 4.891383 -414.536531)
					(end 5.188712 -414.104328)
				)
				(xy 5.268722 -414.024572) (xy 5.59054 -414.024572) (xy 5.59054 -413.859472) (xy 5.269738 -413.859472)
				(arc
					(start 5.188712 -413.7787)
					(mid 4.891383 -413.346497)
					(end 5.323586 -413.643826)
				)
				(xy 5.348478 -413.668972) (xy 5.59054 -413.668972)
			)
		)
	)
	(zone
		(layer "In2.Cu")
		(hatch none 0.5)
		(connect_pads
			(clearance 0)
		)
		(min_thickness 0.25)
		(keepout
			(tracks not_allowed)
			(vias allowed)
			(pads allowed)
			(copperpour not_allowed)
			(footprints allowed)
		)
		(placement
			(enabled no)
			(sheetname "")
		)
		(fill
			(thermal_gap 0.5)
			(thermal_bridge_width 0.5)
			(island_removal_mode 0)
		)
		(polygon
			(pts
				(arc
					(start 5.59054 -289.935666)
					(mid 5.080127 -289.424872)
					(end 4.56946 -289.935412)
				)
				(arc
					(start 4.56946 -290.748212)
					(mid 5.08 -291.258752)
					(end 5.59054 -290.748212)
				)
				(xy 5.59054 -290.615116) (xy 5.347716 -290.615116)
				(arc
					(start 5.323586 -290.6395)
					(mid 4.891383 -290.936829)
					(end 5.188712 -290.504626)
				)
				(xy 5.268976 -290.424616) (xy 5.59054 -290.424616) (xy 5.59054 -290.259516) (xy 5.269484 -290.259516)
				(arc
					(start 5.188712 -290.178998)
					(mid 4.891383 -289.746795)
					(end 5.323586 -290.044124)
				)
				(xy 5.348224 -290.069016) (xy 5.59054 -290.069016)
			)
		)
	)
	(zone
		(net "P3V3")
		(layer "In2.Cu")
		(hatch none 0.5)
		(connect_pads
			(clearance 0.5)
		)
		(min_thickness 0.25)
		(fill yes
			(thermal_gap 0.5)
			(thermal_bridge_width 0.5)
			(island_removal_mode 0)
		)
		(polygon
			(pts
				(xy 79.248 -226.949) (xy 79.629 -227.33) (xy 79.629 -240.8174) (xy 49.022 -271.4244) (xy 36.9316 -271.4244)
				(xy 36.576 -271.0688) (xy 36.576 -268.097) (xy 38.227 -266.446) (xy 39.878 -266.446) (xy 41.402 -267.97)
				(xy 43.434 -267.97) (xy 44.958 -266.446) (xy 45.974 -266.446) (xy 46.482 -265.938) (xy 46.482 -258.191)
				(xy 40.64 -252.349) (xy 40.64 -248.285) (xy 45.974 -242.951) (xy 45.974 -233.98226) (xy 46.36262 -233.59364)
				(xy 53.00726 -226.949)
			)
		)
	)
	(zone
		(layer "In2.Cu")
		(hatch none 0.5)
		(connect_pads
			(clearance 0)
		)
		(min_thickness 0.25)
		(keepout
			(tracks not_allowed)
			(vias allowed)
			(pads allowed)
			(copperpour not_allowed)
			(footprints allowed)
		)
		(placement
			(enabled no)
			(sheetname "")
		)
		(fill
			(thermal_gap 0.5)
			(thermal_bridge_width 0.5)
			(island_removal_mode 0)
		)
		(polygon
			(pts
				(arc
					(start 37.33927 -468.831422)
					(mid 36.72713 -468.219282)
					(end 36.11499 -468.831422)
				)
				(xy 36.11499 -469.117172) (xy 36.30676 -469.117172)
				(arc
					(start 36.483544 -468.940134)
					(mid 36.915747 -468.642805)
					(end 36.618418 -469.075008)
				)
				(xy 36.3855 -469.307672) (xy 36.11499 -469.307672) (xy 36.11499 -469.472772) (xy 36.3855 -469.472772)
				(arc
					(start 36.618418 -469.705436)
					(mid 36.915747 -470.137639)
					(end 36.483544 -469.84031)
				)
				(xy 36.30676 -469.663272) (xy 36.11499 -469.663272)
				(arc
					(start 36.11499 -469.948768)
					(mid 36.727003 -470.561162)
					(end 37.33927 -469.949022)
				)
			)
		)
	)
	(zone
		(layer "In2.Cu")
		(hatch none 0.5)
		(connect_pads
			(clearance 0)
		)
		(min_thickness 0.25)
		(keepout
			(tracks not_allowed)
			(vias allowed)
			(pads allowed)
			(copperpour not_allowed)
			(footprints allowed)
		)
		(placement
			(enabled no)
			(sheetname "")
		)
		(fill
			(thermal_gap 0.5)
			(thermal_bridge_width 0.5)
			(island_removal_mode 0)
		)
		(polygon
			(pts
				(arc
					(start 37.33927 -378.63145)
					(mid 36.727257 -378.019056)
					(end 36.11499 -378.631196)
				)
				(xy 36.11499 -378.9172) (xy 36.306506 -378.9172)
				(arc
					(start 36.483544 -378.739908)
					(mid 36.915747 -378.442579)
					(end 36.618418 -378.874782)
				)
				(xy 36.385246 -379.1077) (xy 36.11499 -379.1077) (xy 36.11499 -379.2728) (xy 36.385754 -379.2728)
				(arc
					(start 36.618418 -379.50521)
					(mid 36.915747 -379.937413)
					(end 36.483544 -379.640084)
				)
				(xy 36.307014 -379.4633) (xy 36.11499 -379.4633)
				(arc
					(start 36.11499 -379.748796)
					(mid 36.72713 -380.360936)
					(end 37.33927 -379.748796)
				)
			)
		)
	)
	(zone
		(net "VDD_IO_2")
		(layer "In2.Cu")
		(hatch none 0.5)
		(connect_pads
			(clearance 0.5)
		)
		(min_thickness 0.25)
		(fill yes
			(thermal_gap 0.5)
			(thermal_bridge_width 0.5)
			(island_removal_mode 0)
		)
		(polygon
			(pts
				(xy 101.092 -315.087) (xy 101.854 -315.087) (xy 102.489 -314.452) (xy 102.489 -312.42) (xy 101.473 -311.404)
				(xy 101.473 -303.53) (xy 102.489 -302.514) (xy 102.489 -299.466) (xy 100.457 -297.434) (xy 93.345 -297.434)
				(xy 92.71 -298.069) (xy 92.71 -310.388) (xy 95.25 -312.928) (xy 100.584 -312.928) (xy 100.838 -313.182)
				(xy 100.838 -314.833)
			)
		)
	)
	(zone
		(layer "In2.Cu")
		(hatch none 0.5)
		(connect_pads
			(clearance 0)
		)
		(min_thickness 0.25)
		(keepout
			(tracks not_allowed)
			(vias allowed)
			(pads allowed)
			(copperpour not_allowed)
			(footprints allowed)
		)
		(placement
			(enabled no)
			(sheetname "")
		)
		(fill
			(thermal_gap 0.5)
			(thermal_bridge_width 0.5)
			(island_removal_mode 0)
		)
		(polygon
			(pts
				(arc
					(start 5.59054 -160.735772)
					(mid 5.080127 -160.224978)
					(end 4.56946 -160.735518)
				)
				(arc
					(start 4.56946 -161.548318)
					(mid 5.08 -162.058858)
					(end 5.59054 -161.548318)
				)
				(xy 5.59054 -161.426144) (xy 5.336794 -161.426144)
				(arc
					(start 5.323586 -161.439606)
					(mid 4.891383 -161.736935)
					(end 5.188712 -161.304732)
				)
				(xy 5.258054 -161.235644) (xy 5.59054 -161.235644) (xy 5.59054 -161.070544) (xy 5.280406 -161.070544)
				(arc
					(start 5.188712 -160.979104)
					(mid 4.891383 -160.546901)
					(end 5.323586 -160.84423)
				)
				(xy 5.359146 -160.880044) (xy 5.59054 -160.880044)
			)
		)
	)
	(zone
		(layer "In2.Cu")
		(hatch none 0.5)
		(connect_pads
			(clearance 0)
		)
		(min_thickness 0.25)
		(keepout
			(tracks not_allowed)
			(vias allowed)
			(pads allowed)
			(copperpour not_allowed)
			(footprints allowed)
		)
		(placement
			(enabled no)
			(sheetname "")
		)
		(fill
			(thermal_gap 0.5)
			(thermal_bridge_width 0.5)
			(island_removal_mode 0)
		)
		(polygon
			(pts
				(arc
					(start 5.59054 -222.335598)
					(mid 5.080127 -221.824804)
					(end 4.56946 -222.335344)
				)
				(arc
					(start 4.56946 -223.148144)
					(mid 5.08 -223.658684)
					(end 5.59054 -223.148144)
				)
				(xy 5.59054 -223.015302) (xy 5.347462 -223.015302)
				(arc
					(start 5.323586 -223.039432)
					(mid 4.891383 -223.336761)
					(end 5.188712 -222.904558)
				)
				(xy 5.268722 -222.824802) (xy 5.59054 -222.824802) (xy 5.59054 -222.659702) (xy 5.269738 -222.659702)
				(arc
					(start 5.188712 -222.57893)
					(mid 4.891383 -222.146727)
					(end 5.323586 -222.444056)
				)
				(xy 5.348478 -222.469202) (xy 5.59054 -222.469202)
			)
		)
	)
	(zone
		(layer "In2.Cu")
		(hatch none 0.5)
		(connect_pads
			(clearance 0)
		)
		(min_thickness 0.25)
		(keepout
			(tracks not_allowed)
			(vias allowed)
			(pads allowed)
			(copperpour not_allowed)
			(footprints allowed)
		)
		(placement
			(enabled no)
			(sheetname "")
		)
		(fill
			(thermal_gap 0.5)
			(thermal_bridge_width 0.5)
			(island_removal_mode 0)
		)
		(polygon
			(pts
				(arc
					(start 5.59054 -438.335166)
					(mid 5.08 -437.824626)
					(end 4.56946 -438.335166)
				)
				(arc
					(start 4.56946 -439.147712)
					(mid 5.079873 -439.658506)
					(end 5.59054 -439.147966)
				)
				(xy 5.59054 -439.01487) (xy 5.347716 -439.01487)
				(arc
					(start 5.323586 -439.039254)
					(mid 4.891383 -439.336583)
					(end 5.188712 -438.90438)
				)
				(xy 5.268976 -438.82437) (xy 5.59054 -438.82437) (xy 5.59054 -438.65927) (xy 5.269484 -438.65927)
				(arc
					(start 5.188712 -438.578752)
					(mid 4.891383 -438.146549)
					(end 5.323586 -438.443878)
				)
				(xy 5.348224 -438.46877) (xy 5.59054 -438.46877)
			)
		)
	)
	(zone
		(layer "In2.Cu")
		(hatch none 0.5)
		(connect_pads
			(clearance 0)
		)
		(min_thickness 0.25)
		(keepout
			(tracks not_allowed)
			(vias allowed)
			(pads allowed)
			(copperpour not_allowed)
			(footprints allowed)
		)
		(placement
			(enabled no)
			(sheetname "")
		)
		(fill
			(thermal_gap 0.5)
			(thermal_bridge_width 0.5)
			(island_removal_mode 0)
		)
		(polygon
			(pts
				(arc
					(start 37.33927 -365.831628)
					(mid 36.727257 -365.219234)
					(end 36.11499 -365.831374)
				)
				(xy 36.11499 -366.117124) (xy 36.30676 -366.117124)
				(arc
					(start 36.483544 -365.940086)
					(mid 36.915747 -365.642757)
					(end 36.618418 -366.07496)
				)
				(xy 36.3855 -366.307624) (xy 36.11499 -366.307624) (xy 36.11499 -366.472724) (xy 36.3855 -366.472724)
				(arc
					(start 36.618418 -366.705388)
					(mid 36.915747 -367.137591)
					(end 36.483544 -366.840262)
				)
				(xy 36.30676 -366.663224) (xy 36.11499 -366.663224)
				(arc
					(start 36.11499 -366.948974)
					(mid 36.72713 -367.561114)
					(end 37.33927 -366.948974)
				)
			)
		)
	)
	(zone
		(layer "In2.Cu")
		(hatch none 0.5)
		(connect_pads
			(clearance 0)
		)
		(min_thickness 0.25)
		(keepout
			(tracks not_allowed)
			(vias allowed)
			(pads allowed)
			(copperpour not_allowed)
			(footprints allowed)
		)
		(placement
			(enabled no)
			(sheetname "")
		)
		(fill
			(thermal_gap 0.5)
			(thermal_bridge_width 0.5)
			(island_removal_mode 0)
		)
		(polygon
			(pts
				(arc
					(start 5.59054 -435.135274)
					(mid 5.08 -434.624734)
					(end 4.56946 -435.135274)
				)
				(arc
					(start 4.56946 -435.94782)
					(mid 5.079873 -436.458614)
					(end 5.59054 -435.948074)
				)
				(xy 5.59054 -435.814978) (xy 5.347716 -435.814978)
				(arc
					(start 5.323586 -435.839362)
					(mid 4.891383 -436.136691)
					(end 5.188712 -435.704488)
				)
				(xy 5.268976 -435.624478) (xy 5.59054 -435.624478) (xy 5.59054 -435.459378) (xy 5.269484 -435.459378)
				(arc
					(start 5.188712 -435.37886)
					(mid 4.891383 -434.946657)
					(end 5.323586 -435.243986)
				)
				(xy 5.348224 -435.268878) (xy 5.59054 -435.268878)
			)
		)
	)
	(zone
		(layer "In2.Cu")
		(hatch none 0.5)
		(connect_pads
			(clearance 0)
		)
		(min_thickness 0.25)
		(keepout
			(tracks not_allowed)
			(vias allowed)
			(pads allowed)
			(copperpour not_allowed)
			(footprints allowed)
		)
		(placement
			(enabled no)
			(sheetname "")
		)
		(fill
			(thermal_gap 0.5)
			(thermal_bridge_width 0.5)
			(island_removal_mode 0)
		)
		(polygon
			(pts
				(arc
					(start 5.59054 -157.535626)
					(mid 5.080127 -157.024832)
					(end 4.56946 -157.535372)
				)
				(arc
					(start 4.56946 -158.348172)
					(mid 5.08 -158.858712)
					(end 5.59054 -158.348172)
				)
				(xy 5.59054 -158.21533) (xy 5.347462 -158.21533)
				(arc
					(start 5.323586 -158.23946)
					(mid 4.891383 -158.536789)
					(end 5.188712 -158.104586)
				)
				(xy 5.268722 -158.02483) (xy 5.59054 -158.02483) (xy 5.59054 -157.85973) (xy 5.269738 -157.85973)
				(arc
					(start 5.188712 -157.778958)
					(mid 4.891383 -157.346755)
					(end 5.323586 -157.644084)
				)
				(xy 5.348478 -157.66923) (xy 5.59054 -157.66923)
			)
		)
	)
	(zone
		(layer "In2.Cu")
		(hatch none 0.5)
		(connect_pads
			(clearance 0)
		)
		(min_thickness 0.25)
		(keepout
			(tracks not_allowed)
			(vias allowed)
			(pads allowed)
			(copperpour not_allowed)
			(footprints allowed)
		)
		(placement
			(enabled no)
			(sheetname "")
		)
		(fill
			(thermal_gap 0.5)
			(thermal_bridge_width 0.5)
			(island_removal_mode 0)
		)
		(polygon
			(pts
				(arc
					(start 25.88514 -448.051428)
					(mid 25.273127 -447.439034)
					(end 24.66086 -448.051174)
				)
				(arc
					(start 24.66086 -449.168774)
					(mid 25.273 -449.780914)
					(end 25.88514 -449.168774)
				)
				(xy 25.88514 -448.883024) (xy 25.69337 -448.883024)
				(arc
					(start 25.516586 -449.060062)
					(mid 25.084383 -449.357391)
					(end 25.381712 -448.925188)
				)
				(xy 25.61463 -448.692524) (xy 25.88514 -448.692524) (xy 25.88514 -448.527424) (xy 25.61463 -448.527424)
				(arc
					(start 25.381712 -448.29476)
					(mid 25.084383 -447.862557)
					(end 25.516586 -448.159886)
				)
				(xy 25.69337 -448.336924) (xy 25.88514 -448.336924)
			)
		)
	)
	(zone
		(layer "In2.Cu")
		(hatch none 0.5)
		(connect_pads
			(clearance 0)
		)
		(min_thickness 0.25)
		(keepout
			(tracks not_allowed)
			(vias allowed)
			(pads allowed)
			(copperpour not_allowed)
			(footprints allowed)
		)
		(placement
			(enabled no)
			(sheetname "")
		)
		(fill
			(thermal_gap 0.5)
			(thermal_bridge_width 0.5)
			(island_removal_mode 0)
		)
		(polygon
			(pts
				(arc
					(start 5.59054 -338.73567)
					(mid 5.080127 -338.224876)
					(end 4.56946 -338.735416)
				)
				(arc
					(start 4.56946 -339.548216)
					(mid 5.08 -340.058756)
					(end 5.59054 -339.548216)
				)
				(xy 5.59054 -339.41512) (xy 5.347716 -339.41512)
				(arc
					(start 5.323586 -339.439504)
					(mid 4.891383 -339.736833)
					(end 5.188712 -339.30463)
				)
				(xy 5.268976 -339.22462) (xy 5.59054 -339.22462) (xy 5.59054 -339.05952) (xy 5.269484 -339.05952)
				(arc
					(start 5.188712 -338.979002)
					(mid 4.891383 -338.546799)
					(end 5.323586 -338.844128)
				)
				(xy 5.348224 -338.86902) (xy 5.59054 -338.86902)
			)
		)
	)
	(zone
		(layer "In2.Cu")
		(hatch none 0.5)
		(connect_pads
			(clearance 0)
		)
		(min_thickness 0.25)
		(keepout
			(tracks not_allowed)
			(vias allowed)
			(pads allowed)
			(copperpour not_allowed)
			(footprints allowed)
		)
		(placement
			(enabled no)
			(sheetname "")
		)
		(fill
			(thermal_gap 0.5)
			(thermal_bridge_width 0.5)
			(island_removal_mode 0)
		)
		(polygon
			(pts
				(arc
					(start 222.339154 -275.631402)
					(mid 221.727141 -275.019008)
					(end 221.114874 -275.631148)
				)
				(xy 221.114874 -275.917152) (xy 221.30639 -275.917152)
				(arc
					(start 221.483428 -275.73986)
					(mid 221.915631 -275.442531)
					(end 221.618302 -275.874734)
				)
				(xy 221.38513 -276.107652) (xy 221.114874 -276.107652) (xy 221.114874 -276.272752) (xy 221.385638 -276.272752)
				(arc
					(start 221.618302 -276.505162)
					(mid 221.915631 -276.937365)
					(end 221.483428 -276.640036)
				)
				(xy 221.306898 -276.463252) (xy 221.114874 -276.463252)
				(arc
					(start 221.114874 -276.748748)
					(mid 221.727014 -277.360888)
					(end 222.339154 -276.748748)
				)
			)
		)
	)
	(zone
		(layer "In2.Cu")
		(hatch none 0.5)
		(connect_pads
			(clearance 0)
		)
		(min_thickness 0.25)
		(keepout
			(tracks not_allowed)
			(vias allowed)
			(pads allowed)
			(copperpour not_allowed)
			(footprints allowed)
		)
		(placement
			(enabled no)
			(sheetname "")
		)
		(fill
			(thermal_gap 0.5)
			(thermal_bridge_width 0.5)
			(island_removal_mode 0)
		)
		(polygon
			(pts
				(arc
					(start 5.59054 -341.935562)
					(mid 5.080127 -341.424768)
					(end 4.56946 -341.935308)
				)
				(arc
					(start 4.56946 -342.748108)
					(mid 5.08 -343.258648)
					(end 5.59054 -342.748108)
				)
				(xy 5.59054 -342.615266) (xy 5.347462 -342.615266)
				(arc
					(start 5.323586 -342.639396)
					(mid 4.891383 -342.936725)
					(end 5.188712 -342.504522)
				)
				(xy 5.268722 -342.424766) (xy 5.59054 -342.424766) (xy 5.59054 -342.259666) (xy 5.269738 -342.259666)
				(arc
					(start 5.188712 -342.178894)
					(mid 4.891383 -341.746691)
					(end 5.323586 -342.04402)
				)
				(xy 5.348478 -342.069166) (xy 5.59054 -342.069166)
			)
		)
	)
	(zone
		(layer "In2.Cu")
		(hatch none 0.5)
		(connect_pads
			(clearance 0)
		)
		(min_thickness 0.25)
		(keepout
			(tracks not_allowed)
			(vias allowed)
			(pads allowed)
			(copperpour not_allowed)
			(footprints allowed)
		)
		(placement
			(enabled no)
			(sheetname "")
		)
		(fill
			(thermal_gap 0.5)
			(thermal_bridge_width 0.5)
			(island_removal_mode 0)
		)
		(polygon
			(pts
				(arc
					(start 222.339154 -182.231538)
					(mid 221.727141 -181.619144)
					(end 221.114874 -182.231284)
				)
				(xy 221.114874 -182.517034) (xy 221.306644 -182.517034)
				(arc
					(start 221.483428 -182.339996)
					(mid 221.915631 -182.042667)
					(end 221.618302 -182.47487)
				)
				(xy 221.385384 -182.707534) (xy 221.114874 -182.707534) (xy 221.114874 -182.872634) (xy 221.385384 -182.872634)
				(arc
					(start 221.618302 -183.105298)
					(mid 221.915631 -183.537501)
					(end 221.483428 -183.240172)
				)
				(xy 221.306644 -183.063134) (xy 221.114874 -183.063134)
				(arc
					(start 221.114874 -183.348884)
					(mid 221.727014 -183.961024)
					(end 222.339154 -183.348884)
				)
			)
		)
	)
	(zone
		(layer "In2.Cu")
		(hatch none 0.5)
		(connect_pads
			(clearance 0)
		)
		(min_thickness 0.25)
		(keepout
			(tracks not_allowed)
			(vias allowed)
			(pads allowed)
			(copperpour not_allowed)
			(footprints allowed)
		)
		(placement
			(enabled no)
			(sheetname "")
		)
		(fill
			(thermal_gap 0.5)
			(thermal_bridge_width 0.5)
			(island_removal_mode 0)
		)
		(polygon
			(pts
				(arc
					(start 5.59054 -391.935462)
					(mid 5.080127 -391.424668)
					(end 4.56946 -391.935208)
				)
				(arc
					(start 4.56946 -392.748008)
					(mid 5.08 -393.258548)
					(end 5.59054 -392.748008)
				)
				(xy 5.59054 -392.614912) (xy 5.347716 -392.614912)
				(arc
					(start 5.323586 -392.639296)
					(mid 4.891383 -392.936625)
					(end 5.188712 -392.504422)
				)
				(xy 5.268976 -392.424412) (xy 5.59054 -392.424412) (xy 5.59054 -392.259312) (xy 5.269484 -392.259312)
				(arc
					(start 5.188712 -392.178794)
					(mid 4.891383 -391.746591)
					(end 5.323586 -392.04392)
				)
				(xy 5.348224 -392.068812) (xy 5.59054 -392.068812)
			)
		)
	)
	(zone
		(layer "In2.Cu")
		(hatch none 0.5)
		(connect_pads
			(clearance 0)
		)
		(min_thickness 0.25)
		(keepout
			(tracks not_allowed)
			(vias allowed)
			(pads allowed)
			(copperpour not_allowed)
			(footprints allowed)
		)
		(placement
			(enabled no)
			(sheetname "")
		)
		(fill
			(thermal_gap 0.5)
			(thermal_bridge_width 0.5)
			(island_removal_mode 0)
		)
		(polygon
			(pts
				(arc
					(start 5.59054 -429.535336)
					(mid 5.080127 -429.024542)
					(end 4.56946 -429.535082)
				)
				(arc
					(start 4.56946 -430.347882)
					(mid 5.08 -430.858422)
					(end 5.59054 -430.347882)
				)
				(xy 5.59054 -430.214786) (xy 5.347716 -430.214786)
				(arc
					(start 5.323586 -430.23917)
					(mid 4.891383 -430.536499)
					(end 5.188712 -430.104296)
				)
				(xy 5.268976 -430.024286) (xy 5.59054 -430.024286) (xy 5.59054 -429.859186) (xy 5.269484 -429.859186)
				(arc
					(start 5.188712 -429.778668)
					(mid 4.891383 -429.346465)
					(end 5.323586 -429.643794)
				)
				(xy 5.348224 -429.668686) (xy 5.59054 -429.668686)
			)
		)
	)
	(zone
		(layer "In2.Cu")
		(hatch none 0.5)
		(connect_pads
			(clearance 0)
		)
		(min_thickness 0.25)
		(keepout
			(tracks not_allowed)
			(vias allowed)
			(pads allowed)
			(copperpour not_allowed)
			(footprints allowed)
		)
		(placement
			(enabled no)
			(sheetname "")
		)
		(fill
			(thermal_gap 0.5)
			(thermal_bridge_width 0.5)
			(island_removal_mode 0)
		)
		(polygon
			(pts
				(arc
					(start 5.59054 -176.73574)
					(mid 5.080127 -176.224946)
					(end 4.56946 -176.735486)
				)
				(arc
					(start 4.56946 -177.548286)
					(mid 5.08 -178.058826)
					(end 5.59054 -177.548286)
				)
				(xy 5.59054 -177.41519) (xy 5.347716 -177.41519)
				(arc
					(start 5.323586 -177.439574)
					(mid 4.891383 -177.736903)
					(end 5.188712 -177.3047)
				)
				(xy 5.268976 -177.22469) (xy 5.59054 -177.22469) (xy 5.59054 -177.05959) (xy 5.269484 -177.05959)
				(arc
					(start 5.188712 -176.979072)
					(mid 4.891383 -176.546869)
					(end 5.323586 -176.844198)
				)
				(xy 5.348224 -176.86909) (xy 5.59054 -176.86909)
			)
		)
	)
	(zone
		(layers "In2.Cu" "In5.Cu")
		(hatch none 0.5)
		(connect_pads
			(clearance 0)
		)
		(min_thickness 0.25)
		(keepout
			(tracks not_allowed)
			(vias allowed)
			(pads allowed)
			(copperpour not_allowed)
			(footprints allowed)
		)
		(placement
			(enabled no)
			(sheetname "")
		)
		(fill yes
			(thermal_gap 0.5)
			(thermal_bridge_width 0.5)
			(island_removal_mode 0)
		)
		(polygon
			(pts
				(arc
					(start 44.907454 -265.279632)
					(mid 44.39666 -265.790045)
					(end 44.9072 -266.300712)
				)
				(arc
					(start 45.72 -266.300712)
					(mid 46.080107 -266.152075)
					(end 46.23054 -265.792712)
				)
				(arc
					(start 45.9867 -265.792712)
					(mid 45.72 -266.056884)
					(end 45.4533 -265.792712)
				)
				(arc
					(start 45.1739 -265.792712)
					(mid 44.9072 -266.056884)
					(end 44.6405 -265.792712)
				)
				(arc
					(start 44.6405 -265.790172)
					(mid 44.9072 -265.523472)
					(end 45.1739 -265.790172)
				)
				(arc
					(start 45.4533 -265.790172)
					(mid 45.72 -265.523472)
					(end 45.9867 -265.790172)
				)
				(arc
					(start 46.23054 -265.790172)
					(mid 46.081006 -265.429166)
					(end 45.72 -265.279632)
				)
			)
		)
	)
	(zone
		(layers "In2.Cu" "In5.Cu")
		(hatch none 0.5)
		(connect_pads
			(clearance 0)
		)
		(min_thickness 0.25)
		(keepout
			(tracks not_allowed)
			(vias allowed)
			(pads allowed)
			(copperpour not_allowed)
			(footprints allowed)
		)
		(placement
			(enabled no)
			(sheetname "")
		)
		(fill yes
			(thermal_gap 0.5)
			(thermal_bridge_width 0.5)
			(island_removal_mode 0)
		)
		(polygon
			(pts
				(arc
					(start 32.00654 -32.603186)
					(mid 31.496 -32.092646)
					(end 30.98546 -32.603186)
				)
				(arc
					(start 30.98546 -33.415986)
					(mid 31.49473 -33.926524)
					(end 32.00654 -33.418526)
				)
				(arc
					(start 31.7627 -33.418526)
					(mid 31.496 -33.682698)
					(end 31.2293 -33.418526)
				)
				(arc
					(start 31.2293 -33.415986)
					(mid 31.496 -33.149286)
					(end 31.7627 -33.415986)
				)
				(xy 32.00654 -33.415986) (xy 32.00654 -32.605726)
				(arc
					(start 31.7627 -32.605726)
					(mid 31.496 -32.869898)
					(end 31.2293 -32.605726)
				)
				(arc
					(start 31.2293 -32.603186)
					(mid 31.496 -32.336486)
					(end 31.7627 -32.603186)
				)
			)
		)
	)
	(zone
		(layers "In2.Cu" "In5.Cu")
		(hatch none 0.5)
		(connect_pads
			(clearance 0)
		)
		(min_thickness 0.25)
		(keepout
			(tracks not_allowed)
			(vias allowed)
			(pads allowed)
			(copperpour not_allowed)
			(footprints allowed)
		)
		(placement
			(enabled no)
			(sheetname "")
		)
		(fill yes
			(thermal_gap 0.5)
			(thermal_bridge_width 0.5)
			(island_removal_mode 0)
		)
		(polygon
			(pts
				(arc
					(start 17.78254 -32.603186)
					(mid 17.272 -32.092646)
					(end 16.76146 -32.603186)
				)
				(arc
					(start 16.76146 -33.415986)
					(mid 17.27073 -33.926524)
					(end 17.78254 -33.418526)
				)
				(arc
					(start 17.5387 -33.418526)
					(mid 17.272 -33.682698)
					(end 17.0053 -33.418526)
				)
				(arc
					(start 17.0053 -33.415986)
					(mid 17.272 -33.149286)
					(end 17.5387 -33.415986)
				)
				(xy 17.78254 -33.415986) (xy 17.78254 -32.605726)
				(arc
					(start 17.5387 -32.605726)
					(mid 17.272 -32.869898)
					(end 17.0053 -32.605726)
				)
				(arc
					(start 17.0053 -32.603186)
					(mid 17.272 -32.336486)
					(end 17.5387 -32.603186)
				)
			)
		)
	)
	(zone
		(layers "In2.Cu" "In5.Cu")
		(hatch none 0.5)
		(connect_pads
			(clearance 0)
		)
		(min_thickness 0.25)
		(keepout
			(tracks not_allowed)
			(vias allowed)
			(pads allowed)
			(copperpour not_allowed)
			(footprints allowed)
		)
		(placement
			(enabled no)
			(sheetname "")
		)
		(fill yes
			(thermal_gap 0.5)
			(thermal_bridge_width 0.5)
			(island_removal_mode 0)
		)
		(polygon
			(pts
				(arc
					(start 44.907454 -59.279536)
					(mid 44.39666 -59.789949)
					(end 44.9072 -60.300616)
				)
				(arc
					(start 45.72 -60.300616)
					(mid 46.080107 -60.151979)
					(end 46.23054 -59.792616)
				)
				(arc
					(start 45.9867 -59.792616)
					(mid 45.72 -60.056788)
					(end 45.4533 -59.792616)
				)
				(arc
					(start 45.1739 -59.792616)
					(mid 44.9072 -60.056788)
					(end 44.6405 -59.792616)
				)
				(arc
					(start 44.6405 -59.790076)
					(mid 44.9072 -59.523376)
					(end 45.1739 -59.790076)
				)
				(arc
					(start 45.4533 -59.790076)
					(mid 45.72 -59.523376)
					(end 45.9867 -59.790076)
				)
				(arc
					(start 46.23054 -59.790076)
					(mid 46.081006 -59.42907)
					(end 45.72 -59.279536)
				)
			)
		)
	)
	(zone
		(layers "In2.Cu" "In5.Cu")
		(hatch none 0.5)
		(connect_pads
			(clearance 0)
		)
		(min_thickness 0.25)
		(keepout
			(tracks not_allowed)
			(vias allowed)
			(pads allowed)
			(copperpour not_allowed)
			(footprints allowed)
		)
		(placement
			(enabled no)
			(sheetname "")
		)
		(fill yes
			(thermal_gap 0.5)
			(thermal_bridge_width 0.5)
			(island_removal_mode 0)
		)
		(polygon
			(pts
				(arc
					(start 17.78254 -238.603282)
					(mid 17.272 -238.092742)
					(end 16.76146 -238.603282)
				)
				(arc
					(start 16.76146 -239.415828)
					(mid 17.270603 -239.92662)
					(end 17.78254 -239.418622)
				)
				(arc
					(start 17.5387 -239.418622)
					(mid 17.272 -239.682794)
					(end 17.0053 -239.418622)
				)
				(arc
					(start 17.0053 -239.416082)
					(mid 17.272 -239.149382)
					(end 17.5387 -239.416082)
				)
				(xy 17.78254 -239.416082) (xy 17.78254 -238.605822)
				(arc
					(start 17.5387 -238.605822)
					(mid 17.272 -238.869994)
					(end 17.0053 -238.605822)
				)
				(arc
					(start 17.0053 -238.603282)
					(mid 17.272 -238.336582)
					(end 17.5387 -238.603282)
				)
			)
		)
	)
	(zone
		(layers "In2.Cu" "In5.Cu")
		(hatch none 0.5)
		(connect_pads
			(clearance 0)
		)
		(min_thickness 0.25)
		(keepout
			(tracks not_allowed)
			(vias allowed)
			(pads allowed)
			(copperpour not_allowed)
			(footprints allowed)
		)
		(placement
			(enabled no)
			(sheetname "")
		)
		(fill yes
			(thermal_gap 0.5)
			(thermal_bridge_width 0.5)
			(island_removal_mode 0)
		)
		(polygon
			(pts
				(arc
					(start 48.89754 -369.579398)
					(mid 48.387 -369.068858)
					(end 47.87646 -369.579398)
				)
				(arc
					(start 47.87646 -370.392198)
					(mid 48.38573 -370.902736)
					(end 48.89754 -370.394738)
				)
				(arc
					(start 48.6537 -370.394738)
					(mid 48.387 -370.65891)
					(end 48.1203 -370.394738)
				)
				(arc
					(start 48.1203 -370.392198)
					(mid 48.387 -370.125498)
					(end 48.6537 -370.392198)
				)
				(xy 48.89754 -370.392198) (xy 48.89754 -369.581938)
				(arc
					(start 48.6537 -369.581938)
					(mid 48.387 -369.84611)
					(end 48.1203 -369.581938)
				)
				(arc
					(start 48.1203 -369.579398)
					(mid 48.387 -369.312698)
					(end 48.6537 -369.579398)
				)
			)
		)
	)
	(zone
		(layers "In2.Cu" "In5.Cu")
		(hatch none 0.5)
		(connect_pads
			(clearance 0)
		)
		(min_thickness 0.25)
		(keepout
			(tracks not_allowed)
			(vias allowed)
			(pads allowed)
			(copperpour not_allowed)
			(footprints allowed)
		)
		(placement
			(enabled no)
			(sheetname "")
		)
		(fill yes
			(thermal_gap 0.5)
			(thermal_bridge_width 0.5)
			(island_removal_mode 0)
		)
		(polygon
			(pts
				(arc
					(start 48.89754 -266.57935)
					(mid 48.387 -266.06881)
					(end 47.87646 -266.57935)
				)
				(arc
					(start 47.87646 -267.39215)
					(mid 48.38573 -267.902688)
					(end 48.89754 -267.39469)
				)
				(arc
					(start 48.6537 -267.39469)
					(mid 48.387 -267.658862)
					(end 48.1203 -267.39469)
				)
				(arc
					(start 48.1203 -267.39215)
					(mid 48.387 -267.12545)
					(end 48.6537 -267.39215)
				)
				(xy 48.89754 -267.39215) (xy 48.89754 -266.58189)
				(arc
					(start 48.6537 -266.58189)
					(mid 48.387 -266.846062)
					(end 48.1203 -266.58189)
				)
				(arc
					(start 48.1203 -266.57935)
					(mid 48.387 -266.31265)
					(end 48.6537 -266.57935)
				)
			)
		)
	)
	(zone
		(layers "In2.Cu" "In5.Cu")
		(hatch none 0.5)
		(connect_pads
			(clearance 0)
		)
		(min_thickness 0.25)
		(keepout
			(tracks not_allowed)
			(vias allowed)
			(pads allowed)
			(copperpour not_allowed)
			(footprints allowed)
		)
		(placement
			(enabled no)
			(sheetname "")
		)
		(fill yes
			(thermal_gap 0.5)
			(thermal_bridge_width 0.5)
			(island_removal_mode 0)
		)
		(polygon
			(pts
				(arc
					(start 32.26054 -444.584836)
					(mid 31.75 -444.074296)
					(end 31.23946 -444.584836)
				)
				(arc
					(start 31.23946 -445.397636)
					(mid 31.74873 -445.908174)
					(end 32.26054 -445.400176)
				)
				(arc
					(start 32.0167 -445.400176)
					(mid 31.75 -445.664348)
					(end 31.4833 -445.400176)
				)
				(arc
					(start 31.4833 -445.397636)
					(mid 31.75 -445.130936)
					(end 32.0167 -445.397636)
				)
				(xy 32.26054 -445.397636) (xy 32.26054 -444.587376)
				(arc
					(start 32.0167 -444.587376)
					(mid 31.75 -444.851548)
					(end 31.4833 -444.587376)
				)
				(arc
					(start 31.4833 -444.584836)
					(mid 31.75 -444.318136)
					(end 32.0167 -444.584836)
				)
			)
		)
	)
	(zone
		(layers "In2.Cu" "In5.Cu")
		(hatch none 0.5)
		(connect_pads
			(clearance 0)
		)
		(min_thickness 0.25)
		(keepout
			(tracks not_allowed)
			(vias allowed)
			(pads allowed)
			(copperpour not_allowed)
			(footprints allowed)
		)
		(placement
			(enabled no)
			(sheetname "")
		)
		(fill yes
			(thermal_gap 0.5)
			(thermal_bridge_width 0.5)
			(island_removal_mode 0)
		)
		(polygon
			(pts
				(arc
					(start 229.907084 -471.279728)
					(mid 229.396544 -471.790268)
					(end 229.907084 -472.300808)
				)
				(arc
					(start 230.71963 -472.300808)
					(mid 231.079901 -472.152261)
					(end 231.230424 -471.792808)
				)
				(arc
					(start 230.986584 -471.792808)
					(mid 230.719884 -472.05698)
					(end 230.453184 -471.792808)
				)
				(arc
					(start 230.173784 -471.792808)
					(mid 229.907084 -472.05698)
					(end 229.640384 -471.792808)
				)
				(arc
					(start 229.640384 -471.790268)
					(mid 229.907084 -471.523568)
					(end 230.173784 -471.790268)
				)
				(arc
					(start 230.453184 -471.790268)
					(mid 230.719884 -471.523568)
					(end 230.986584 -471.790268)
				)
				(arc
					(start 231.230424 -471.790268)
					(mid 231.08089 -471.429262)
					(end 230.719884 -471.279728)
				)
			)
		)
	)
	(zone
		(layers "In2.Cu" "In5.Cu")
		(hatch none 0.5)
		(connect_pads
			(clearance 0)
		)
		(min_thickness 0.25)
		(keepout
			(tracks not_allowed)
			(vias allowed)
			(pads allowed)
			(copperpour not_allowed)
			(footprints allowed)
		)
		(placement
			(enabled no)
			(sheetname "")
		)
		(fill yes
			(thermal_gap 0.5)
			(thermal_bridge_width 0.5)
			(island_removal_mode 0)
		)
		(polygon
			(pts
				(arc
					(start 233.897424 -163.579302)
					(mid 233.386884 -163.068762)
					(end 232.876344 -163.579302)
				)
				(arc
					(start 232.876344 -164.391848)
					(mid 233.385487 -164.90264)
					(end 233.897424 -164.394642)
				)
				(arc
					(start 233.653584 -164.394642)
					(mid 233.386884 -164.658814)
					(end 233.120184 -164.394642)
				)
				(arc
					(start 233.120184 -164.392102)
					(mid 233.386884 -164.125402)
					(end 233.653584 -164.392102)
				)
				(xy 233.897424 -164.392102) (xy 233.897424 -163.581842)
				(arc
					(start 233.653584 -163.581842)
					(mid 233.386884 -163.846014)
					(end 233.120184 -163.581842)
				)
				(arc
					(start 233.120184 -163.579302)
					(mid 233.386884 -163.312602)
					(end 233.653584 -163.579302)
				)
			)
		)
	)
	(zone
		(layers "In2.Cu" "In5.Cu")
		(hatch none 0.5)
		(connect_pads
			(clearance 0)
		)
		(min_thickness 0.25)
		(keepout
			(tracks not_allowed)
			(vias allowed)
			(pads allowed)
			(copperpour not_allowed)
			(footprints allowed)
		)
		(placement
			(enabled no)
			(sheetname "")
		)
		(fill yes
			(thermal_gap 0.5)
			(thermal_bridge_width 0.5)
			(island_removal_mode 0)
		)
		(polygon
			(pts
				(arc
					(start 233.897424 -369.579398)
					(mid 233.386884 -369.068858)
					(end 232.876344 -369.579398)
				)
				(arc
					(start 232.876344 -370.391944)
					(mid 233.385487 -370.902736)
					(end 233.897424 -370.394738)
				)
				(arc
					(start 233.653584 -370.394738)
					(mid 233.386884 -370.65891)
					(end 233.120184 -370.394738)
				)
				(arc
					(start 233.120184 -370.392198)
					(mid 233.386884 -370.125498)
					(end 233.653584 -370.392198)
				)
				(xy 233.897424 -370.392198) (xy 233.897424 -369.581938)
				(arc
					(start 233.653584 -369.581938)
					(mid 233.386884 -369.84611)
					(end 233.120184 -369.581938)
				)
				(arc
					(start 233.120184 -369.579398)
					(mid 233.386884 -369.312698)
					(end 233.653584 -369.579398)
				)
			)
		)
	)
	(zone
		(layers "In2.Cu" "In5.Cu")
		(hatch none 0.5)
		(connect_pads
			(clearance 0)
		)
		(min_thickness 0.25)
		(keepout
			(tracks not_allowed)
			(vias allowed)
			(pads allowed)
			(copperpour not_allowed)
			(footprints allowed)
		)
		(placement
			(enabled no)
			(sheetname "")
		)
		(fill yes
			(thermal_gap 0.5)
			(thermal_bridge_width 0.5)
			(island_removal_mode 0)
		)
		(polygon
			(pts
				(arc
					(start 33.40354 -341.584534)
					(mid 32.893 -341.073994)
					(end 32.38246 -341.584534)
				)
				(arc
					(start 32.38246 -342.397334)
					(mid 32.89173 -342.907872)
					(end 33.40354 -342.399874)
				)
				(arc
					(start 33.1597 -342.399874)
					(mid 32.893 -342.664046)
					(end 32.6263 -342.399874)
				)
				(arc
					(start 32.6263 -342.397334)
					(mid 32.893 -342.130634)
					(end 33.1597 -342.397334)
				)
				(xy 33.40354 -342.397334) (xy 33.40354 -341.587074)
				(arc
					(start 33.1597 -341.587074)
					(mid 32.893 -341.851246)
					(end 32.6263 -341.587074)
				)
				(arc
					(start 32.6263 -341.584534)
					(mid 32.893 -341.317834)
					(end 33.1597 -341.584534)
				)
			)
		)
	)
	(zone
		(layers "In2.Cu" "In5.Cu")
		(hatch none 0.5)
		(connect_pads
			(clearance 0)
		)
		(min_thickness 0.25)
		(keepout
			(tracks not_allowed)
			(vias allowed)
			(pads allowed)
			(copperpour not_allowed)
			(footprints allowed)
		)
		(placement
			(enabled no)
			(sheetname "")
		)
		(fill yes
			(thermal_gap 0.5)
			(thermal_bridge_width 0.5)
			(island_removal_mode 0)
		)
		(polygon
			(pts
				(arc
					(start 48.89754 -163.579302)
					(mid 48.387 -163.068762)
					(end 47.87646 -163.579302)
				)
				(arc
					(start 47.87646 -164.392102)
					(mid 48.38573 -164.90264)
					(end 48.89754 -164.394642)
				)
				(arc
					(start 48.6537 -164.394642)
					(mid 48.387 -164.658814)
					(end 48.1203 -164.394642)
				)
				(arc
					(start 48.1203 -164.392102)
					(mid 48.387 -164.125402)
					(end 48.6537 -164.392102)
				)
				(xy 48.89754 -164.392102) (xy 48.89754 -163.581842)
				(arc
					(start 48.6537 -163.581842)
					(mid 48.387 -163.846014)
					(end 48.1203 -163.581842)
				)
				(arc
					(start 48.1203 -163.579302)
					(mid 48.387 -163.312602)
					(end 48.6537 -163.579302)
				)
			)
		)
	)
	(zone
		(layers "In2.Cu" "In5.Cu")
		(hatch none 0.5)
		(connect_pads
			(clearance 0)
		)
		(min_thickness 0.25)
		(keepout
			(tracks not_allowed)
			(vias allowed)
			(pads allowed)
			(copperpour not_allowed)
			(footprints allowed)
		)
		(placement
			(enabled no)
			(sheetname "")
		)
		(fill yes
			(thermal_gap 0.5)
			(thermal_bridge_width 0.5)
			(island_removal_mode 0)
		)
		(polygon
			(pts
				(arc
					(start 44.9072 -471.279728)
					(mid 44.39666 -471.790268)
					(end 44.9072 -472.300808)
				)
				(arc
					(start 45.719746 -472.300808)
					(mid 46.080017 -472.152261)
					(end 46.23054 -471.792808)
				)
				(arc
					(start 45.9867 -471.792808)
					(mid 45.72 -472.05698)
					(end 45.4533 -471.792808)
				)
				(arc
					(start 45.1739 -471.792808)
					(mid 44.9072 -472.05698)
					(end 44.6405 -471.792808)
				)
				(arc
					(start 44.6405 -471.790268)
					(mid 44.9072 -471.523568)
					(end 45.1739 -471.790268)
				)
				(arc
					(start 45.4533 -471.790268)
					(mid 45.72 -471.523568)
					(end 45.9867 -471.790268)
				)
				(arc
					(start 46.23054 -471.790268)
					(mid 46.081006 -471.429262)
					(end 45.72 -471.279728)
				)
			)
		)
	)
	(zone
		(layers "In2.Cu" "In5.Cu")
		(hatch none 0.5)
		(connect_pads
			(clearance 0)
		)
		(min_thickness 0.25)
		(keepout
			(tracks not_allowed)
			(vias allowed)
			(pads allowed)
			(copperpour not_allowed)
			(footprints allowed)
		)
		(placement
			(enabled no)
			(sheetname "")
		)
		(fill yes
			(thermal_gap 0.5)
			(thermal_bridge_width 0.5)
			(island_removal_mode 0)
		)
		(polygon
			(pts
				(arc
					(start 32.00654 -135.603742)
					(mid 31.496 -135.093202)
					(end 30.98546 -135.603742)
				)
				(arc
					(start 30.98546 -136.416542)
					(mid 31.49473 -136.92708)
					(end 32.00654 -136.419082)
				)
				(arc
					(start 31.7627 -136.419082)
					(mid 31.496 -136.683254)
					(end 31.2293 -136.419082)
				)
				(arc
					(start 31.2293 -136.416542)
					(mid 31.496 -136.149842)
					(end 31.7627 -136.416542)
				)
				(xy 32.00654 -136.416542) (xy 32.00654 -135.606282)
				(arc
					(start 31.7627 -135.606282)
					(mid 31.496 -135.870454)
					(end 31.2293 -135.606282)
				)
				(arc
					(start 31.2293 -135.603742)
					(mid 31.496 -135.337042)
					(end 31.7627 -135.603742)
				)
			)
		)
	)
	(zone
		(layers "In2.Cu" "In5.Cu")
		(hatch none 0.5)
		(connect_pads
			(clearance 0)
		)
		(min_thickness 0.25)
		(keepout
			(tracks not_allowed)
			(vias allowed)
			(pads allowed)
			(copperpour not_allowed)
			(footprints allowed)
		)
		(placement
			(enabled no)
			(sheetname "")
		)
		(fill yes
			(thermal_gap 0.5)
			(thermal_bridge_width 0.5)
			(island_removal_mode 0)
		)
		(polygon
			(pts
				(arc
					(start 229.907084 -162.279584)
					(mid 229.396544 -162.790124)
					(end 229.907084 -163.300664)
				)
				(arc
					(start 230.71963 -163.300664)
					(mid 231.079901 -163.152117)
					(end 231.230424 -162.792664)
				)
				(arc
					(start 230.986584 -162.792664)
					(mid 230.719884 -163.056836)
					(end 230.453184 -162.792664)
				)
				(arc
					(start 230.173784 -162.792664)
					(mid 229.907084 -163.056836)
					(end 229.640384 -162.792664)
				)
				(arc
					(start 229.640384 -162.790124)
					(mid 229.907084 -162.523424)
					(end 230.173784 -162.790124)
				)
				(arc
					(start 230.453184 -162.790124)
					(mid 230.719884 -162.523424)
					(end 230.986584 -162.790124)
				)
				(arc
					(start 231.230424 -162.790124)
					(mid 231.08089 -162.429118)
					(end 230.719884 -162.279584)
				)
			)
		)
	)
	(zone
		(layers "In2.Cu" "In5.Cu")
		(hatch none 0.5)
		(connect_pads
			(clearance 0)
		)
		(min_thickness 0.25)
		(keepout
			(tracks not_allowed)
			(vias allowed)
			(pads allowed)
			(copperpour not_allowed)
			(footprints allowed)
		)
		(placement
			(enabled no)
			(sheetname "")
		)
		(fill yes
			(thermal_gap 0.5)
			(thermal_bridge_width 0.5)
			(island_removal_mode 0)
		)
		(polygon
			(pts
				(arc
					(start 229.907084 -368.27968)
					(mid 229.396544 -368.79022)
					(end 229.907084 -369.30076)
				)
				(arc
					(start 230.71963 -369.30076)
					(mid 231.079901 -369.152213)
					(end 231.230424 -368.79276)
				)
				(arc
					(start 230.986584 -368.79276)
					(mid 230.719884 -369.056932)
					(end 230.453184 -368.79276)
				)
				(arc
					(start 230.173784 -368.79276)
					(mid 229.907084 -369.056932)
					(end 229.640384 -368.79276)
				)
				(arc
					(start 229.640384 -368.79022)
					(mid 229.907084 -368.52352)
					(end 230.173784 -368.79022)
				)
				(arc
					(start 230.453184 -368.79022)
					(mid 230.719884 -368.52352)
					(end 230.986584 -368.79022)
				)
				(arc
					(start 231.230424 -368.79022)
					(mid 231.08089 -368.429214)
					(end 230.719884 -368.27968)
				)
			)
		)
	)
	(zone
		(layers "In2.Cu" "In5.Cu")
		(hatch none 0.5)
		(connect_pads
			(clearance 0)
		)
		(min_thickness 0.25)
		(keepout
			(tracks not_allowed)
			(vias allowed)
			(pads allowed)
			(copperpour not_allowed)
			(footprints allowed)
		)
		(placement
			(enabled no)
			(sheetname "")
		)
		(fill yes
			(thermal_gap 0.5)
			(thermal_bridge_width 0.5)
			(island_removal_mode 0)
		)
		(polygon
			(pts
				(arc
					(start 8.382254 -385.092702)
					(mid 7.871714 -385.603242)
					(end 8.382254 -386.113782)
				)
				(arc
					(start 9.1948 -386.113782)
					(mid 9.555071 -385.965235)
					(end 9.705594 -385.605782)
				)
				(arc
					(start 9.461754 -385.605782)
					(mid 9.195054 -385.869954)
					(end 8.928354 -385.605782)
				)
				(arc
					(start 8.648954 -385.605782)
					(mid 8.382254 -385.869954)
					(end 8.115554 -385.605782)
				)
				(arc
					(start 8.115554 -385.603242)
					(mid 8.382254 -385.336542)
					(end 8.648954 -385.603242)
				)
				(arc
					(start 8.928354 -385.603242)
					(mid 9.195054 -385.336542)
					(end 9.461754 -385.603242)
				)
				(arc
					(start 9.705594 -385.603242)
					(mid 9.55606 -385.242236)
					(end 9.195054 -385.092702)
				)
			)
		)
	)
	(zone
		(layers "In2.Cu" "In5.Cu")
		(hatch none 0.5)
		(connect_pads
			(clearance 0)
		)
		(min_thickness 0.25)
		(keepout
			(tracks not_allowed)
			(vias allowed)
			(pads allowed)
			(copperpour not_allowed)
			(footprints allowed)
		)
		(placement
			(enabled no)
			(sheetname "")
		)
		(fill yes
			(thermal_gap 0.5)
			(thermal_bridge_width 0.5)
			(island_removal_mode 0)
		)
		(polygon
			(pts
				(arc
					(start 72.90054 -431.1396)
					(mid 72.39 -430.62906)
					(end 71.87946 -431.1396)
				)
				(arc
					(start 71.87946 -431.9524)
					(mid 72.38873 -432.462938)
					(end 72.90054 -431.95494)
				)
				(arc
					(start 72.6567 -431.95494)
					(mid 72.39 -432.219112)
					(end 72.1233 -431.95494)
				)
				(arc
					(start 72.1233 -431.9524)
					(mid 72.39 -431.6857)
					(end 72.6567 -431.9524)
				)
				(xy 72.90054 -431.9524) (xy 72.90054 -431.14214)
				(arc
					(start 72.6567 -431.14214)
					(mid 72.39 -431.406312)
					(end 72.1233 -431.14214)
				)
				(arc
					(start 72.1233 -431.1396)
					(mid 72.39 -430.8729)
					(end 72.6567 -431.1396)
				)
			)
		)
	)
	(zone
		(layers "In2.Cu" "In5.Cu")
		(hatch none 0.5)
		(connect_pads
			(clearance 0)
		)
		(min_thickness 0.25)
		(keepout
			(tracks not_allowed)
			(vias allowed)
			(pads allowed)
			(copperpour not_allowed)
			(footprints allowed)
		)
		(placement
			(enabled no)
			(sheetname "")
		)
		(fill yes
			(thermal_gap 0.5)
			(thermal_bridge_width 0.5)
			(island_removal_mode 0)
		)
		(polygon
			(pts
				(arc
					(start 17.78254 -341.60333)
					(mid 17.272 -341.09279)
					(end 16.76146 -341.60333)
				)
				(arc
					(start 16.76146 -342.415876)
					(mid 17.270603 -342.926668)
					(end 17.78254 -342.41867)
				)
				(arc
					(start 17.5387 -342.41867)
					(mid 17.272 -342.682842)
					(end 17.0053 -342.41867)
				)
				(arc
					(start 17.0053 -342.41613)
					(mid 17.272 -342.14943)
					(end 17.5387 -342.41613)
				)
				(xy 17.78254 -342.41613) (xy 17.78254 -341.60587)
				(arc
					(start 17.5387 -341.60587)
					(mid 17.272 -341.870042)
					(end 17.0053 -341.60587)
				)
				(arc
					(start 17.0053 -341.60333)
					(mid 17.272 -341.33663)
					(end 17.5387 -341.60333)
				)
			)
		)
	)
	(zone
		(layers "In2.Cu" "In5.Cu")
		(hatch none 0.5)
		(connect_pads
			(clearance 0)
		)
		(min_thickness 0.25)
		(keepout
			(tracks not_allowed)
			(vias allowed)
			(pads allowed)
			(copperpour not_allowed)
			(footprints allowed)
		)
		(placement
			(enabled no)
			(sheetname "")
		)
		(fill yes
			(thermal_gap 0.5)
			(thermal_bridge_width 0.5)
			(island_removal_mode 0)
		)
		(polygon
			(pts
				(arc
					(start 229.907084 -265.279632)
					(mid 229.396544 -265.790172)
					(end 229.907084 -266.300712)
				)
				(arc
					(start 230.71963 -266.300712)
					(mid 231.079901 -266.152165)
					(end 231.230424 -265.792712)
				)
				(arc
					(start 230.986584 -265.792712)
					(mid 230.719884 -266.056884)
					(end 230.453184 -265.792712)
				)
				(arc
					(start 230.173784 -265.792712)
					(mid 229.907084 -266.056884)
					(end 229.640384 -265.792712)
				)
				(arc
					(start 229.640384 -265.790172)
					(mid 229.907084 -265.523472)
					(end 230.173784 -265.790172)
				)
				(arc
					(start 230.453184 -265.790172)
					(mid 230.719884 -265.523472)
					(end 230.986584 -265.790172)
				)
				(arc
					(start 231.230424 -265.790172)
					(mid 231.08089 -265.429166)
					(end 230.719884 -265.279632)
				)
			)
		)
	)
	(zone
		(layers "In2.Cu" "In5.Cu")
		(hatch none 0.5)
		(connect_pads
			(clearance 0)
		)
		(min_thickness 0.25)
		(keepout
			(tracks not_allowed)
			(vias allowed)
			(pads allowed)
			(copperpour not_allowed)
			(footprints allowed)
		)
		(placement
			(enabled no)
			(sheetname "")
		)
		(fill yes
			(thermal_gap 0.5)
			(thermal_bridge_width 0.5)
			(island_removal_mode 0)
		)
		(polygon
			(pts
				(arc
					(start 48.89754 -472.579446)
					(mid 48.387 -472.068906)
					(end 47.87646 -472.579446)
				)
				(arc
					(start 47.87646 -473.392246)
					(mid 48.38573 -473.902784)
					(end 48.89754 -473.394786)
				)
				(arc
					(start 48.6537 -473.394786)
					(mid 48.387 -473.658958)
					(end 48.1203 -473.394786)
				)
				(arc
					(start 48.1203 -473.392246)
					(mid 48.387 -473.125546)
					(end 48.6537 -473.392246)
				)
				(xy 48.89754 -473.392246) (xy 48.89754 -472.581986)
				(arc
					(start 48.6537 -472.581986)
					(mid 48.387 -472.846158)
					(end 48.1203 -472.581986)
				)
				(arc
					(start 48.1203 -472.579446)
					(mid 48.387 -472.312746)
					(end 48.6537 -472.579446)
				)
			)
		)
	)
	(zone
		(layers "In2.Cu" "In5.Cu")
		(hatch none 0.5)
		(connect_pads
			(clearance 0)
		)
		(min_thickness 0.25)
		(keepout
			(tracks not_allowed)
			(vias allowed)
			(pads allowed)
			(copperpour not_allowed)
			(footprints allowed)
		)
		(placement
			(enabled no)
			(sheetname "")
		)
		(fill yes
			(thermal_gap 0.5)
			(thermal_bridge_width 0.5)
			(island_removal_mode 0)
		)
		(polygon
			(pts
				(arc
					(start 17.78254 -135.603234)
					(mid 17.272 -135.092694)
					(end 16.76146 -135.603234)
				)
				(arc
					(start 16.76146 -136.41578)
					(mid 17.270603 -136.926572)
					(end 17.78254 -136.418574)
				)
				(arc
					(start 17.5387 -136.418574)
					(mid 17.272 -136.682746)
					(end 17.0053 -136.418574)
				)
				(arc
					(start 17.0053 -136.416034)
					(mid 17.272 -136.149334)
					(end 17.5387 -136.416034)
				)
				(xy 17.78254 -136.416034) (xy 17.78254 -135.605774)
				(arc
					(start 17.5387 -135.605774)
					(mid 17.272 -135.869946)
					(end 17.0053 -135.605774)
				)
				(arc
					(start 17.0053 -135.603234)
					(mid 17.272 -135.336534)
					(end 17.5387 -135.603234)
				)
			)
		)
	)
	(zone
		(layers "In2.Cu" "In5.Cu")
		(hatch none 0.5)
		(connect_pads
			(clearance 0)
		)
		(min_thickness 0.25)
		(keepout
			(tracks not_allowed)
			(vias allowed)
			(pads allowed)
			(copperpour not_allowed)
			(footprints allowed)
		)
		(placement
			(enabled no)
			(sheetname "")
		)
		(fill yes
			(thermal_gap 0.5)
			(thermal_bridge_width 0.5)
			(island_removal_mode 0)
		)
		(polygon
			(pts
				(arc
					(start 74.269854 -429.61306)
					(mid 73.75906 -430.123473)
					(end 74.2696 -430.63414)
				)
				(arc
					(start 75.0824 -430.63414)
					(mid 75.442507 -430.485503)
					(end 75.59294 -430.12614)
				)
				(arc
					(start 75.3491 -430.12614)
					(mid 75.0824 -430.390312)
					(end 74.8157 -430.12614)
				)
				(arc
					(start 74.5363 -430.12614)
					(mid 74.2696 -430.390312)
					(end 74.0029 -430.12614)
				)
				(arc
					(start 74.0029 -430.1236)
					(mid 74.2696 -429.8569)
					(end 74.5363 -430.1236)
				)
				(arc
					(start 74.8157 -430.1236)
					(mid 75.0824 -429.8569)
					(end 75.3491 -430.1236)
				)
				(arc
					(start 75.59294 -430.1236)
					(mid 75.443406 -429.762594)
					(end 75.0824 -429.61306)
				)
			)
		)
	)
	(zone
		(layers "In2.Cu" "In5.Cu")
		(hatch none 0.5)
		(connect_pads
			(clearance 0)
		)
		(min_thickness 0.25)
		(keepout
			(tracks not_allowed)
			(vias allowed)
			(pads allowed)
			(copperpour not_allowed)
			(footprints allowed)
		)
		(placement
			(enabled no)
			(sheetname "")
		)
		(fill yes
			(thermal_gap 0.5)
			(thermal_bridge_width 0.5)
			(island_removal_mode 0)
		)
		(polygon
			(pts
				(arc
					(start 48.89754 -60.579254)
					(mid 48.387 -60.068714)
					(end 47.87646 -60.579254)
				)
				(arc
					(start 47.87646 -61.392054)
					(mid 48.38573 -61.902592)
					(end 48.89754 -61.394594)
				)
				(arc
					(start 48.6537 -61.394594)
					(mid 48.387 -61.658766)
					(end 48.1203 -61.394594)
				)
				(arc
					(start 48.1203 -61.392054)
					(mid 48.387 -61.125354)
					(end 48.6537 -61.392054)
				)
				(xy 48.89754 -61.392054) (xy 48.89754 -60.581794)
				(arc
					(start 48.6537 -60.581794)
					(mid 48.387 -60.845966)
					(end 48.1203 -60.581794)
				)
				(arc
					(start 48.1203 -60.579254)
					(mid 48.387 -60.312554)
					(end 48.6537 -60.579254)
				)
			)
		)
	)
	(zone
		(layers "In2.Cu" "In5.Cu")
		(hatch none 0.5)
		(connect_pads
			(clearance 0)
		)
		(min_thickness 0.25)
		(keepout
			(tracks not_allowed)
			(vias allowed)
			(pads allowed)
			(copperpour not_allowed)
			(footprints allowed)
		)
		(placement
			(enabled no)
			(sheetname "")
		)
		(fill yes
			(thermal_gap 0.5)
			(thermal_bridge_width 0.5)
			(island_removal_mode 0)
		)
		(polygon
			(pts
				(arc
					(start 233.897424 -60.579254)
					(mid 233.386884 -60.068714)
					(end 232.876344 -60.579254)
				)
				(arc
					(start 232.876344 -61.3918)
					(mid 233.385487 -61.902592)
					(end 233.897424 -61.394594)
				)
				(arc
					(start 233.653584 -61.394594)
					(mid 233.386884 -61.658766)
					(end 233.120184 -61.394594)
				)
				(arc
					(start 233.120184 -61.392054)
					(mid 233.386884 -61.125354)
					(end 233.653584 -61.392054)
				)
				(xy 233.897424 -61.392054) (xy 233.897424 -60.581794)
				(arc
					(start 233.653584 -60.581794)
					(mid 233.386884 -60.845966)
					(end 233.120184 -60.581794)
				)
				(arc
					(start 233.120184 -60.579254)
					(mid 233.386884 -60.312554)
					(end 233.653584 -60.579254)
				)
			)
		)
	)
	(zone
		(layers "In2.Cu" "In5.Cu")
		(hatch none 0.5)
		(connect_pads
			(clearance 0)
		)
		(min_thickness 0.25)
		(keepout
			(tracks not_allowed)
			(vias allowed)
			(pads allowed)
			(copperpour not_allowed)
			(footprints allowed)
		)
		(placement
			(enabled no)
			(sheetname "")
		)
		(fill yes
			(thermal_gap 0.5)
			(thermal_bridge_width 0.5)
			(island_removal_mode 0)
		)
		(polygon
			(pts
				(arc
					(start 44.907454 -368.27968)
					(mid 44.39666 -368.790093)
					(end 44.9072 -369.30076)
				)
				(arc
					(start 45.72 -369.30076)
					(mid 46.080107 -369.152123)
					(end 46.23054 -368.79276)
				)
				(arc
					(start 45.9867 -368.79276)
					(mid 45.72 -369.056932)
					(end 45.4533 -368.79276)
				)
				(arc
					(start 45.1739 -368.79276)
					(mid 44.9072 -369.056932)
					(end 44.6405 -368.79276)
				)
				(arc
					(start 44.6405 -368.79022)
					(mid 44.9072 -368.52352)
					(end 45.1739 -368.79022)
				)
				(arc
					(start 45.4533 -368.79022)
					(mid 45.72 -368.52352)
					(end 45.9867 -368.79022)
				)
				(arc
					(start 46.23054 -368.79022)
					(mid 46.081006 -368.429214)
					(end 45.72 -368.27968)
				)
			)
		)
	)
	(zone
		(layers "In2.Cu" "In5.Cu")
		(hatch none 0.5)
		(connect_pads
			(clearance 0)
		)
		(min_thickness 0.25)
		(keepout
			(tracks not_allowed)
			(vias allowed)
			(pads allowed)
			(copperpour not_allowed)
			(footprints allowed)
		)
		(placement
			(enabled no)
			(sheetname "")
		)
		(fill yes
			(thermal_gap 0.5)
			(thermal_bridge_width 0.5)
			(island_removal_mode 0)
		)
		(polygon
			(pts
				(arc
					(start 233.897424 -266.57935)
					(mid 233.386884 -266.06881)
					(end 232.876344 -266.57935)
				)
				(arc
					(start 232.876344 -267.391896)
					(mid 233.385487 -267.902688)
					(end 233.897424 -267.39469)
				)
				(arc
					(start 233.653584 -267.39469)
					(mid 233.386884 -267.658862)
					(end 233.120184 -267.39469)
				)
				(arc
					(start 233.120184 -267.39215)
					(mid 233.386884 -267.12545)
					(end 233.653584 -267.39215)
				)
				(xy 233.897424 -267.39215) (xy 233.897424 -266.58189)
				(arc
					(start 233.653584 -266.58189)
					(mid 233.386884 -266.846062)
					(end 233.120184 -266.58189)
				)
				(arc
					(start 233.120184 -266.57935)
					(mid 233.386884 -266.31265)
					(end 233.653584 -266.57935)
				)
			)
		)
	)
	(zone
		(layers "In2.Cu" "In5.Cu")
		(hatch none 0.5)
		(connect_pads
			(clearance 0)
		)
		(min_thickness 0.25)
		(keepout
			(tracks not_allowed)
			(vias allowed)
			(pads allowed)
			(copperpour not_allowed)
			(footprints allowed)
		)
		(placement
			(enabled no)
			(sheetname "")
		)
		(fill yes
			(thermal_gap 0.5)
			(thermal_bridge_width 0.5)
			(island_removal_mode 0)
		)
		(polygon
			(pts
				(arc
					(start 42.92854 -238.584486)
					(mid 42.418 -238.073946)
					(end 41.90746 -238.584486)
				)
				(arc
					(start 41.90746 -239.397286)
					(mid 42.41673 -239.907824)
					(end 42.92854 -239.399826)
				)
				(arc
					(start 42.6847 -239.399826)
					(mid 42.418 -239.663998)
					(end 42.1513 -239.399826)
				)
				(arc
					(start 42.1513 -239.397286)
					(mid 42.418 -239.130586)
					(end 42.6847 -239.397286)
				)
				(xy 42.92854 -239.397286) (xy 42.92854 -238.587026)
				(arc
					(start 42.6847 -238.587026)
					(mid 42.418 -238.851198)
					(end 42.1513 -238.587026)
				)
				(arc
					(start 42.1513 -238.584486)
					(mid 42.418 -238.317786)
					(end 42.6847 -238.584486)
				)
			)
		)
	)
	(zone
		(layers "In2.Cu" "In5.Cu")
		(hatch none 0.5)
		(connect_pads
			(clearance 0)
		)
		(min_thickness 0.25)
		(keepout
			(tracks not_allowed)
			(vias allowed)
			(pads allowed)
			(copperpour not_allowed)
			(footprints allowed)
		)
		(placement
			(enabled no)
			(sheetname "")
		)
		(fill yes
			(thermal_gap 0.5)
			(thermal_bridge_width 0.5)
			(island_removal_mode 0)
		)
		(polygon
			(pts
				(arc
					(start 17.78254 -444.603378)
					(mid 17.272 -444.092838)
					(end 16.76146 -444.603378)
				)
				(arc
					(start 16.76146 -445.415924)
					(mid 17.270603 -445.926716)
					(end 17.78254 -445.418718)
				)
				(arc
					(start 17.5387 -445.418718)
					(mid 17.272 -445.68289)
					(end 17.0053 -445.418718)
				)
				(arc
					(start 17.0053 -445.416178)
					(mid 17.272 -445.149478)
					(end 17.5387 -445.416178)
				)
				(xy 17.78254 -445.416178) (xy 17.78254 -444.605918)
				(arc
					(start 17.5387 -444.605918)
					(mid 17.272 -444.87009)
					(end 17.0053 -444.605918)
				)
				(arc
					(start 17.0053 -444.603378)
					(mid 17.272 -444.336678)
					(end 17.5387 -444.603378)
				)
			)
		)
	)
	(zone
		(layers "In2.Cu" "In5.Cu")
		(hatch none 0.5)
		(connect_pads
			(clearance 0)
		)
		(min_thickness 0.25)
		(keepout
			(tracks not_allowed)
			(vias allowed)
			(pads allowed)
			(copperpour not_allowed)
			(footprints allowed)
		)
		(placement
			(enabled no)
			(sheetname "")
		)
		(fill yes
			(thermal_gap 0.5)
			(thermal_bridge_width 0.5)
			(island_removal_mode 0)
		)
		(polygon
			(pts
				(arc
					(start 6.477254 -448.957192)
					(mid 5.96646 -449.467605)
					(end 6.477 -449.978272)
				)
				(arc
					(start 7.2898 -449.978272)
					(mid 7.649907 -449.829635)
					(end 7.80034 -449.470272)
				)
				(arc
					(start 7.5565 -449.470272)
					(mid 7.2898 -449.734444)
					(end 7.0231 -449.470272)
				)
				(arc
					(start 6.7437 -449.470272)
					(mid 6.477 -449.734444)
					(end 6.2103 -449.470272)
				)
				(arc
					(start 6.2103 -449.467732)
					(mid 6.477 -449.201032)
					(end 6.7437 -449.467732)
				)
				(arc
					(start 7.0231 -449.467732)
					(mid 7.2898 -449.201032)
					(end 7.5565 -449.467732)
				)
				(arc
					(start 7.80034 -449.467732)
					(mid 7.650806 -449.106726)
					(end 7.2898 -448.957192)
				)
			)
		)
	)
	(zone
		(layers "In2.Cu" "In5.Cu")
		(hatch none 0.5)
		(connect_pads
			(clearance 0)
		)
		(min_thickness 0.25)
		(keepout
			(tracks not_allowed)
			(vias allowed)
			(pads allowed)
			(copperpour not_allowed)
			(footprints allowed)
		)
		(placement
			(enabled no)
			(sheetname "")
		)
		(fill yes
			(thermal_gap 0.5)
			(thermal_bridge_width 0.5)
			(island_removal_mode 0)
		)
		(polygon
			(pts
				(arc
					(start 229.907084 -59.279536)
					(mid 229.396544 -59.790076)
					(end 229.907084 -60.300616)
				)
				(arc
					(start 230.71963 -60.300616)
					(mid 231.079901 -60.152069)
					(end 231.230424 -59.792616)
				)
				(arc
					(start 230.986584 -59.792616)
					(mid 230.719884 -60.056788)
					(end 230.453184 -59.792616)
				)
				(arc
					(start 230.173784 -59.792616)
					(mid 229.907084 -60.056788)
					(end 229.640384 -59.792616)
				)
				(arc
					(start 229.640384 -59.790076)
					(mid 229.907084 -59.523376)
					(end 230.173784 -59.790076)
				)
				(arc
					(start 230.453184 -59.790076)
					(mid 230.719884 -59.523376)
					(end 230.986584 -59.790076)
				)
				(arc
					(start 231.230424 -59.790076)
					(mid 231.08089 -59.42907)
					(end 230.719884 -59.279536)
				)
			)
		)
	)
	(zone
		(net "P12V")
		(layers "In2.Cu" "In5.Cu")
		(hatch none 0.5)
		(connect_pads
			(clearance 0.5)
		)
		(min_thickness 0.25)
		(fill yes
			(thermal_gap 0.5)
			(thermal_bridge_width 0.5)
			(island_removal_mode 0)
		)
		(polygon
			(pts
				(xy 7.0358 -462.8642) (xy 4.318 -462.8642) (xy 3.507486 -463.674714) (xy 3.507486 -466.902038) (xy 3.407156 -467.002368)
				(xy 2.719832 -467.002368) (xy 1.811274 -467.002368) (xy 1.56972 -467.243922) (xy 1.56972 -471.330528)
				(xy 1.764538 -471.525346) (xy 2.127504 -471.525346) (xy 3.587496 -471.525346) (xy 4.43611 -472.37396)
				(xy 4.43611 -473.748862) (xy 3.592576 -474.592396) (xy 2.530348 -474.592396) (xy 2.341118 -474.781626)
				(xy 2.341118 -476.813118) (xy 3.286252 -477.758252) (xy 8.134858 -477.758252) (xy 8.1534 -477.73971)
				(xy 8.1534 -466.3948) (xy 8.1534 -462.97977) (xy 8.03783 -462.8642)
			)
		)
	)
	(zone
		(layers "In2.Cu" "In5.Cu")
		(hatch none 0.5)
		(connect_pads
			(clearance 0)
		)
		(min_thickness 0.25)
		(keepout
			(tracks not_allowed)
			(vias allowed)
			(pads allowed)
			(copperpour not_allowed)
			(footprints allowed)
		)
		(placement
			(enabled no)
			(sheetname "")
		)
		(fill yes
			(thermal_gap 0.5)
			(thermal_bridge_width 0.5)
			(island_removal_mode 0)
		)
		(polygon
			(pts
				(arc
					(start 44.907454 -162.279584)
					(mid 44.39666 -162.789997)
					(end 44.9072 -163.300664)
				)
				(arc
					(start 45.72 -163.300664)
					(mid 46.080107 -163.152027)
					(end 46.23054 -162.792664)
				)
				(arc
					(start 45.9867 -162.792664)
					(mid 45.72 -163.056836)
					(end 45.4533 -162.792664)
				)
				(arc
					(start 45.1739 -162.792664)
					(mid 44.9072 -163.056836)
					(end 44.6405 -162.792664)
				)
				(arc
					(start 44.6405 -162.790124)
					(mid 44.9072 -162.523424)
					(end 45.1739 -162.790124)
				)
				(arc
					(start 45.4533 -162.790124)
					(mid 45.72 -162.523424)
					(end 45.9867 -162.790124)
				)
				(arc
					(start 46.23054 -162.790124)
					(mid 46.081006 -162.429118)
					(end 45.72 -162.279584)
				)
			)
		)
	)
	(zone
		(layers "In2.Cu" "In5.Cu")
		(hatch none 0.5)
		(connect_pads
			(clearance 0)
		)
		(min_thickness 0.25)
		(keepout
			(tracks not_allowed)
			(vias allowed)
			(pads allowed)
			(copperpour not_allowed)
			(footprints allowed)
		)
		(placement
			(enabled no)
			(sheetname "")
		)
		(fill yes
			(thermal_gap 0.5)
			(thermal_bridge_width 0.5)
			(island_removal_mode 0)
		)
		(polygon
			(pts
				(arc
					(start 233.897424 -472.579446)
					(mid 233.386884 -472.068906)
					(end 232.876344 -472.579446)
				)
				(arc
					(start 232.876344 -473.391992)
					(mid 233.385487 -473.902784)
					(end 233.897424 -473.394786)
				)
				(arc
					(start 233.653584 -473.394786)
					(mid 233.386884 -473.658958)
					(end 233.120184 -473.394786)
				)
				(arc
					(start 233.120184 -473.392246)
					(mid 233.386884 -473.125546)
					(end 233.653584 -473.392246)
				)
				(xy 233.897424 -473.392246) (xy 233.897424 -472.581986)
				(arc
					(start 233.653584 -472.581986)
					(mid 233.386884 -472.846158)
					(end 233.120184 -472.581986)
				)
				(arc
					(start 233.120184 -472.579446)
					(mid 233.386884 -472.312746)
					(end 233.653584 -472.579446)
				)
			)
		)
	)
	(zone
		(net "GND")
		(layer "In3.Cu")
		(hatch none 0.5)
		(connect_pads
			(clearance 0.5)
		)
		(min_thickness 0.25)
		(fill yes
			(thermal_gap 0.5)
			(thermal_bridge_width 0.5)
			(island_removal_mode 0)
		)
		(polygon
			(pts
				(arc
					(start 0.999998 -0.763016)
					(mid 0.832426 -0.832426)
					(end 0.763016 -0.999998)
				)
				(xy 0.763016 -186.42584) (xy 0.816102 -186.478926)
				(arc
					(start 4.400042 -186.478926)
					(mid 6.263132 -188.342016)
					(end 4.400042 -190.205106)
				)
				(xy 0.816102 -190.205106) (xy 0.763016 -190.258192) (xy 0.763016 -312.425842) (xy 0.816102 -312.478928)
				(arc
					(start 4.400042 -312.478928)
					(mid 6.263132 -314.342018)
					(end 4.400042 -316.205108)
				)
				(xy 0.816102 -316.205108) (xy 0.763016 -316.258194) (xy 0.763016 -418.425884) (xy 0.816102 -418.47897)
				(arc
					(start 4.400042 -418.47897)
					(mid 6.263132 -420.34206)
					(end 4.400042 -422.204896)
				)
				(xy 0.816356 -422.204896) (xy 0.763016 -422.258236)
				(arc
					(start 0.763016 -505.000006)
					(mid 0.832426 -505.167578)
					(end 0.999998 -505.236988)
				)
				(arc
					(start 262.50011 -505.236988)
					(mid 262.667682 -505.167578)
					(end 262.737092 -505.000006)
				)
				(xy 262.737092 -428.396146) (xy 262.18388 -427.842934)
				(arc
					(start 261.2898 -427.842934)
					(mid 259.767467 -427.212363)
					(end 259.136896 -425.69003)
				)
				(xy 259.136896 -411.80131) (xy 258.583684 -411.248098)
				(arc
					(start 252.394974 -411.248098)
					(mid 251.097034 -409.950158)
					(end 252.394974 -408.651964)
				)
				(xy 258.583684 -408.651964) (xy 259.136896 -408.098752)
				(arc
					(start 259.136896 -364.309914)
					(mid 259.767541 -362.787655)
					(end 261.2898 -362.15701)
				)
				(xy 262.18388 -362.15701) (xy 262.737092 -361.603798)
				(arc
					(start 262.737092 -0.999998)
					(mid 262.667682 -0.832426)
					(end 262.50011 -0.763016)
				)
				(xy 37.667692 -0.763016)
				(arc
					(start 36.343336 -3.365754)
					(mid 36.283478 -3.527891)
					(end 36.263072 -3.69951)
				)
				(arc
					(start 36.263072 -4.500118)
					(mid 34.000186 -6.763004)
					(end 31.737046 -4.500118)
				)
				(arc
					(start 31.737046 -3.700018)
					(mid 31.716858 -3.528435)
					(end 31.65729 -3.366262)
				)
				(xy 31.657036 -3.366262) (xy 30.332426 -0.763016)
			)
		)
		(polygon
			(pts
				(arc
					(start 37.33927 -491.231428)
					(mid 36.72713 -490.619288)
					(end 36.11499 -491.231428)
				)
				(arc
					(start 36.11499 -492.349282)
					(mid 36.727257 -492.961168)
					(end 37.33927 -492.349028)
				)
			)
		)
		(polygon
			(pts
				(arc
					(start 222.339154 -491.231174)
					(mid 221.726887 -490.619288)
					(end 221.114874 -491.231428)
				)
				(arc
					(start 221.114874 -492.349028)
					(mid 221.727014 -492.961168)
					(end 222.339154 -492.349028)
				)
			)
		)
		(polygon
			(pts
				(arc
					(start 35.84067 -488.983782)
					(mid 35.33013 -488.473242)
					(end 34.81959 -488.983782)
				)
				(arc
					(start 34.81959 -489.796836)
					(mid 35.330257 -490.307122)
					(end 35.84067 -489.796582)
				)
			)
		)
		(polygon
			(pts
				(arc
					(start 220.840554 -488.983528)
					(mid 220.329887 -488.473242)
					(end 219.819474 -488.983782)
				)
				(arc
					(start 219.819474 -489.796582)
					(mid 220.330014 -490.307122)
					(end 220.840554 -489.796582)
				)
			)
		)
		(polygon
			(pts
				(arc
					(start 222.339154 -486.431082)
					(mid 221.726887 -485.819196)
					(end 221.114874 -486.431336)
				)
				(arc
					(start 221.114874 -487.548936)
					(mid 221.727014 -488.161076)
					(end 222.339154 -487.548936)
				)
			)
		)
		(polygon
			(pts
				(arc
					(start 37.33927 -486.431082)
					(mid 36.727003 -485.819196)
					(end 36.11499 -486.431336)
				)
				(arc
					(start 36.11499 -487.548936)
					(mid 36.72713 -488.161076)
					(end 37.33927 -487.548936)
				)
			)
		)
		(polygon
			(pts
				(arc
					(start 35.84067 -484.18369)
					(mid 35.33013 -483.67315)
					(end 34.81959 -484.18369)
				)
				(arc
					(start 34.81959 -484.996744)
					(mid 35.330257 -485.50703)
					(end 35.84067 -484.99649)
				)
			)
		)
		(polygon
			(pts
				(arc
					(start 220.840554 -484.183436)
					(mid 220.329887 -483.67315)
					(end 219.819474 -484.18369)
				)
				(arc
					(start 219.819474 -484.99649)
					(mid 220.330014 -485.50703)
					(end 220.840554 -484.99649)
				)
			)
		)
		(polygon
			(pts
				(arc
					(start 37.33927 -481.631244)
					(mid 36.72713 -481.019104)
					(end 36.11499 -481.631244)
				)
				(arc
					(start 36.11499 -482.749098)
					(mid 36.727257 -483.360984)
					(end 37.33927 -482.748844)
				)
			)
		)
		(polygon
			(pts
				(arc
					(start 222.339154 -481.63099)
					(mid 221.726887 -481.019104)
					(end 221.114874 -481.631244)
				)
				(arc
					(start 221.114874 -482.748844)
					(mid 221.727014 -483.360984)
					(end 222.339154 -482.748844)
				)
			)
		)
		(polygon
			(pts
				(arc
					(start 35.84067 -479.383852)
					(mid 35.33013 -478.873312)
					(end 34.81959 -479.383852)
				)
				(arc
					(start 34.81959 -480.196906)
					(mid 35.330257 -480.707192)
					(end 35.84067 -480.196652)
				)
			)
		)
		(polygon
			(pts
				(arc
					(start 220.840554 -479.383598)
					(mid 220.329887 -478.873312)
					(end 219.819474 -479.383852)
				)
				(arc
					(start 219.819474 -480.196652)
					(mid 220.330014 -480.707192)
					(end 220.840554 -480.196652)
				)
			)
		)
		(polygon
			(pts
				(arc
					(start 233.897424 -472.579446)
					(mid 233.386884 -472.068906)
					(end 232.876344 -472.579446)
				)
				(arc
					(start 232.876344 -473.3925)
					(mid 233.387011 -473.902786)
					(end 233.897424 -473.392246)
				)
			)
		)
		(polygon
			(pts
				(arc
					(start 48.89754 -472.579192)
					(mid 48.386873 -472.068906)
					(end 47.87646 -472.579446)
				)
				(arc
					(start 47.87646 -473.392246)
					(mid 48.387 -473.902786)
					(end 48.89754 -473.392246)
				)
			)
		)
		(polygon
			(pts
				(arc
					(start 230.720138 -472.300808)
					(mid 231.230424 -471.790141)
					(end 230.719884 -471.279728)
				)
				(arc
					(start 229.907084 -471.279728)
					(mid 229.396544 -471.790268)
					(end 229.907084 -472.300808)
				)
			)
		)
		(polygon
			(pts
				(arc
					(start 45.720254 -472.300808)
					(mid 46.23054 -471.790141)
					(end 45.72 -471.279728)
				)
				(arc
					(start 44.9072 -471.279728)
					(mid 44.39666 -471.790268)
					(end 44.9072 -472.300808)
				)
			)
		)
		(polygon
			(pts
				(arc
					(start 37.33927 -468.831422)
					(mid 36.72713 -468.219282)
					(end 36.11499 -468.831422)
				)
				(arc
					(start 36.11499 -469.949276)
					(mid 36.727257 -470.561162)
					(end 37.33927 -469.949022)
				)
			)
		)
		(polygon
			(pts
				(arc
					(start 222.339154 -468.831168)
					(mid 221.726887 -468.219282)
					(end 221.114874 -468.831422)
				)
				(arc
					(start 221.114874 -469.949022)
					(mid 221.727014 -470.561162)
					(end 222.339154 -469.949022)
				)
			)
		)
		(polygon
			(pts
				(arc
					(start 35.84067 -466.583776)
					(mid 35.33013 -466.073236)
					(end 34.81959 -466.583776)
				)
				(arc
					(start 34.81959 -467.39683)
					(mid 35.330257 -467.907116)
					(end 35.84067 -467.396576)
				)
			)
		)
		(polygon
			(pts
				(arc
					(start 220.840554 -466.583522)
					(mid 220.329887 -466.073236)
					(end 219.819474 -466.583776)
				)
				(arc
					(start 219.819474 -467.396576)
					(mid 220.330014 -467.907116)
					(end 220.840554 -467.396576)
				)
			)
		)
		(polygon
			(pts
				(arc
					(start 27.18054 -450.603366)
					(mid 26.669873 -450.09308)
					(end 26.15946 -450.60362)
				)
				(arc
					(start 26.15946 -451.41642)
					(mid 26.67 -451.92696)
					(end 27.18054 -451.41642)
				)
			)
		)
		(polygon
			(pts
				(arc
					(start 7.2898 -449.978272)
					(mid 7.80034 -449.467732)
					(end 7.2898 -448.957192)
				)
				(arc
					(start 6.476746 -448.957192)
					(mid 5.96646 -449.467859)
					(end 6.477 -449.978272)
				)
			)
		)
		(polygon
			(pts
				(arc
					(start 25.88514 -448.05092)
					(mid 25.272873 -447.439034)
					(end 24.66086 -448.051174)
				)
				(arc
					(start 24.66086 -449.168774)
					(mid 25.273 -449.780914)
					(end 25.88514 -449.168774)
				)
			)
		)
		(polygon
			(pts
				(arc
					(start 7.502906 -446.384172)
					(mid 6.992366 -445.873632)
					(end 6.481826 -446.384172)
				)
				(arc
					(start 6.481826 -447.197226)
					(mid 6.992493 -447.707512)
					(end 7.502906 -447.196972)
				)
			)
		)
		(polygon
			(pts
				(arc
					(start 5.59054 -444.735204)
					(mid 5.08 -444.224664)
					(end 4.56946 -444.735204)
				)
				(arc
					(start 4.56946 -445.548258)
					(mid 5.080127 -446.058544)
					(end 5.59054 -445.548004)
				)
			)
		)
		(polygon
			(pts
				(arc
					(start 17.78254 -444.603378)
					(mid 17.272 -444.092838)
					(end 16.76146 -444.603378)
				)
				(arc
					(start 16.76146 -445.416432)
					(mid 17.272127 -445.926718)
					(end 17.78254 -445.416178)
				)
			)
		)
		(polygon
			(pts
				(arc
					(start 32.26054 -444.584582)
					(mid 31.749873 -444.074296)
					(end 31.23946 -444.584836)
				)
				(arc
					(start 31.23946 -445.397636)
					(mid 31.75 -445.908176)
					(end 32.26054 -445.397636)
				)
			)
		)
		(polygon
			(pts
				(arc
					(start 7.502906 -443.18428)
					(mid 6.992366 -442.67374)
					(end 6.481826 -443.18428)
				)
				(arc
					(start 6.481826 -443.997334)
					(mid 6.992493 -444.50762)
					(end 7.502906 -443.99708)
				)
			)
		)
		(polygon
			(pts
				(arc
					(start 5.59054 -441.535312)
					(mid 5.08 -441.024772)
					(end 4.56946 -441.535312)
				)
				(arc
					(start 4.56946 -442.348366)
					(mid 5.080127 -442.858652)
					(end 5.59054 -442.348112)
				)
			)
		)
		(polygon
			(pts
				(arc
					(start 7.502906 -439.984134)
					(mid 6.992366 -439.473594)
					(end 6.481826 -439.984134)
				)
				(arc
					(start 6.481826 -440.797188)
					(mid 6.992493 -441.307474)
					(end 7.502906 -440.796934)
				)
			)
		)
		(polygon
			(pts
				(arc
					(start 5.59054 -438.335166)
					(mid 5.08 -437.824626)
					(end 4.56946 -438.335166)
				)
				(arc
					(start 4.56946 -439.14822)
					(mid 5.080127 -439.658506)
					(end 5.59054 -439.147966)
				)
			)
		)
		(polygon
			(pts
				(arc
					(start 27.18054 -437.80329)
					(mid 26.669873 -437.293004)
					(end 26.15946 -437.803544)
				)
				(arc
					(start 26.15946 -438.616344)
					(mid 26.67 -439.126884)
					(end 27.18054 -438.616344)
				)
			)
		)
		(polygon
			(pts
				(arc
					(start 7.502906 -436.784242)
					(mid 6.992366 -436.273702)
					(end 6.481826 -436.784242)
				)
				(arc
					(start 6.481826 -437.597296)
					(mid 6.992493 -438.107582)
					(end 7.502906 -437.597042)
				)
			)
		)
		(polygon
			(pts
				(arc
					(start 25.88514 -435.251098)
					(mid 25.272873 -434.639212)
					(end 24.66086 -435.251352)
				)
				(arc
					(start 24.66086 -436.368952)
					(mid 25.273 -436.981092)
					(end 25.88514 -436.368952)
				)
			)
		)
		(polygon
			(pts
				(arc
					(start 5.59054 -435.135274)
					(mid 5.08 -434.624734)
					(end 4.56946 -435.135274)
				)
				(arc
					(start 4.56946 -435.948328)
					(mid 5.080127 -436.458614)
					(end 5.59054 -435.948074)
				)
			)
		)
		(polygon
			(pts
				(arc
					(start 27.18054 -433.003452)
					(mid 26.669873 -432.493166)
					(end 26.15946 -433.003706)
				)
				(arc
					(start 26.15946 -433.816506)
					(mid 26.67 -434.327046)
					(end 27.18054 -433.816506)
				)
			)
		)
		(polygon
			(pts
				(arc
					(start 7.502906 -431.18405)
					(mid 6.992239 -430.673764)
					(end 6.481826 -431.184304)
				)
				(arc
					(start 6.481826 -431.997104)
					(mid 6.992366 -432.507644)
					(end 7.502906 -431.997104)
				)
			)
		)
		(polygon
			(pts
				(arc
					(start 72.90054 -431.139346)
					(mid 72.389873 -430.62906)
					(end 71.87946 -431.1396)
				)
				(arc
					(start 71.87946 -431.9524)
					(mid 72.39 -432.46294)
					(end 72.90054 -431.9524)
				)
			)
		)
		(polygon
			(pts
				(arc
					(start 25.88514 -430.451006)
					(mid 25.272873 -429.83912)
					(end 24.66086 -430.45126)
				)
				(arc
					(start 24.66086 -431.56886)
					(mid 25.273 -432.181)
					(end 25.88514 -431.56886)
				)
			)
		)
		(polygon
			(pts
				(arc
					(start 75.0824 -430.63414)
					(mid 75.59294 -430.1236)
					(end 75.0824 -429.61306)
				)
				(arc
					(start 74.269346 -429.61306)
					(mid 73.75906 -430.123727)
					(end 74.2696 -430.63414)
				)
			)
		)
		(polygon
			(pts
				(arc
					(start 5.59054 -429.534828)
					(mid 5.079873 -429.024542)
					(end 4.56946 -429.535082)
				)
				(arc
					(start 4.56946 -430.347882)
					(mid 5.08 -430.858422)
					(end 5.59054 -430.347882)
				)
			)
		)
		(polygon
			(pts
				(arc
					(start 27.18054 -428.20336)
					(mid 26.669873 -427.693074)
					(end 26.15946 -428.203614)
				)
				(arc
					(start 26.15946 -429.016414)
					(mid 26.67 -429.526954)
					(end 27.18054 -429.016414)
				)
			)
		)
		(polygon
			(pts
				(arc
					(start 7.502906 -427.983904)
					(mid 6.992239 -427.473618)
					(end 6.481826 -427.984158)
				)
				(arc
					(start 6.481826 -428.796958)
					(mid 6.992366 -429.307498)
					(end 7.502906 -428.796958)
				)
			)
		)
		(polygon
			(pts
				(arc
					(start 5.59054 -426.334936)
					(mid 5.079873 -425.82465)
					(end 4.56946 -426.33519)
				)
				(arc
					(start 4.56946 -427.14799)
					(mid 5.08 -427.65853)
					(end 5.59054 -427.14799)
				)
			)
		)
		(polygon
			(pts
				(arc
					(start 25.88514 -425.650914)
					(mid 25.272873 -425.039028)
					(end 24.66086 -425.651168)
				)
				(arc
					(start 24.66086 -426.768768)
					(mid 25.273 -427.380908)
					(end 25.88514 -426.768768)
				)
			)
		)
		(polygon
			(pts
				(arc
					(start 7.502906 -424.784012)
					(mid 6.992239 -424.273726)
					(end 6.481826 -424.784266)
				)
				(arc
					(start 6.481826 -425.597066)
					(mid 6.992366 -426.107606)
					(end 7.502906 -425.597066)
				)
			)
		)
		(polygon
			(pts
				(arc
					(start 5.59054 -423.135044)
					(mid 5.079873 -422.624758)
					(end 4.56946 -423.135298)
				)
				(arc
					(start 4.56946 -423.948098)
					(mid 5.08 -424.458638)
					(end 5.59054 -423.948098)
				)
			)
		)
		(polygon
			(pts
				(arc
					(start 5.59054 -416.735006)
					(mid 5.079873 -416.22472)
					(end 4.56946 -416.73526)
				)
				(arc
					(start 4.56946 -417.54806)
					(mid 5.08 -418.0586)
					(end 5.59054 -417.54806)
				)
			)
		)
		(polygon
			(pts
				(arc
					(start 7.502906 -415.135568)
					(mid 6.992239 -414.625282)
					(end 6.481826 -415.135822)
				)
				(arc
					(start 6.481826 -415.948622)
					(mid 6.992366 -416.459162)
					(end 7.502906 -415.948622)
				)
			)
		)
		(polygon
			(pts
				(arc
					(start 5.59054 -413.535114)
					(mid 5.08 -413.024574)
					(end 4.56946 -413.535114)
				)
				(arc
					(start 4.56946 -414.348168)
					(mid 5.080127 -414.858454)
					(end 5.59054 -414.347914)
				)
			)
		)
		(polygon
			(pts
				(arc
					(start 7.502906 -411.935676)
					(mid 6.992366 -411.425136)
					(end 6.481826 -411.935676)
				)
				(arc
					(start 6.481826 -412.74873)
					(mid 6.992493 -413.259016)
					(end 7.502906 -412.748476)
				)
			)
		)
		(polygon
			(pts
				(arc
					(start 5.59054 -410.335222)
					(mid 5.08 -409.824682)
					(end 4.56946 -410.335222)
				)
				(arc
					(start 4.56946 -411.148276)
					(mid 5.080127 -411.658562)
					(end 5.59054 -411.148022)
				)
			)
		)
		(polygon
			(pts
				(arc
					(start 7.502906 -408.735784)
					(mid 6.992366 -408.225244)
					(end 6.481826 -408.735784)
				)
				(arc
					(start 6.481826 -409.548838)
					(mid 6.992493 -410.059124)
					(end 7.502906 -409.548584)
				)
			)
		)
		(polygon
			(pts
				(arc
					(start 5.59054 -407.135076)
					(mid 5.08 -406.624536)
					(end 4.56946 -407.135076)
				)
				(arc
					(start 4.56946 -407.94813)
					(mid 5.080127 -408.458416)
					(end 5.59054 -407.947876)
				)
			)
		)
		(polygon
			(pts
				(arc
					(start 7.502906 -405.535638)
					(mid 6.992366 -405.025098)
					(end 6.481826 -405.535638)
				)
				(arc
					(start 6.481826 -406.348692)
					(mid 6.992493 -406.858978)
					(end 7.502906 -406.348438)
				)
			)
		)
		(polygon
			(pts
				(arc
					(start 5.59054 -403.935184)
					(mid 5.08 -403.424644)
					(end 4.56946 -403.935184)
				)
				(arc
					(start 4.56946 -404.748238)
					(mid 5.080127 -405.258524)
					(end 5.59054 -404.747984)
				)
			)
		)
		(polygon
			(pts
				(arc
					(start 7.502906 -402.335746)
					(mid 6.992366 -401.825206)
					(end 6.481826 -402.335746)
				)
				(arc
					(start 6.481826 -403.1488)
					(mid 6.992493 -403.659086)
					(end 7.502906 -403.148546)
				)
			)
		)
		(polygon
			(pts
				(arc
					(start 5.59054 -398.334992)
					(mid 5.079873 -397.824706)
					(end 4.56946 -398.335246)
				)
				(arc
					(start 4.56946 -399.148046)
					(mid 5.08 -399.658586)
					(end 5.59054 -399.148046)
				)
			)
		)
		(polygon
			(pts
				(arc
					(start 7.502906 -396.735554)
					(mid 6.992239 -396.225268)
					(end 6.481826 -396.735808)
				)
				(arc
					(start 6.481826 -397.548608)
					(mid 6.992366 -398.059148)
					(end 7.502906 -397.548608)
				)
			)
		)
		(polygon
			(pts
				(arc
					(start 5.59054 -395.134846)
					(mid 5.079873 -394.62456)
					(end 4.56946 -395.1351)
				)
				(arc
					(start 4.56946 -395.9479)
					(mid 5.08 -396.45844)
					(end 5.59054 -395.9479)
				)
			)
		)
		(polygon
			(pts
				(arc
					(start 7.502906 -393.535408)
					(mid 6.992239 -393.025122)
					(end 6.481826 -393.535662)
				)
				(arc
					(start 6.481826 -394.348462)
					(mid 6.992366 -394.859002)
					(end 7.502906 -394.348462)
				)
			)
		)
		(polygon
			(pts
				(arc
					(start 5.59054 -391.934954)
					(mid 5.079873 -391.424668)
					(end 4.56946 -391.935208)
				)
				(arc
					(start 4.56946 -392.748008)
					(mid 5.08 -393.258548)
					(end 5.59054 -392.748008)
				)
			)
		)
		(polygon
			(pts
				(arc
					(start 7.502906 -390.335516)
					(mid 6.992239 -389.82523)
					(end 6.481826 -390.33577)
				)
				(arc
					(start 6.481826 -391.14857)
					(mid 6.992366 -391.65911)
					(end 7.502906 -391.14857)
				)
			)
		)
		(polygon
			(pts
				(arc
					(start 5.59054 -388.735062)
					(mid 5.079873 -388.224776)
					(end 4.56946 -388.735316)
				)
				(arc
					(start 4.56946 -389.548116)
					(mid 5.08 -390.058656)
					(end 5.59054 -389.548116)
				)
			)
		)
		(polygon
			(pts
				(arc
					(start 222.339154 -388.231126)
					(mid 221.726887 -387.61924)
					(end 221.114874 -388.23138)
				)
				(arc
					(start 221.114874 -389.34898)
					(mid 221.727014 -389.96112)
					(end 222.339154 -389.34898)
				)
			)
		)
		(polygon
			(pts
				(arc
					(start 37.33927 -388.231126)
					(mid 36.727003 -387.61924)
					(end 36.11499 -388.23138)
				)
				(arc
					(start 36.11499 -389.34898)
					(mid 36.72713 -389.96112)
					(end 37.33927 -389.34898)
				)
			)
		)
		(polygon
			(pts
				(arc
					(start 7.502906 -387.13537)
					(mid 6.992239 -386.625084)
					(end 6.481826 -387.135624)
				)
				(arc
					(start 6.481826 -387.948424)
					(mid 6.992366 -388.458964)
					(end 7.502906 -387.948424)
				)
			)
		)
		(polygon
			(pts
				(arc
					(start 220.840554 -385.98348)
					(mid 220.329887 -385.473194)
					(end 219.819474 -385.983734)
				)
				(arc
					(start 219.819474 -386.796534)
					(mid 220.330014 -387.307074)
					(end 220.840554 -386.796534)
				)
			)
		)
		(polygon
			(pts
				(arc
					(start 35.84067 -385.98348)
					(mid 35.330003 -385.473194)
					(end 34.81959 -385.983734)
				)
				(arc
					(start 34.81959 -386.796534)
					(mid 35.33013 -387.307074)
					(end 35.84067 -386.796534)
				)
			)
		)
		(polygon
			(pts
				(arc
					(start 9.195308 -386.113782)
					(mid 9.705594 -385.603115)
					(end 9.195054 -385.092702)
				)
				(arc
					(start 8.382254 -385.092702)
					(mid 7.871714 -385.603242)
					(end 8.382254 -386.113782)
				)
			)
		)
		(polygon
			(pts
				(arc
					(start 222.339154 -383.431034)
					(mid 221.726887 -382.819148)
					(end 221.114874 -383.431288)
				)
				(arc
					(start 221.114874 -384.548888)
					(mid 221.727014 -385.161028)
					(end 222.339154 -384.548888)
				)
			)
		)
		(polygon
			(pts
				(arc
					(start 37.33927 -383.431034)
					(mid 36.727003 -382.819148)
					(end 36.11499 -383.431288)
				)
				(arc
					(start 36.11499 -384.548888)
					(mid 36.72713 -385.161028)
					(end 37.33927 -384.548888)
				)
			)
		)
		(polygon
			(pts
				(arc
					(start 220.840554 -381.183388)
					(mid 220.329887 -380.673102)
					(end 219.819474 -381.183642)
				)
				(arc
					(start 219.819474 -381.996442)
					(mid 220.330014 -382.506982)
					(end 220.840554 -381.996442)
				)
			)
		)
		(polygon
			(pts
				(arc
					(start 35.84067 -381.183388)
					(mid 35.330003 -380.673102)
					(end 34.81959 -381.183642)
				)
				(arc
					(start 34.81959 -381.996442)
					(mid 35.33013 -382.506982)
					(end 35.84067 -381.996442)
				)
			)
		)
		(polygon
			(pts
				(arc
					(start 222.339154 -378.630942)
					(mid 221.726887 -378.019056)
					(end 221.114874 -378.631196)
				)
				(arc
					(start 221.114874 -379.748796)
					(mid 221.727014 -380.360936)
					(end 222.339154 -379.748796)
				)
			)
		)
		(polygon
			(pts
				(arc
					(start 37.33927 -378.630942)
					(mid 36.727003 -378.019056)
					(end 36.11499 -378.631196)
				)
				(arc
					(start 36.11499 -379.748796)
					(mid 36.72713 -380.360936)
					(end 37.33927 -379.748796)
				)
			)
		)
		(polygon
			(pts
				(arc
					(start 220.840554 -376.38355)
					(mid 220.329887 -375.873264)
					(end 219.819474 -376.383804)
				)
				(arc
					(start 219.819474 -377.196604)
					(mid 220.330014 -377.707144)
					(end 220.840554 -377.196604)
				)
			)
		)
		(polygon
			(pts
				(arc
					(start 35.84067 -376.38355)
					(mid 35.330003 -375.873264)
					(end 34.81959 -376.383804)
				)
				(arc
					(start 34.81959 -377.196604)
					(mid 35.33013 -377.707144)
					(end 35.84067 -377.196604)
				)
			)
		)
		(polygon
			(pts
				(arc
					(start 233.897424 -369.579398)
					(mid 233.386884 -369.068858)
					(end 232.876344 -369.579398)
				)
				(arc
					(start 232.876344 -370.392452)
					(mid 233.387011 -370.902738)
					(end 233.897424 -370.392198)
				)
			)
		)
		(polygon
			(pts
				(arc
					(start 48.89754 -369.579144)
					(mid 48.386873 -369.068858)
					(end 47.87646 -369.579398)
				)
				(arc
					(start 47.87646 -370.392198)
					(mid 48.387 -370.902738)
					(end 48.89754 -370.392198)
				)
			)
		)
		(polygon
			(pts
				(arc
					(start 230.720138 -369.30076)
					(mid 231.230424 -368.790093)
					(end 230.719884 -368.27968)
				)
				(arc
					(start 229.907084 -368.27968)
					(mid 229.396544 -368.79022)
					(end 229.907084 -369.30076)
				)
			)
		)
		(polygon
			(pts
				(arc
					(start 45.72 -369.30076)
					(mid 46.23054 -368.79022)
					(end 45.72 -368.27968)
				)
				(arc
					(start 44.906946 -368.27968)
					(mid 44.39666 -368.790347)
					(end 44.9072 -369.30076)
				)
			)
		)
		(polygon
			(pts
				(arc
					(start 222.339154 -365.83112)
					(mid 221.726887 -365.219234)
					(end 221.114874 -365.831374)
				)
				(arc
					(start 221.114874 -366.948974)
					(mid 221.727014 -367.561114)
					(end 222.339154 -366.948974)
				)
			)
		)
		(polygon
			(pts
				(arc
					(start 37.33927 -365.83112)
					(mid 36.727003 -365.219234)
					(end 36.11499 -365.831374)
				)
				(arc
					(start 36.11499 -366.948974)
					(mid 36.72713 -367.561114)
					(end 37.33927 -366.948974)
				)
			)
		)
		(polygon
			(pts
				(arc
					(start 220.840554 -363.583474)
					(mid 220.329887 -363.073188)
					(end 219.819474 -363.583728)
				)
				(arc
					(start 219.819474 -364.396528)
					(mid 220.330014 -364.907068)
					(end 220.840554 -364.396528)
				)
			)
		)
		(polygon
			(pts
				(arc
					(start 35.84067 -363.583474)
					(mid 35.330003 -363.073188)
					(end 34.81959 -363.583728)
				)
				(arc
					(start 34.81959 -364.396528)
					(mid 35.33013 -364.907068)
					(end 35.84067 -364.396528)
				)
			)
		)
		(polygon
			(pts
				(arc
					(start 5.59054 -357.935276)
					(mid 5.079873 -357.42499)
					(end 4.56946 -357.93553)
				)
				(arc
					(start 4.56946 -358.74833)
					(mid 5.08 -359.25887)
					(end 5.59054 -358.74833)
				)
			)
		)
		(polygon
			(pts
				(arc
					(start 7.502906 -356.335838)
					(mid 6.992366 -355.825298)
					(end 6.481826 -356.335838)
				)
				(arc
					(start 6.481826 -357.148892)
					(mid 6.992493 -357.659178)
					(end 7.502906 -357.148638)
				)
			)
		)
		(polygon
			(pts
				(arc
					(start 5.59054 -354.73513)
					(mid 5.079873 -354.224844)
					(end 4.56946 -354.735384)
				)
				(arc
					(start 4.56946 -355.548184)
					(mid 5.08 -356.058724)
					(end 5.59054 -355.548184)
				)
			)
		)
		(polygon
			(pts
				(arc
					(start 7.502906 -353.135692)
					(mid 6.992239 -352.625406)
					(end 6.481826 -353.135946)
				)
				(arc
					(start 6.481826 -353.948746)
					(mid 6.992366 -354.459286)
					(end 7.502906 -353.948746)
				)
			)
		)
		(polygon
			(pts
				(arc
					(start 5.59054 -351.535238)
					(mid 5.079873 -351.024952)
					(end 4.56946 -351.535492)
				)
				(arc
					(start 4.56946 -352.348292)
					(mid 5.08 -352.858832)
					(end 5.59054 -352.348292)
				)
			)
		)
		(polygon
			(pts
				(arc
					(start 7.502906 -349.9358)
					(mid 6.992366 -349.42526)
					(end 6.481826 -349.9358)
				)
				(arc
					(start 6.481826 -350.748854)
					(mid 6.992493 -351.25914)
					(end 7.502906 -350.7486)
				)
			)
		)
		(polygon
			(pts
				(arc
					(start 5.59054 -348.335092)
					(mid 5.079873 -347.824806)
					(end 4.56946 -348.335346)
				)
				(arc
					(start 4.56946 -349.148146)
					(mid 5.08 -349.658686)
					(end 5.59054 -349.148146)
				)
			)
		)
		(polygon
			(pts
				(arc
					(start 27.18054 -347.603572)
					(mid 26.67 -347.093032)
					(end 26.15946 -347.603572)
				)
				(arc
					(start 26.15946 -348.416626)
					(mid 26.670127 -348.926912)
					(end 27.18054 -348.416372)
				)
			)
		)
		(polygon
			(pts
				(arc
					(start 7.502906 -346.735908)
					(mid 6.992366 -346.225368)
					(end 6.481826 -346.735908)
				)
				(arc
					(start 6.481826 -347.548962)
					(mid 6.992493 -348.059248)
					(end 7.502906 -347.548708)
				)
			)
		)
		(polygon
			(pts
				(arc
					(start 5.59054 -345.1352)
					(mid 5.079873 -344.624914)
					(end 4.56946 -345.135454)
				)
				(arc
					(start 4.56946 -345.948254)
					(mid 5.08 -346.458794)
					(end 5.59054 -345.948254)
				)
			)
		)
		(polygon
			(pts
				(arc
					(start 25.88514 -345.050872)
					(mid 25.272873 -344.438986)
					(end 24.66086 -345.051126)
				)
				(arc
					(start 24.66086 -346.168726)
					(mid 25.273 -346.780866)
					(end 25.88514 -346.168726)
				)
			)
		)
		(polygon
			(pts
				(arc
					(start 7.502906 -343.586562)
					(mid 6.992239 -343.076276)
					(end 6.481826 -343.586816)
				)
				(arc
					(start 6.481826 -344.399616)
					(mid 6.992366 -344.910156)
					(end 7.502906 -344.399616)
				)
			)
		)
		(polygon
			(pts
				(arc
					(start 5.59054 -341.935054)
					(mid 5.079873 -341.424768)
					(end 4.56946 -341.935308)
				)
				(arc
					(start 4.56946 -342.748108)
					(mid 5.08 -343.258648)
					(end 5.59054 -342.748108)
				)
			)
		)
		(polygon
			(pts
				(arc
					(start 17.78254 -341.60333)
					(mid 17.272 -341.09279)
					(end 16.76146 -341.60333)
				)
				(arc
					(start 16.76146 -342.416384)
					(mid 17.272127 -342.92667)
					(end 17.78254 -342.41613)
				)
			)
		)
		(polygon
			(pts
				(arc
					(start 33.40354 -341.58428)
					(mid 32.892873 -341.073994)
					(end 32.38246 -341.584534)
				)
				(arc
					(start 32.38246 -342.397334)
					(mid 32.893 -342.907874)
					(end 33.40354 -342.397334)
				)
			)
		)
		(polygon
			(pts
				(arc
					(start 7.502906 -340.386416)
					(mid 6.992239 -339.87613)
					(end 6.481826 -340.38667)
				)
				(arc
					(start 6.481826 -341.19947)
					(mid 6.992366 -341.71001)
					(end 7.502906 -341.19947)
				)
			)
		)
		(polygon
			(pts
				(arc
					(start 5.59054 -338.735162)
					(mid 5.079873 -338.224876)
					(end 4.56946 -338.735416)
				)
				(arc
					(start 4.56946 -339.548216)
					(mid 5.08 -340.058756)
					(end 5.59054 -339.548216)
				)
			)
		)
		(polygon
			(pts
				(arc
					(start 7.502906 -337.186524)
					(mid 6.992239 -336.676238)
					(end 6.481826 -337.186778)
				)
				(arc
					(start 6.481826 -337.999578)
					(mid 6.992366 -338.510118)
					(end 7.502906 -337.999578)
				)
			)
		)
		(polygon
			(pts
				(arc
					(start 5.59054 -335.53527)
					(mid 5.079873 -335.024984)
					(end 4.56946 -335.535524)
				)
				(arc
					(start 4.56946 -336.348324)
					(mid 5.08 -336.858864)
					(end 5.59054 -336.348324)
				)
			)
		)
		(polygon
			(pts
				(arc
					(start 27.18054 -334.803496)
					(mid 26.67 -334.292956)
					(end 26.15946 -334.803496)
				)
				(arc
					(start 26.15946 -335.61655)
					(mid 26.670127 -336.126836)
					(end 27.18054 -335.616296)
				)
			)
		)
		(polygon
			(pts
				(arc
					(start 7.502906 -333.986378)
					(mid 6.992239 -333.476092)
					(end 6.481826 -333.986632)
				)
				(arc
					(start 6.481826 -334.799432)
					(mid 6.992366 -335.309972)
					(end 7.502906 -334.799432)
				)
			)
		)
		(polygon
			(pts
				(arc
					(start 25.88514 -332.251304)
					(mid 25.273 -331.639164)
					(end 24.66086 -332.251304)
				)
				(arc
					(start 24.66086 -333.369158)
					(mid 25.273127 -333.981044)
					(end 25.88514 -333.368904)
				)
			)
		)
		(polygon
			(pts
				(arc
					(start 27.18054 -330.003658)
					(mid 26.67 -329.493118)
					(end 26.15946 -330.003658)
				)
				(arc
					(start 26.15946 -330.816712)
					(mid 26.670127 -331.326998)
					(end 27.18054 -330.816458)
				)
			)
		)
		(polygon
			(pts
				(arc
					(start 5.59054 -329.935078)
					(mid 5.079873 -329.424792)
					(end 4.56946 -329.935332)
				)
				(arc
					(start 4.56946 -330.748132)
					(mid 5.08 -331.258672)
					(end 5.59054 -330.748132)
				)
			)
		)
		(polygon
			(pts
				(arc
					(start 7.502906 -328.335894)
					(mid 6.992366 -327.825354)
					(end 6.481826 -328.335894)
				)
				(arc
					(start 6.481826 -329.148948)
					(mid 6.992493 -329.659234)
					(end 7.502906 -329.148694)
				)
			)
		)
		(polygon
			(pts
				(arc
					(start 25.88514 -327.451212)
					(mid 25.273 -326.839072)
					(end 24.66086 -327.451212)
				)
				(arc
					(start 24.66086 -328.569066)
					(mid 25.273127 -329.180952)
					(end 25.88514 -328.568812)
				)
			)
		)
		(polygon
			(pts
				(arc
					(start 5.59054 -326.735186)
					(mid 5.079873 -326.2249)
					(end 4.56946 -326.73544)
				)
				(arc
					(start 4.56946 -327.54824)
					(mid 5.08 -328.05878)
					(end 5.59054 -327.54824)
				)
			)
		)
		(polygon
			(pts
				(arc
					(start 27.18054 -325.203566)
					(mid 26.67 -324.693026)
					(end 26.15946 -325.203566)
				)
				(arc
					(start 26.15946 -326.01662)
					(mid 26.670127 -326.526906)
					(end 27.18054 -326.016366)
				)
			)
		)
		(polygon
			(pts
				(arc
					(start 7.502906 -325.136002)
					(mid 6.992366 -324.625462)
					(end 6.481826 -325.136002)
				)
				(arc
					(start 6.481826 -325.949056)
					(mid 6.992493 -326.459342)
					(end 7.502906 -325.948802)
				)
			)
		)
		(polygon
			(pts
				(arc
					(start 5.59054 -323.53504)
					(mid 5.079873 -323.024754)
					(end 4.56946 -323.535294)
				)
				(arc
					(start 4.56946 -324.348094)
					(mid 5.08 -324.858634)
					(end 5.59054 -324.348094)
				)
			)
		)
		(polygon
			(pts
				(arc
					(start 25.88514 -322.65112)
					(mid 25.273 -322.03898)
					(end 24.66086 -322.65112)
				)
				(arc
					(start 24.66086 -323.768974)
					(mid 25.273127 -324.38086)
					(end 25.88514 -323.76872)
				)
			)
		)
		(polygon
			(pts
				(arc
					(start 7.502906 -321.935856)
					(mid 6.992366 -321.425316)
					(end 6.481826 -321.935856)
				)
				(arc
					(start 6.481826 -322.74891)
					(mid 6.992493 -323.259196)
					(end 7.502906 -322.748656)
				)
			)
		)
		(polygon
			(pts
				(arc
					(start 5.59054 -320.335148)
					(mid 5.079873 -319.824862)
					(end 4.56946 -320.335402)
				)
				(arc
					(start 4.56946 -321.148202)
					(mid 5.08 -321.658742)
					(end 5.59054 -321.148202)
				)
			)
		)
		(polygon
			(pts
				(arc
					(start 7.502906 -318.735964)
					(mid 6.992366 -318.225424)
					(end 6.481826 -318.735964)
				)
				(arc
					(start 6.481826 -319.549018)
					(mid 6.992493 -320.059304)
					(end 7.502906 -319.548764)
				)
			)
		)
		(polygon
			(pts
				(arc
					(start 5.59054 -317.135256)
					(mid 5.079873 -316.62497)
					(end 4.56946 -317.13551)
				)
				(arc
					(start 4.56946 -317.94831)
					(mid 5.08 -318.45885)
					(end 5.59054 -317.94831)
				)
			)
		)
		(polygon
			(pts
				(arc
					(start 7.502906 -310.73598)
					(mid 6.992366 -310.22544)
					(end 6.481826 -310.73598)
				)
				(arc
					(start 6.481826 -311.549034)
					(mid 6.992493 -312.05932)
					(end 7.502906 -311.54878)
				)
			)
		)
		(polygon
			(pts
				(arc
					(start 5.59054 -309.135272)
					(mid 5.079873 -308.624986)
					(end 4.56946 -309.135526)
				)
				(arc
					(start 4.56946 -309.948326)
					(mid 5.08 -310.458866)
					(end 5.59054 -309.948326)
				)
			)
		)
		(polygon
			(pts
				(arc
					(start 7.502906 -307.535834)
					(mid 6.992366 -307.025294)
					(end 6.481826 -307.535834)
				)
				(arc
					(start 6.481826 -308.348888)
					(mid 6.992493 -308.859174)
					(end 7.502906 -308.348634)
				)
			)
		)
		(polygon
			(pts
				(arc
					(start 5.59054 -305.935126)
					(mid 5.079873 -305.42484)
					(end 4.56946 -305.93538)
				)
				(arc
					(start 4.56946 -306.74818)
					(mid 5.08 -307.25872)
					(end 5.59054 -306.74818)
				)
			)
		)
		(polygon
			(pts
				(arc
					(start 7.502906 -304.335942)
					(mid 6.992366 -303.825402)
					(end 6.481826 -304.335942)
				)
				(arc
					(start 6.481826 -305.148996)
					(mid 6.992493 -305.659282)
					(end 7.502906 -305.148742)
				)
			)
		)
		(polygon
			(pts
				(arc
					(start 5.59054 -302.735234)
					(mid 5.079873 -302.224948)
					(end 4.56946 -302.735488)
				)
				(arc
					(start 4.56946 -303.548288)
					(mid 5.08 -304.058828)
					(end 5.59054 -303.548288)
				)
			)
		)
		(polygon
			(pts
				(arc
					(start 7.502906 -301.135796)
					(mid 6.992366 -300.625256)
					(end 6.481826 -301.135796)
				)
				(arc
					(start 6.481826 -301.94885)
					(mid 6.992493 -302.459136)
					(end 7.502906 -301.948596)
				)
			)
		)
		(polygon
			(pts
				(arc
					(start 5.59054 -299.535088)
					(mid 5.079873 -299.024802)
					(end 4.56946 -299.535342)
				)
				(arc
					(start 4.56946 -300.348142)
					(mid 5.08 -300.858682)
					(end 5.59054 -300.348142)
				)
			)
		)
		(polygon
			(pts
				(arc
					(start 7.502906 -297.935904)
					(mid 6.992366 -297.425364)
					(end 6.481826 -297.935904)
				)
				(arc
					(start 6.481826 -298.748958)
					(mid 6.992493 -299.259244)
					(end 7.502906 -298.748704)
				)
			)
		)
		(polygon
			(pts
				(arc
					(start 5.59054 -296.335196)
					(mid 5.079873 -295.82491)
					(end 4.56946 -296.33545)
				)
				(arc
					(start 4.56946 -297.14825)
					(mid 5.08 -297.65879)
					(end 5.59054 -297.14825)
				)
			)
		)
		(polygon
			(pts
				(arc
					(start 7.502906 -294.736012)
					(mid 6.992366 -294.225472)
					(end 6.481826 -294.736012)
				)
				(arc
					(start 6.481826 -295.549066)
					(mid 6.992493 -296.059352)
					(end 7.502906 -295.548812)
				)
			)
		)
		(polygon
			(pts
				(arc
					(start 5.59054 -293.13505)
					(mid 5.079873 -292.624764)
					(end 4.56946 -293.135304)
				)
				(arc
					(start 4.56946 -293.948104)
					(mid 5.08 -294.458644)
					(end 5.59054 -293.948104)
				)
			)
		)
		(polygon
			(pts
				(arc
					(start 7.502906 -291.535866)
					(mid 6.992366 -291.025326)
					(end 6.481826 -291.535866)
				)
				(arc
					(start 6.481826 -292.34892)
					(mid 6.992493 -292.859206)
					(end 7.502906 -292.348666)
				)
			)
		)
		(polygon
			(pts
				(arc
					(start 5.59054 -289.935158)
					(mid 5.079873 -289.424872)
					(end 4.56946 -289.935412)
				)
				(arc
					(start 4.56946 -290.748212)
					(mid 5.08 -291.258752)
					(end 5.59054 -290.748212)
				)
			)
		)
		(polygon
			(pts
				(arc
					(start 7.502906 -288.33572)
					(mid 6.992239 -287.825434)
					(end 6.481826 -288.335974)
				)
				(arc
					(start 6.481826 -289.148774)
					(mid 6.992366 -289.659314)
					(end 7.502906 -289.148774)
				)
			)
		)
		(polygon
			(pts
				(arc
					(start 222.339154 -285.231078)
					(mid 221.726887 -284.619192)
					(end 221.114874 -285.231332)
				)
				(arc
					(start 221.114874 -286.348932)
					(mid 221.727014 -286.961072)
					(end 222.339154 -286.348932)
				)
			)
		)
		(polygon
			(pts
				(arc
					(start 37.33927 -285.231078)
					(mid 36.727003 -284.619192)
					(end 36.11499 -285.231332)
				)
				(arc
					(start 36.11499 -286.348932)
					(mid 36.72713 -286.961072)
					(end 37.33927 -286.348932)
				)
			)
		)
		(polygon
			(pts
				(arc
					(start 5.59054 -283.53512)
					(mid 5.079873 -283.024834)
					(end 4.56946 -283.535374)
				)
				(arc
					(start 4.56946 -284.348174)
					(mid 5.08 -284.858714)
					(end 5.59054 -284.348174)
				)
			)
		)
		(polygon
			(pts
				(arc
					(start 220.840554 -282.983432)
					(mid 220.329887 -282.473146)
					(end 219.819474 -282.983686)
				)
				(arc
					(start 219.819474 -283.796486)
					(mid 220.330014 -284.307026)
					(end 220.840554 -283.796486)
				)
			)
		)
		(polygon
			(pts
				(arc
					(start 35.84067 -282.983432)
					(mid 35.330003 -282.473146)
					(end 34.81959 -282.983686)
				)
				(arc
					(start 34.81959 -283.796486)
					(mid 35.33013 -284.307026)
					(end 35.84067 -283.796486)
				)
			)
		)
		(polygon
			(pts
				(arc
					(start 7.502906 -281.986482)
					(mid 6.992239 -281.476196)
					(end 6.481826 -281.986736)
				)
				(arc
					(start 6.481826 -282.799536)
					(mid 6.992366 -283.310076)
					(end 7.502906 -282.799536)
				)
			)
		)
		(polygon
			(pts
				(arc
					(start 5.59054 -280.335228)
					(mid 5.079873 -279.824942)
					(end 4.56946 -280.335482)
				)
				(arc
					(start 4.56946 -281.148282)
					(mid 5.08 -281.658822)
					(end 5.59054 -281.148282)
				)
			)
		)
		(polygon
			(pts
				(arc
					(start 222.339154 -280.430986)
					(mid 221.726887 -279.8191)
					(end 221.114874 -280.43124)
				)
				(arc
					(start 221.114874 -281.54884)
					(mid 221.727014 -282.16098)
					(end 222.339154 -281.54884)
				)
			)
		)
		(polygon
			(pts
				(arc
					(start 37.33927 -280.430986)
					(mid 36.727003 -279.8191)
					(end 36.11499 -280.43124)
				)
				(arc
					(start 36.11499 -281.54884)
					(mid 36.72713 -282.16098)
					(end 37.33927 -281.54884)
				)
			)
		)
		(polygon
			(pts
				(arc
					(start 7.502906 -278.786336)
					(mid 6.992239 -278.27605)
					(end 6.481826 -278.78659)
				)
				(arc
					(start 6.481826 -279.59939)
					(mid 6.992366 -280.10993)
					(end 7.502906 -279.59939)
				)
			)
		)
		(polygon
			(pts
				(arc
					(start 220.840554 -278.18334)
					(mid 220.329887 -277.673054)
					(end 219.819474 -278.183594)
				)
				(arc
					(start 219.819474 -278.996394)
					(mid 220.330014 -279.506934)
					(end 220.840554 -278.996394)
				)
			)
		)
		(polygon
			(pts
				(arc
					(start 35.84067 -278.18334)
					(mid 35.330003 -277.673054)
					(end 34.81959 -278.183594)
				)
				(arc
					(start 34.81959 -278.996394)
					(mid 35.33013 -279.506934)
					(end 35.84067 -278.996394)
				)
			)
		)
		(polygon
			(pts
				(arc
					(start 222.339154 -275.630894)
					(mid 221.726887 -275.019008)
					(end 221.114874 -275.631148)
				)
				(arc
					(start 221.114874 -276.748748)
					(mid 221.727014 -277.360888)
					(end 222.339154 -276.748748)
				)
			)
		)
		(polygon
			(pts
				(arc
					(start 37.33927 -275.630894)
					(mid 36.727003 -275.019008)
					(end 36.11499 -275.631148)
				)
				(arc
					(start 36.11499 -276.748748)
					(mid 36.72713 -277.360888)
					(end 37.33927 -276.748748)
				)
			)
		)
		(polygon
			(pts
				(arc
					(start 220.840554 -273.383502)
					(mid 220.329887 -272.873216)
					(end 219.819474 -273.383756)
				)
				(arc
					(start 219.819474 -274.196556)
					(mid 220.330014 -274.707096)
					(end 220.840554 -274.196556)
				)
			)
		)
		(polygon
			(pts
				(arc
					(start 35.84067 -273.383502)
					(mid 35.330003 -272.873216)
					(end 34.81959 -273.383756)
				)
				(arc
					(start 34.81959 -274.196556)
					(mid 35.33013 -274.707096)
					(end 35.84067 -274.196556)
				)
			)
		)
		(polygon
			(pts
				(arc
					(start 233.897424 -266.57935)
					(mid 233.386884 -266.06881)
					(end 232.876344 -266.57935)
				)
				(arc
					(start 232.876344 -267.392404)
					(mid 233.387011 -267.90269)
					(end 233.897424 -267.39215)
				)
			)
		)
		(polygon
			(pts
				(arc
					(start 48.89754 -266.579096)
					(mid 48.386873 -266.06881)
					(end 47.87646 -266.57935)
				)
				(arc
					(start 47.87646 -267.39215)
					(mid 48.387 -267.90269)
					(end 48.89754 -267.39215)
				)
			)
		)
		(polygon
			(pts
				(arc
					(start 230.720138 -266.300712)
					(mid 231.230424 -265.790045)
					(end 230.719884 -265.279632)
				)
				(arc
					(start 229.907084 -265.279632)
					(mid 229.396544 -265.790172)
					(end 229.907084 -266.300712)
				)
			)
		)
		(polygon
			(pts
				(arc
					(start 45.72 -266.300712)
					(mid 46.23054 -265.790172)
					(end 45.72 -265.279632)
				)
				(arc
					(start 44.906946 -265.279632)
					(mid 44.39666 -265.790299)
					(end 44.9072 -266.300712)
				)
			)
		)
		(polygon
			(pts
				(arc
					(start 222.339154 -262.831072)
					(mid 221.726887 -262.219186)
					(end 221.114874 -262.831326)
				)
				(arc
					(start 221.114874 -263.948926)
					(mid 221.727014 -264.561066)
					(end 222.339154 -263.948926)
				)
			)
		)
		(polygon
			(pts
				(arc
					(start 37.33927 -262.831072)
					(mid 36.727003 -262.219186)
					(end 36.11499 -262.831326)
				)
				(arc
					(start 36.11499 -263.948926)
					(mid 36.72713 -264.561066)
					(end 37.33927 -263.948926)
				)
			)
		)
		(polygon
			(pts
				(arc
					(start 220.840554 -260.583426)
					(mid 220.329887 -260.07314)
					(end 219.819474 -260.58368)
				)
				(arc
					(start 219.819474 -261.39648)
					(mid 220.330014 -261.90702)
					(end 220.840554 -261.39648)
				)
			)
		)
		(polygon
			(pts
				(arc
					(start 35.84067 -260.583426)
					(mid 35.330003 -260.07314)
					(end 34.81959 -260.58368)
				)
				(arc
					(start 34.81959 -261.39648)
					(mid 35.33013 -261.90702)
					(end 35.84067 -261.39648)
				)
			)
		)
		(polygon
			(pts
				(arc
					(start 27.18054 -244.603524)
					(mid 26.67 -244.092984)
					(end 26.15946 -244.603524)
				)
				(arc
					(start 26.15946 -245.416578)
					(mid 26.670127 -245.926864)
					(end 27.18054 -245.416324)
				)
			)
		)
		(polygon
			(pts
				(arc
					(start 25.88514 -242.051078)
					(mid 25.273 -241.438938)
					(end 24.66086 -242.051078)
				)
				(arc
					(start 24.66086 -243.168932)
					(mid 25.273127 -243.780818)
					(end 25.88514 -243.168678)
				)
			)
		)
		(polygon
			(pts
				(arc
					(start 17.78254 -238.603282)
					(mid 17.272 -238.092742)
					(end 16.76146 -238.603282)
				)
				(arc
					(start 16.76146 -239.416336)
					(mid 17.272127 -239.926622)
					(end 17.78254 -239.416082)
				)
			)
		)
		(polygon
			(pts
				(arc
					(start 42.92854 -238.584232)
					(mid 42.417873 -238.073946)
					(end 41.90746 -238.584486)
				)
				(arc
					(start 41.90746 -239.397286)
					(mid 42.418 -239.907826)
					(end 42.92854 -239.397286)
				)
			)
		)
		(polygon
			(pts
				(arc
					(start 5.59054 -231.935274)
					(mid 5.079873 -231.424988)
					(end 4.56946 -231.935528)
				)
				(arc
					(start 4.56946 -232.748328)
					(mid 5.08 -233.258868)
					(end 5.59054 -232.748328)
				)
			)
		)
		(polygon
			(pts
				(arc
					(start 27.18054 -231.803448)
					(mid 26.67 -231.292908)
					(end 26.15946 -231.803448)
				)
				(arc
					(start 26.15946 -232.616502)
					(mid 26.670127 -233.126788)
					(end 27.18054 -232.616248)
				)
			)
		)
		(polygon
			(pts
				(arc
					(start 7.502906 -230.335582)
					(mid 6.992239 -229.825296)
					(end 6.481826 -230.335836)
				)
				(arc
					(start 6.481826 -231.148636)
					(mid 6.992366 -231.659176)
					(end 7.502906 -231.148636)
				)
			)
		)
		(polygon
			(pts
				(arc
					(start 25.88514 -229.251256)
					(mid 25.273 -228.639116)
					(end 24.66086 -229.251256)
				)
				(arc
					(start 24.66086 -230.36911)
					(mid 25.273127 -230.980996)
					(end 25.88514 -230.368856)
				)
			)
		)
		(polygon
			(pts
				(arc
					(start 5.59054 -228.735128)
					(mid 5.079873 -228.224842)
					(end 4.56946 -228.735382)
				)
				(arc
					(start 4.56946 -229.548182)
					(mid 5.08 -230.058722)
					(end 5.59054 -229.548182)
				)
			)
		)
		(polygon
			(pts
				(arc
					(start 7.502906 -227.13569)
					(mid 6.992239 -226.625404)
					(end 6.481826 -227.135944)
				)
				(arc
					(start 6.481826 -227.948744)
					(mid 6.992366 -228.459284)
					(end 7.502906 -227.948744)
				)
			)
		)
		(polygon
			(pts
				(arc
					(start 27.18054 -227.00361)
					(mid 26.67 -226.49307)
					(end 26.15946 -227.00361)
				)
				(arc
					(start 26.15946 -227.816664)
					(mid 26.670127 -228.32695)
					(end 27.18054 -227.81641)
				)
			)
		)
		(polygon
			(pts
				(arc
					(start 25.88514 -224.451164)
					(mid 25.273 -223.839024)
					(end 24.66086 -224.451164)
				)
				(arc
					(start 24.66086 -225.569018)
					(mid 25.273127 -226.180904)
					(end 25.88514 -225.568764)
				)
			)
		)
		(polygon
			(pts
				(arc
					(start 7.502906 -223.897444)
					(mid 6.992239 -223.387158)
					(end 6.481826 -223.897698)
				)
				(arc
					(start 6.481826 -224.710498)
					(mid 6.992366 -225.221038)
					(end 7.502906 -224.710498)
				)
			)
		)
		(polygon
			(pts
				(arc
					(start 5.59054 -222.33509)
					(mid 5.079873 -221.824804)
					(end 4.56946 -222.335344)
				)
				(arc
					(start 4.56946 -223.148144)
					(mid 5.08 -223.658684)
					(end 5.59054 -223.148144)
				)
			)
		)
		(polygon
			(pts
				(arc
					(start 27.18054 -222.203518)
					(mid 26.67 -221.692978)
					(end 26.15946 -222.203518)
				)
				(arc
					(start 26.15946 -223.016572)
					(mid 26.670127 -223.526858)
					(end 27.18054 -223.016318)
				)
			)
		)
		(polygon
			(pts
				(arc
					(start 7.502906 -220.685106)
					(mid 6.992366 -220.174566)
					(end 6.481826 -220.685106)
				)
				(arc
					(start 6.481826 -221.49816)
					(mid 6.992493 -222.008446)
					(end 7.502906 -221.497906)
				)
			)
		)
		(polygon
			(pts
				(arc
					(start 25.88514 -219.650818)
					(mid 25.272873 -219.038932)
					(end 24.66086 -219.651072)
				)
				(arc
					(start 24.66086 -220.768672)
					(mid 25.273 -221.380812)
					(end 25.88514 -220.768672)
				)
			)
		)
		(polygon
			(pts
				(arc
					(start 5.59054 -219.135198)
					(mid 5.079873 -218.624912)
					(end 4.56946 -219.135452)
				)
				(arc
					(start 4.56946 -219.948252)
					(mid 5.08 -220.458792)
					(end 5.59054 -219.948252)
				)
			)
		)
		(polygon
			(pts
				(arc
					(start 7.502906 -217.48496)
					(mid 6.992239 -216.974674)
					(end 6.481826 -217.485214)
				)
				(arc
					(start 6.481826 -218.298014)
					(mid 6.992366 -218.808554)
					(end 7.502906 -218.298014)
				)
			)
		)
		(polygon
			(pts
				(arc
					(start 5.59054 -215.935052)
					(mid 5.079873 -215.424766)
					(end 4.56946 -215.935306)
				)
				(arc
					(start 4.56946 -216.748106)
					(mid 5.08 -217.258646)
					(end 5.59054 -216.748106)
				)
			)
		)
		(polygon
			(pts
				(arc
					(start 7.502906 -214.284814)
					(mid 6.992239 -213.774528)
					(end 6.481826 -214.285068)
				)
				(arc
					(start 6.481826 -215.097868)
					(mid 6.992366 -215.608408)
					(end 7.502906 -215.097868)
				)
			)
		)
		(polygon
			(pts
				(arc
					(start 5.59054 -212.73516)
					(mid 5.079873 -212.224874)
					(end 4.56946 -212.735414)
				)
				(arc
					(start 4.56946 -213.548214)
					(mid 5.08 -214.058754)
					(end 5.59054 -213.548214)
				)
			)
		)
		(polygon
			(pts
				(arc
					(start 7.502906 -211.135722)
					(mid 6.992239 -210.625436)
					(end 6.481826 -211.135976)
				)
				(arc
					(start 6.481826 -211.948776)
					(mid 6.992366 -212.459316)
					(end 7.502906 -211.948776)
				)
			)
		)
		(polygon
			(pts
				(arc
					(start 5.59054 -209.535268)
					(mid 5.079873 -209.024982)
					(end 4.56946 -209.535522)
				)
				(arc
					(start 4.56946 -210.348322)
					(mid 5.08 -210.858862)
					(end 5.59054 -210.348322)
				)
			)
		)
		(polygon
			(pts
				(arc
					(start 7.502906 -207.935576)
					(mid 6.992239 -207.42529)
					(end 6.481826 -207.93583)
				)
				(arc
					(start 6.481826 -208.74863)
					(mid 6.992366 -209.25917)
					(end 7.502906 -208.74863)
				)
			)
		)
		(polygon
			(pts
				(arc
					(start 5.59054 -206.335122)
					(mid 5.079873 -205.824836)
					(end 4.56946 -206.335376)
				)
				(arc
					(start 4.56946 -207.148176)
					(mid 5.08 -207.658716)
					(end 5.59054 -207.148176)
				)
			)
		)
		(polygon
			(pts
				(arc
					(start 7.502906 -204.735684)
					(mid 6.992239 -204.225398)
					(end 6.481826 -204.735938)
				)
				(arc
					(start 6.481826 -205.548738)
					(mid 6.992366 -206.059278)
					(end 7.502906 -205.548738)
				)
			)
		)
		(polygon
			(pts
				(arc
					(start 5.59054 -203.13523)
					(mid 5.079873 -202.624944)
					(end 4.56946 -203.135484)
				)
				(arc
					(start 4.56946 -203.948284)
					(mid 5.08 -204.458824)
					(end 5.59054 -203.948284)
				)
			)
		)
		(polygon
			(pts
				(arc
					(start 7.502906 -201.535538)
					(mid 6.992239 -201.025252)
					(end 6.481826 -201.535792)
				)
				(arc
					(start 6.481826 -202.348592)
					(mid 6.992366 -202.859132)
					(end 7.502906 -202.348592)
				)
			)
		)
		(polygon
			(pts
				(arc
					(start 5.59054 -199.935084)
					(mid 5.079873 -199.424798)
					(end 4.56946 -199.935338)
				)
				(arc
					(start 4.56946 -200.748138)
					(mid 5.08 -201.258678)
					(end 5.59054 -200.748138)
				)
			)
		)
		(polygon
			(pts
				(arc
					(start 7.502906 -195.9356)
					(mid 6.992239 -195.425314)
					(end 6.481826 -195.935854)
				)
				(arc
					(start 6.481826 -196.748654)
					(mid 6.992366 -197.259194)
					(end 7.502906 -196.748654)
				)
			)
		)
		(polygon
			(pts
				(arc
					(start 5.59054 -194.335146)
					(mid 5.079873 -193.82486)
					(end 4.56946 -194.3354)
				)
				(arc
					(start 4.56946 -195.1482)
					(mid 5.08 -195.65874)
					(end 5.59054 -195.1482)
				)
			)
		)
		(polygon
			(pts
				(arc
					(start 7.502906 -192.735708)
					(mid 6.992239 -192.225422)
					(end 6.481826 -192.735962)
				)
				(arc
					(start 6.481826 -193.548762)
					(mid 6.992366 -194.059302)
					(end 7.502906 -193.548762)
				)
			)
		)
		(polygon
			(pts
				(arc
					(start 5.59054 -191.135254)
					(mid 5.079873 -190.624968)
					(end 4.56946 -191.135508)
				)
				(arc
					(start 4.56946 -191.948308)
					(mid 5.08 -192.458848)
					(end 5.59054 -191.948308)
				)
			)
		)
		(polygon
			(pts
				(arc
					(start 7.502906 -184.735724)
					(mid 6.992239 -184.225438)
					(end 6.481826 -184.735978)
				)
				(arc
					(start 6.481826 -185.548778)
					(mid 6.992366 -186.059318)
					(end 7.502906 -185.548778)
				)
			)
		)
		(polygon
			(pts
				(arc
					(start 5.59054 -183.13527)
					(mid 5.079873 -182.624984)
					(end 4.56946 -183.135524)
				)
				(arc
					(start 4.56946 -183.948324)
					(mid 5.08 -184.458864)
					(end 5.59054 -183.948324)
				)
			)
		)
		(polygon
			(pts
				(arc
					(start 222.339154 -182.23103)
					(mid 221.726887 -181.619144)
					(end 221.114874 -182.231284)
				)
				(arc
					(start 221.114874 -183.348884)
					(mid 221.727014 -183.961024)
					(end 222.339154 -183.348884)
				)
			)
		)
		(polygon
			(pts
				(arc
					(start 37.33927 -182.23103)
					(mid 36.727003 -181.619144)
					(end 36.11499 -182.231284)
				)
				(arc
					(start 36.11499 -183.348884)
					(mid 36.72713 -183.961024)
					(end 37.33927 -183.348884)
				)
			)
		)
		(polygon
			(pts
				(arc
					(start 7.502906 -181.535578)
					(mid 6.992239 -181.025292)
					(end 6.481826 -181.535832)
				)
				(arc
					(start 6.481826 -182.348632)
					(mid 6.992366 -182.859172)
					(end 7.502906 -182.348632)
				)
			)
		)
		(polygon
			(pts
				(arc
					(start 220.840554 -179.983384)
					(mid 220.329887 -179.473098)
					(end 219.819474 -179.983638)
				)
				(arc
					(start 219.819474 -180.796438)
					(mid 220.330014 -181.306978)
					(end 220.840554 -180.796438)
				)
			)
		)
		(polygon
			(pts
				(arc
					(start 35.84067 -179.983384)
					(mid 35.330003 -179.473098)
					(end 34.81959 -179.983638)
				)
				(arc
					(start 34.81959 -180.796438)
					(mid 35.33013 -181.306978)
					(end 35.84067 -180.796438)
				)
			)
		)
		(polygon
			(pts
				(arc
					(start 5.59054 -179.935124)
					(mid 5.079873 -179.424838)
					(end 4.56946 -179.935378)
				)
				(arc
					(start 4.56946 -180.748178)
					(mid 5.08 -181.258718)
					(end 5.59054 -180.748178)
				)
			)
		)
		(polygon
			(pts
				(arc
					(start 7.502906 -178.386486)
					(mid 6.992239 -177.8762)
					(end 6.481826 -178.38674)
				)
				(arc
					(start 6.481826 -179.19954)
					(mid 6.992366 -179.71008)
					(end 7.502906 -179.19954)
				)
			)
		)
		(polygon
			(pts
				(arc
					(start 222.339154 -177.430938)
					(mid 221.726887 -176.819052)
					(end 221.114874 -177.431192)
				)
				(arc
					(start 221.114874 -178.548792)
					(mid 221.727014 -179.160932)
					(end 222.339154 -178.548792)
				)
			)
		)
		(polygon
			(pts
				(arc
					(start 37.33927 -177.430938)
					(mid 36.727003 -176.819052)
					(end 36.11499 -177.431192)
				)
				(arc
					(start 36.11499 -178.548792)
					(mid 36.72713 -179.160932)
					(end 37.33927 -178.548792)
				)
			)
		)
		(polygon
			(pts
				(arc
					(start 5.59054 -176.735232)
					(mid 5.079873 -176.224946)
					(end 4.56946 -176.735486)
				)
				(arc
					(start 4.56946 -177.548286)
					(mid 5.08 -178.058826)
					(end 5.59054 -177.548286)
				)
			)
		)
		(polygon
			(pts
				(arc
					(start 7.502906 -175.18634)
					(mid 6.992239 -174.676054)
					(end 6.481826 -175.186594)
				)
				(arc
					(start 6.481826 -175.999394)
					(mid 6.992366 -176.509934)
					(end 7.502906 -175.999394)
				)
			)
		)
		(polygon
			(pts
				(arc
					(start 220.840554 -175.183292)
					(mid 220.329887 -174.673006)
					(end 219.819474 -175.183546)
				)
				(arc
					(start 219.819474 -175.996346)
					(mid 220.330014 -176.506886)
					(end 220.840554 -175.996346)
				)
			)
		)
		(polygon
			(pts
				(arc
					(start 35.84067 -175.183292)
					(mid 35.330003 -174.673006)
					(end 34.81959 -175.183546)
				)
				(arc
					(start 34.81959 -175.996346)
					(mid 35.33013 -176.506886)
					(end 35.84067 -175.996346)
				)
			)
		)
		(polygon
			(pts
				(arc
					(start 5.59054 -173.535086)
					(mid 5.079873 -173.0248)
					(end 4.56946 -173.53534)
				)
				(arc
					(start 4.56946 -174.34814)
					(mid 5.08 -174.85868)
					(end 5.59054 -174.34814)
				)
			)
		)
		(polygon
			(pts
				(arc
					(start 222.339154 -172.630846)
					(mid 221.726887 -172.01896)
					(end 221.114874 -172.6311)
				)
				(arc
					(start 221.114874 -173.7487)
					(mid 221.727014 -174.36084)
					(end 222.339154 -173.7487)
				)
			)
		)
		(polygon
			(pts
				(arc
					(start 37.33927 -172.630846)
					(mid 36.727003 -172.01896)
					(end 36.11499 -172.6311)
				)
				(arc
					(start 36.11499 -173.7487)
					(mid 36.72713 -174.36084)
					(end 37.33927 -173.7487)
				)
			)
		)
		(polygon
			(pts
				(arc
					(start 7.502906 -171.986448)
					(mid 6.992239 -171.476162)
					(end 6.481826 -171.986702)
				)
				(arc
					(start 6.481826 -172.799502)
					(mid 6.992366 -173.310042)
					(end 7.502906 -172.799502)
				)
			)
		)
		(polygon
			(pts
				(arc
					(start 220.840554 -170.383454)
					(mid 220.329887 -169.873168)
					(end 219.819474 -170.383708)
				)
				(arc
					(start 219.819474 -171.196508)
					(mid 220.330014 -171.707048)
					(end 220.840554 -171.196508)
				)
			)
		)
		(polygon
			(pts
				(arc
					(start 35.84067 -170.383454)
					(mid 35.330003 -169.873168)
					(end 34.81959 -170.383708)
				)
				(arc
					(start 34.81959 -171.196508)
					(mid 35.33013 -171.707048)
					(end 35.84067 -171.196508)
				)
			)
		)
		(polygon
			(pts
				(arc
					(start 5.59054 -170.335194)
					(mid 5.079873 -169.824908)
					(end 4.56946 -170.335448)
				)
				(arc
					(start 4.56946 -171.148248)
					(mid 5.08 -171.658788)
					(end 5.59054 -171.148248)
				)
			)
		)
		(polygon
			(pts
				(arc
					(start 7.502906 -168.786556)
					(mid 6.992239 -168.27627)
					(end 6.481826 -168.78681)
				)
				(arc
					(start 6.481826 -169.59961)
					(mid 6.992366 -170.11015)
					(end 7.502906 -169.59961)
				)
			)
		)
		(polygon
			(pts
				(arc
					(start 5.59054 -167.135048)
					(mid 5.079873 -166.624762)
					(end 4.56946 -167.135302)
				)
				(arc
					(start 4.56946 -167.948102)
					(mid 5.08 -168.458642)
					(end 5.59054 -167.948102)
				)
			)
		)
		(polygon
			(pts
				(arc
					(start 5.59054 -163.935156)
					(mid 5.079873 -163.42487)
					(end 4.56946 -163.93541)
				)
				(arc
					(start 4.56946 -164.74821)
					(mid 5.08 -165.25875)
					(end 5.59054 -164.74821)
				)
			)
		)
		(polygon
			(pts
				(arc
					(start 233.897424 -163.579302)
					(mid 233.386884 -163.068762)
					(end 232.876344 -163.579302)
				)
				(arc
					(start 232.876344 -164.392356)
					(mid 233.387011 -164.902642)
					(end 233.897424 -164.392102)
				)
			)
		)
		(polygon
			(pts
				(arc
					(start 48.89754 -163.579048)
					(mid 48.386873 -163.068762)
					(end 47.87646 -163.579302)
				)
				(arc
					(start 47.87646 -164.392102)
					(mid 48.387 -164.902642)
					(end 48.89754 -164.392102)
				)
			)
		)
		(polygon
			(pts
				(arc
					(start 230.720138 -163.300664)
					(mid 231.230424 -162.789997)
					(end 230.719884 -162.279584)
				)
				(arc
					(start 229.907084 -162.279584)
					(mid 229.396544 -162.790124)
					(end 229.907084 -163.300664)
				)
			)
		)
		(polygon
			(pts
				(arc
					(start 45.72 -163.300664)
					(mid 46.23054 -162.790124)
					(end 45.72 -162.279584)
				)
				(arc
					(start 44.906946 -162.279584)
					(mid 44.39666 -162.790251)
					(end 44.9072 -163.300664)
				)
			)
		)
		(polygon
			(pts
				(arc
					(start 7.502906 -162.386518)
					(mid 6.992239 -161.876232)
					(end 6.481826 -162.386772)
				)
				(arc
					(start 6.481826 -163.199572)
					(mid 6.992366 -163.710112)
					(end 7.502906 -163.199572)
				)
			)
		)
		(polygon
			(pts
				(arc
					(start 5.59054 -160.735264)
					(mid 5.079873 -160.224978)
					(end 4.56946 -160.735518)
				)
				(arc
					(start 4.56946 -161.548318)
					(mid 5.08 -162.058858)
					(end 5.59054 -161.548318)
				)
			)
		)
		(polygon
			(pts
				(arc
					(start 222.339154 -159.831024)
					(mid 221.726887 -159.219138)
					(end 221.114874 -159.831278)
				)
				(arc
					(start 221.114874 -160.948878)
					(mid 221.727014 -161.561018)
					(end 222.339154 -160.948878)
				)
			)
		)
		(polygon
			(pts
				(arc
					(start 37.33927 -159.831024)
					(mid 36.727003 -159.219138)
					(end 36.11499 -159.831278)
				)
				(arc
					(start 36.11499 -160.948878)
					(mid 36.72713 -161.561018)
					(end 37.33927 -160.948878)
				)
			)
		)
		(polygon
			(pts
				(arc
					(start 7.502906 -159.186372)
					(mid 6.992239 -158.676086)
					(end 6.481826 -159.186626)
				)
				(arc
					(start 6.481826 -159.999426)
					(mid 6.992366 -160.509966)
					(end 7.502906 -159.999426)
				)
			)
		)
		(polygon
			(pts
				(arc
					(start 220.840554 -157.583378)
					(mid 220.329887 -157.073092)
					(end 219.819474 -157.583632)
				)
				(arc
					(start 219.819474 -158.396432)
					(mid 220.330014 -158.906972)
					(end 220.840554 -158.396432)
				)
			)
		)
		(polygon
			(pts
				(arc
					(start 35.84067 -157.583378)
					(mid 35.330003 -157.073092)
					(end 34.81959 -157.583632)
				)
				(arc
					(start 34.81959 -158.396432)
					(mid 35.33013 -158.906972)
					(end 35.84067 -158.396432)
				)
			)
		)
		(polygon
			(pts
				(arc
					(start 5.59054 -157.535118)
					(mid 5.079873 -157.024832)
					(end 4.56946 -157.535372)
				)
				(arc
					(start 4.56946 -158.348172)
					(mid 5.08 -158.858712)
					(end 5.59054 -158.348172)
				)
			)
		)
		(polygon
			(pts
				(arc
					(start 7.502906 -155.97378)
					(mid 6.992239 -155.463494)
					(end 6.481826 -155.974034)
				)
				(arc
					(start 6.481826 -156.786834)
					(mid 6.992366 -157.297374)
					(end 7.502906 -156.786834)
				)
			)
		)
		(polygon
			(pts
				(arc
					(start 5.59054 -154.335226)
					(mid 5.079873 -153.82494)
					(end 4.56946 -154.33548)
				)
				(arc
					(start 4.56946 -155.14828)
					(mid 5.08 -155.65882)
					(end 5.59054 -155.14828)
				)
			)
		)
		(polygon
			(pts
				(arc
					(start 7.502906 -152.786334)
					(mid 6.992239 -152.276048)
					(end 6.481826 -152.786588)
				)
				(arc
					(start 6.481826 -153.599388)
					(mid 6.992366 -154.109928)
					(end 7.502906 -153.599388)
				)
			)
		)
		(polygon
			(pts
				(arc
					(start 27.18054 -141.603476)
					(mid 26.67 -141.092936)
					(end 26.15946 -141.603476)
				)
				(arc
					(start 26.15946 -142.41653)
					(mid 26.670127 -142.926816)
					(end 27.18054 -142.416276)
				)
			)
		)
		(polygon
			(pts
				(arc
					(start 25.88514 -139.050776)
					(mid 25.272873 -138.43889)
					(end 24.66086 -139.05103)
				)
				(arc
					(start 24.66086 -140.16863)
					(mid 25.273 -140.78077)
					(end 25.88514 -140.16863)
				)
			)
		)
		(polygon
			(pts
				(arc
					(start 32.00654 -135.603488)
					(mid 31.495873 -135.093202)
					(end 30.98546 -135.603742)
				)
				(arc
					(start 30.98546 -136.416542)
					(mid 31.496 -136.927082)
					(end 32.00654 -136.416542)
				)
			)
		)
		(polygon
			(pts
				(arc
					(start 17.78254 -135.603234)
					(mid 17.272 -135.092694)
					(end 16.76146 -135.603234)
				)
				(arc
					(start 16.76146 -136.416288)
					(mid 17.272127 -136.926574)
					(end 17.78254 -136.416034)
				)
			)
		)
		(polygon
			(pts
				(arc
					(start 27.18054 -128.8034)
					(mid 26.67 -128.29286)
					(end 26.15946 -128.8034)
				)
				(arc
					(start 26.15946 -129.616454)
					(mid 26.670127 -130.12674)
					(end 27.18054 -129.6162)
				)
			)
		)
		(polygon
			(pts
				(arc
					(start 25.88514 -126.251208)
					(mid 25.273 -125.639068)
					(end 24.66086 -126.251208)
				)
				(arc
					(start 24.66086 -127.369062)
					(mid 25.273127 -127.980948)
					(end 25.88514 -127.368808)
				)
			)
		)
		(polygon
			(pts
				(arc
					(start 27.18054 -124.003562)
					(mid 26.67 -123.493022)
					(end 26.15946 -124.003562)
				)
				(arc
					(start 26.15946 -124.816616)
					(mid 26.670127 -125.326902)
					(end 27.18054 -124.816362)
				)
			)
		)
		(polygon
			(pts
				(arc
					(start 25.88514 -121.451116)
					(mid 25.273 -120.838976)
					(end 24.66086 -121.451116)
				)
				(arc
					(start 24.66086 -122.56897)
					(mid 25.273127 -123.180856)
					(end 25.88514 -122.568716)
				)
			)
		)
		(polygon
			(pts
				(arc
					(start 27.18054 -119.20347)
					(mid 26.67 -118.69293)
					(end 26.15946 -119.20347)
				)
				(arc
					(start 26.15946 -120.016524)
					(mid 26.670127 -120.52681)
					(end 27.18054 -120.01627)
				)
			)
		)
		(polygon
			(pts
				(arc
					(start 25.88514 -116.65077)
					(mid 25.272873 -116.038884)
					(end 24.66086 -116.651024)
				)
				(arc
					(start 24.66086 -117.768624)
					(mid 25.273 -118.380764)
					(end 25.88514 -117.768624)
				)
			)
		)
		(polygon
			(pts
				(arc
					(start 222.339154 -79.230982)
					(mid 221.726887 -78.619096)
					(end 221.114874 -79.231236)
				)
				(arc
					(start 221.114874 -80.348836)
					(mid 221.727014 -80.960976)
					(end 222.339154 -80.348836)
				)
			)
		)
		(polygon
			(pts
				(arc
					(start 37.33927 -79.230982)
					(mid 36.727003 -78.619096)
					(end 36.11499 -79.231236)
				)
				(arc
					(start 36.11499 -80.348836)
					(mid 36.72713 -80.960976)
					(end 37.33927 -80.348836)
				)
			)
		)
		(polygon
			(pts
				(arc
					(start 220.840554 -76.983336)
					(mid 220.329887 -76.47305)
					(end 219.819474 -76.98359)
				)
				(arc
					(start 219.819474 -77.79639)
					(mid 220.330014 -78.30693)
					(end 220.840554 -77.79639)
				)
			)
		)
		(polygon
			(pts
				(arc
					(start 35.84067 -76.983336)
					(mid 35.330003 -76.47305)
					(end 34.81959 -76.98359)
				)
				(arc
					(start 34.81959 -77.79639)
					(mid 35.33013 -78.30693)
					(end 35.84067 -77.79639)
				)
			)
		)
		(polygon
			(pts
				(arc
					(start 222.339154 -74.43089)
					(mid 221.726887 -73.819004)
					(end 221.114874 -74.431144)
				)
				(arc
					(start 221.114874 -75.548744)
					(mid 221.727014 -76.160884)
					(end 222.339154 -75.548744)
				)
			)
		)
		(polygon
			(pts
				(arc
					(start 37.33927 -74.43089)
					(mid 36.727003 -73.819004)
					(end 36.11499 -74.431144)
				)
				(arc
					(start 36.11499 -75.548744)
					(mid 36.72713 -76.160884)
					(end 37.33927 -75.548744)
				)
			)
		)
		(polygon
			(pts
				(arc
					(start 220.840554 -72.183244)
					(mid 220.329887 -71.672958)
					(end 219.819474 -72.183498)
				)
				(arc
					(start 219.819474 -72.996298)
					(mid 220.330014 -73.506838)
					(end 220.840554 -72.996298)
				)
			)
		)
		(polygon
			(pts
				(arc
					(start 35.84067 -72.183244)
					(mid 35.330003 -71.672958)
					(end 34.81959 -72.183498)
				)
				(arc
					(start 34.81959 -72.996298)
					(mid 35.33013 -73.506838)
					(end 35.84067 -72.996298)
				)
			)
		)
		(polygon
			(pts
				(arc
					(start 222.339154 -69.630798)
					(mid 221.726887 -69.018912)
					(end 221.114874 -69.631052)
				)
				(arc
					(start 221.114874 -70.748652)
					(mid 221.727014 -71.360792)
					(end 222.339154 -70.748652)
				)
			)
		)
		(polygon
			(pts
				(arc
					(start 37.33927 -69.630798)
					(mid 36.727003 -69.018912)
					(end 36.11499 -69.631052)
				)
				(arc
					(start 36.11499 -70.748652)
					(mid 36.72713 -71.360792)
					(end 37.33927 -70.748652)
				)
			)
		)
		(polygon
			(pts
				(arc
					(start 220.840554 -67.383406)
					(mid 220.329887 -66.87312)
					(end 219.819474 -67.38366)
				)
				(arc
					(start 219.819474 -68.19646)
					(mid 220.330014 -68.707)
					(end 220.840554 -68.19646)
				)
			)
		)
		(polygon
			(pts
				(arc
					(start 35.84067 -67.383406)
					(mid 35.330003 -66.87312)
					(end 34.81959 -67.38366)
				)
				(arc
					(start 34.81959 -68.19646)
					(mid 35.33013 -68.707)
					(end 35.84067 -68.19646)
				)
			)
		)
		(polygon
			(pts
				(arc
					(start 233.897424 -60.579254)
					(mid 233.386884 -60.068714)
					(end 232.876344 -60.579254)
				)
				(arc
					(start 232.876344 -61.392308)
					(mid 233.387011 -61.902594)
					(end 233.897424 -61.392054)
				)
			)
		)
		(polygon
			(pts
				(arc
					(start 48.89754 -60.579)
					(mid 48.386873 -60.068714)
					(end 47.87646 -60.579254)
				)
				(arc
					(start 47.87646 -61.392054)
					(mid 48.387 -61.902594)
					(end 48.89754 -61.392054)
				)
			)
		)
		(polygon
			(pts
				(arc
					(start 230.720138 -60.300616)
					(mid 231.230424 -59.789949)
					(end 230.719884 -59.279536)
				)
				(arc
					(start 229.907084 -59.279536)
					(mid 229.396544 -59.790076)
					(end 229.907084 -60.300616)
				)
			)
		)
		(polygon
			(pts
				(arc
					(start 45.72 -60.300616)
					(mid 46.23054 -59.790076)
					(end 45.72 -59.279536)
				)
				(arc
					(start 44.906946 -59.279536)
					(mid 44.39666 -59.790203)
					(end 44.9072 -60.300616)
				)
			)
		)
		(polygon
			(pts
				(arc
					(start 222.339154 -56.830976)
					(mid 221.726887 -56.21909)
					(end 221.114874 -56.83123)
				)
				(arc
					(start 221.114874 -57.94883)
					(mid 221.727014 -58.56097)
					(end 222.339154 -57.94883)
				)
			)
		)
		(polygon
			(pts
				(arc
					(start 37.33927 -56.830976)
					(mid 36.727003 -56.21909)
					(end 36.11499 -56.83123)
				)
				(arc
					(start 36.11499 -57.94883)
					(mid 36.72713 -58.56097)
					(end 37.33927 -57.94883)
				)
			)
		)
		(polygon
			(pts
				(arc
					(start 220.840554 -54.58333)
					(mid 220.329887 -54.073044)
					(end 219.819474 -54.583584)
				)
				(arc
					(start 219.819474 -55.396384)
					(mid 220.330014 -55.906924)
					(end 220.840554 -55.396384)
				)
			)
		)
		(polygon
			(pts
				(arc
					(start 35.84067 -54.58333)
					(mid 35.330003 -54.073044)
					(end 34.81959 -54.583584)
				)
				(arc
					(start 34.81959 -55.396384)
					(mid 35.33013 -55.906924)
					(end 35.84067 -55.396384)
				)
			)
		)
		(polygon
			(pts
				(arc
					(start 27.18054 -38.603428)
					(mid 26.67 -38.092888)
					(end 26.15946 -38.603428)
				)
				(arc
					(start 26.15946 -39.416482)
					(mid 26.670127 -39.926768)
					(end 27.18054 -39.416228)
				)
			)
		)
		(polygon
			(pts
				(arc
					(start 25.88514 -36.050982)
					(mid 25.273 -35.438842)
					(end 24.66086 -36.050982)
				)
				(arc
					(start 24.66086 -37.168836)
					(mid 25.273127 -37.780722)
					(end 25.88514 -37.168582)
				)
			)
		)
		(polygon
			(pts
				(arc
					(start 32.00654 -32.602932)
					(mid 31.495873 -32.092646)
					(end 30.98546 -32.603186)
				)
				(arc
					(start 30.98546 -33.415986)
					(mid 31.496 -33.926526)
					(end 32.00654 -33.415986)
				)
			)
		)
		(polygon
			(pts
				(arc
					(start 17.78254 -32.602932)
					(mid 17.271873 -32.092646)
					(end 16.76146 -32.603186)
				)
				(arc
					(start 16.76146 -33.415986)
					(mid 17.272 -33.926526)
					(end 17.78254 -33.415986)
				)
			)
		)
		(polygon
			(pts
				(arc
					(start 27.18054 -25.803352)
					(mid 26.67 -25.292812)
					(end 26.15946 -25.803352)
				)
				(arc
					(start 26.15946 -26.616406)
					(mid 26.670127 -27.126692)
					(end 27.18054 -26.616152)
				)
			)
		)
		(polygon
			(pts
				(arc
					(start 25.88514 -23.25116)
					(mid 25.273 -22.63902)
					(end 24.66086 -23.25116)
				)
				(arc
					(start 24.66086 -24.369014)
					(mid 25.273127 -24.9809)
					(end 25.88514 -24.36876)
				)
			)
		)
		(polygon
			(pts
				(arc
					(start 27.18054 -21.003514)
					(mid 26.67 -20.492974)
					(end 26.15946 -21.003514)
				)
				(arc
					(start 26.15946 -21.816568)
					(mid 26.670127 -22.326854)
					(end 27.18054 -21.816314)
				)
			)
		)
		(polygon
			(pts
				(arc
					(start 25.88514 -18.451068)
					(mid 25.273 -17.838928)
					(end 24.66086 -18.451068)
				)
				(arc
					(start 24.66086 -19.568922)
					(mid 25.273127 -20.180808)
					(end 25.88514 -19.568668)
				)
			)
		)
		(polygon
			(pts
				(arc
					(start 27.18054 -16.203422)
					(mid 26.67 -15.692882)
					(end 26.15946 -16.203422)
				)
				(arc
					(start 26.15946 -17.016476)
					(mid 26.670127 -17.526762)
					(end 27.18054 -17.016222)
				)
			)
		)
		(polygon
			(pts
				(arc
					(start 25.88514 -13.676122)
					(mid 25.272873 -13.064236)
					(end 24.66086 -13.676376)
				)
				(arc
					(start 24.66086 -14.793976)
					(mid 25.273 -15.406116)
					(end 25.88514 -14.793976)
				)
			)
		)
	)
	(zone
		(net "P12V")
		(layer "In4.Cu")
		(hatch none 0.5)
		(connect_pads
			(clearance 0.5)
		)
		(min_thickness 0.25)
		(fill yes
			(thermal_gap 0.5)
			(thermal_bridge_width 0.5)
			(island_removal_mode 0)
		)
		(polygon
			(pts
				(xy 1.27 -1.27) (xy 1.27 -185.971942)
				(arc
					(start 4.400042 -185.971942)
					(mid 6.748938 -188.025883)
					(end 5.02666 -190.627762)
				)
				(arc
					(start 5.02666 -190.627762)
					(mid 5.421533 -190.756027)
					(end 5.59054 -191.135254)
				)
				(arc
					(start 5.59054 -191.948308)
					(mid 5.08 -192.458848)
					(end 4.56946 -191.948308)
				)
				(arc
					(start 4.56946 -191.135508)
					(mid 4.658352 -190.847646)
					(end 4.894072 -190.66002)
				)
				(arc
					(start 4.894072 -190.66002)
					(mid 4.648425 -190.69903)
					(end 4.400042 -190.71209)
				)
				(xy 1.27 -190.71209) (xy 1.27 -311.971944)
				(arc
					(start 4.400042 -311.971944)
					(mid 6.748938 -314.025885)
					(end 5.02666 -316.627764)
				)
				(arc
					(start 5.02666 -316.627764)
					(mid 5.421533 -316.756029)
					(end 5.59054 -317.135256)
				)
				(arc
					(start 5.59054 -317.94831)
					(mid 5.08 -318.45885)
					(end 4.56946 -317.94831)
				)
				(arc
					(start 4.56946 -317.13551)
					(mid 4.658352 -316.847648)
					(end 4.894072 -316.660022)
				)
				(arc
					(start 4.894072 -316.660022)
					(mid 4.648425 -316.699032)
					(end 4.400042 -316.712092)
				)
				(xy 1.27 -316.712092) (xy 1.27 -417.971986)
				(arc
					(start 4.400042 -417.971986)
					(mid 4.649978 -417.985257)
					(end 4.89712 -418.024818)
				)
				(arc
					(start 4.89712 -418.024818)
					(mid 4.659322 -417.837288)
					(end 4.56946 -417.54806)
				)
				(arc
					(start 4.56946 -416.73526)
					(mid 5.079873 -416.22472)
					(end 5.59054 -416.735006)
				)
				(arc
					(start 5.59054 -417.54806)
					(mid 5.420396 -417.928562)
					(end 5.023358 -418.055552)
				)
				(arc
					(start 5.023358 -418.055552)
					(mid 6.7698 -420.340456)
					(end 5.026406 -422.627552)
				)
				(arc
					(start 5.026406 -422.627552)
					(mid 5.421457 -422.755712)
					(end 5.59054 -423.135044)
				)
				(arc
					(start 5.59054 -423.948098)
					(mid 5.08 -424.458638)
					(end 4.56946 -423.948098)
				)
				(arc
					(start 4.56946 -423.135298)
					(mid 4.658352 -422.847436)
					(end 4.894072 -422.65981)
				)
				(arc
					(start 4.894072 -422.65981)
					(mid 4.648425 -422.69882)
					(end 4.400042 -422.71188)
				)
				(xy 1.27 -422.71188) (xy 1.27 -504.730004) (xy 262.230108 -504.730004) (xy 262.230108 -428.60595)
				(xy 261.974076 -428.349918)
				(arc
					(start 261.290054 -428.349918)
					(mid 259.409065 -427.570945)
					(end 258.629912 -425.69003)
				)
				(xy 258.629912 -412.011114) (xy 258.37388 -411.755082)
				(arc
					(start 252.394974 -411.755082)
					(mid 250.59005 -409.950158)
					(end 252.394974 -408.14498)
				)
				(xy 258.37388 -408.14498) (xy 258.629912 -407.888948)
				(arc
					(start 258.629912 -364.309914)
					(mid 259.409139 -362.429074)
					(end 261.290054 -361.650026)
				)
				(xy 261.974076 -361.650026) (xy 262.230108 -361.393994) (xy 262.230108 -1.27) (xy 37.978588 -1.27)
				(arc
					(start 36.794948 -3.59537)
					(mid 36.776323 -3.646095)
					(end 36.770056 -3.699764)
				)
				(arc
					(start 36.770056 -4.500118)
					(mid 34.000186 -7.269988)
					(end 31.230062 -4.500118)
				)
				(arc
					(start 31.230062 -3.700018)
					(mid 31.223617 -3.646471)
					(end 31.204916 -3.595878)
				)
				(xy 30.021276 -1.27)
			)
		)
		(polygon
			(pts
				(arc
					(start 37.33927 -491.231428)
					(mid 36.72713 -490.619288)
					(end 36.11499 -491.231428)
				)
				(arc
					(start 36.11499 -492.349282)
					(mid 36.727257 -492.961168)
					(end 37.33927 -492.349028)
				)
			)
		)
		(polygon
			(pts
				(arc
					(start 222.339154 -491.231174)
					(mid 221.726887 -490.619288)
					(end 221.114874 -491.231428)
				)
				(arc
					(start 221.114874 -492.349028)
					(mid 221.727014 -492.961168)
					(end 222.339154 -492.349028)
				)
			)
		)
		(polygon
			(pts
				(arc
					(start 35.84067 -488.983782)
					(mid 35.33013 -488.473242)
					(end 34.81959 -488.983782)
				)
				(arc
					(start 34.81959 -489.796836)
					(mid 35.330257 -490.307122)
					(end 35.84067 -489.796582)
				)
			)
		)
		(polygon
			(pts
				(arc
					(start 220.840554 -488.983528)
					(mid 220.329887 -488.473242)
					(end 219.819474 -488.983782)
				)
				(arc
					(start 219.819474 -489.796582)
					(mid 220.330014 -490.307122)
					(end 220.840554 -489.796582)
				)
			)
		)
		(polygon
			(pts
				(arc
					(start 222.339154 -486.431082)
					(mid 221.726887 -485.819196)
					(end 221.114874 -486.431336)
				)
				(arc
					(start 221.114874 -487.548936)
					(mid 221.727014 -488.161076)
					(end 222.339154 -487.548936)
				)
			)
		)
		(polygon
			(pts
				(arc
					(start 37.33927 -486.431082)
					(mid 36.727003 -485.819196)
					(end 36.11499 -486.431336)
				)
				(arc
					(start 36.11499 -487.548936)
					(mid 36.72713 -488.161076)
					(end 37.33927 -487.548936)
				)
			)
		)
		(polygon
			(pts
				(arc
					(start 35.84067 -484.18369)
					(mid 35.33013 -483.67315)
					(end 34.81959 -484.18369)
				)
				(arc
					(start 34.81959 -484.996744)
					(mid 35.330257 -485.50703)
					(end 35.84067 -484.99649)
				)
			)
		)
		(polygon
			(pts
				(arc
					(start 220.840554 -484.183436)
					(mid 220.329887 -483.67315)
					(end 219.819474 -484.18369)
				)
				(arc
					(start 219.819474 -484.99649)
					(mid 220.330014 -485.50703)
					(end 220.840554 -484.99649)
				)
			)
		)
		(polygon
			(pts
				(arc
					(start 37.33927 -481.631244)
					(mid 36.72713 -481.019104)
					(end 36.11499 -481.631244)
				)
				(arc
					(start 36.11499 -482.749098)
					(mid 36.727257 -483.360984)
					(end 37.33927 -482.748844)
				)
			)
		)
		(polygon
			(pts
				(arc
					(start 222.339154 -481.63099)
					(mid 221.726887 -481.019104)
					(end 221.114874 -481.631244)
				)
				(arc
					(start 221.114874 -482.748844)
					(mid 221.727014 -483.360984)
					(end 222.339154 -482.748844)
				)
			)
		)
		(polygon
			(pts
				(arc
					(start 35.84067 -479.383852)
					(mid 35.33013 -478.873312)
					(end 34.81959 -479.383852)
				)
				(arc
					(start 34.81959 -480.196906)
					(mid 35.330257 -480.707192)
					(end 35.84067 -480.196652)
				)
			)
		)
		(polygon
			(pts
				(arc
					(start 220.840554 -479.383598)
					(mid 220.329887 -478.873312)
					(end 219.819474 -479.383852)
				)
				(arc
					(start 219.819474 -480.196652)
					(mid 220.330014 -480.707192)
					(end 220.840554 -480.196652)
				)
			)
		)
		(polygon
			(pts
				(arc
					(start 233.897424 -472.579446)
					(mid 233.386884 -472.068906)
					(end 232.876344 -472.579446)
				)
				(arc
					(start 232.876344 -473.3925)
					(mid 233.387011 -473.902786)
					(end 233.897424 -473.392246)
				)
			)
		)
		(polygon
			(pts
				(arc
					(start 48.89754 -472.579192)
					(mid 48.386873 -472.068906)
					(end 47.87646 -472.579446)
				)
				(arc
					(start 47.87646 -473.392246)
					(mid 48.387 -473.902786)
					(end 48.89754 -473.392246)
				)
			)
		)
		(polygon
			(pts
				(arc
					(start 230.720138 -472.300808)
					(mid 231.230424 -471.790141)
					(end 230.719884 -471.279728)
				)
				(arc
					(start 229.907084 -471.279728)
					(mid 229.396544 -471.790268)
					(end 229.907084 -472.300808)
				)
			)
		)
		(polygon
			(pts
				(arc
					(start 45.720254 -472.300808)
					(mid 46.23054 -471.790141)
					(end 45.72 -471.279728)
				)
				(arc
					(start 44.9072 -471.279728)
					(mid 44.39666 -471.790268)
					(end 44.9072 -472.300808)
				)
			)
		)
		(polygon
			(pts
				(arc
					(start 37.33927 -468.831422)
					(mid 36.72713 -468.219282)
					(end 36.11499 -468.831422)
				)
				(arc
					(start 36.11499 -469.949276)
					(mid 36.727257 -470.561162)
					(end 37.33927 -469.949022)
				)
			)
		)
		(polygon
			(pts
				(arc
					(start 222.339154 -468.831168)
					(mid 221.726887 -468.219282)
					(end 221.114874 -468.831422)
				)
				(arc
					(start 221.114874 -469.949022)
					(mid 221.727014 -470.561162)
					(end 222.339154 -469.949022)
				)
			)
		)
		(polygon
			(pts
				(arc
					(start 35.84067 -466.583776)
					(mid 35.33013 -466.073236)
					(end 34.81959 -466.583776)
				)
				(arc
					(start 34.81959 -467.39683)
					(mid 35.330257 -467.907116)
					(end 35.84067 -467.396576)
				)
			)
		)
		(polygon
			(pts
				(arc
					(start 220.840554 -466.583522)
					(mid 220.329887 -466.073236)
					(end 219.819474 -466.583776)
				)
				(arc
					(start 219.819474 -467.396576)
					(mid 220.330014 -467.907116)
					(end 220.840554 -467.396576)
				)
			)
		)
		(polygon
			(pts
				(arc
					(start 27.18054 -450.603366)
					(mid 26.669873 -450.09308)
					(end 26.15946 -450.60362)
				)
				(arc
					(start 26.15946 -451.41642)
					(mid 26.67 -451.92696)
					(end 27.18054 -451.41642)
				)
			)
		)
		(polygon
			(pts
				(arc
					(start 7.2898 -449.978272)
					(mid 7.80034 -449.467732)
					(end 7.2898 -448.957192)
				)
				(arc
					(start 6.476746 -448.957192)
					(mid 5.96646 -449.467859)
					(end 6.477 -449.978272)
				)
			)
		)
		(polygon
			(pts
				(arc
					(start 25.88514 -448.05092)
					(mid 25.272873 -447.439034)
					(end 24.66086 -448.051174)
				)
				(arc
					(start 24.66086 -449.168774)
					(mid 25.273 -449.780914)
					(end 25.88514 -449.168774)
				)
			)
		)
		(polygon
			(pts
				(arc
					(start 7.502906 -446.384172)
					(mid 6.992366 -445.873632)
					(end 6.481826 -446.384172)
				)
				(arc
					(start 6.481826 -447.197226)
					(mid 6.992493 -447.707512)
					(end 7.502906 -447.196972)
				)
			)
		)
		(polygon
			(pts
				(arc
					(start 5.59054 -444.735204)
					(mid 5.08 -444.224664)
					(end 4.56946 -444.735204)
				)
				(arc
					(start 4.56946 -445.548258)
					(mid 5.080127 -446.058544)
					(end 5.59054 -445.548004)
				)
			)
		)
		(polygon
			(pts
				(arc
					(start 17.78254 -444.603378)
					(mid 17.272 -444.092838)
					(end 16.76146 -444.603378)
				)
				(arc
					(start 16.76146 -445.416432)
					(mid 17.272127 -445.926718)
					(end 17.78254 -445.416178)
				)
			)
		)
		(polygon
			(pts
				(arc
					(start 32.26054 -444.584582)
					(mid 31.749873 -444.074296)
					(end 31.23946 -444.584836)
				)
				(arc
					(start 31.23946 -445.397636)
					(mid 31.75 -445.908176)
					(end 32.26054 -445.397636)
				)
			)
		)
		(polygon
			(pts
				(arc
					(start 7.502906 -443.18428)
					(mid 6.992366 -442.67374)
					(end 6.481826 -443.18428)
				)
				(arc
					(start 6.481826 -443.997334)
					(mid 6.992493 -444.50762)
					(end 7.502906 -443.99708)
				)
			)
		)
		(polygon
			(pts
				(arc
					(start 5.59054 -441.535312)
					(mid 5.08 -441.024772)
					(end 4.56946 -441.535312)
				)
				(arc
					(start 4.56946 -442.348366)
					(mid 5.080127 -442.858652)
					(end 5.59054 -442.348112)
				)
			)
		)
		(polygon
			(pts
				(arc
					(start 7.502906 -439.984134)
					(mid 6.992366 -439.473594)
					(end 6.481826 -439.984134)
				)
				(arc
					(start 6.481826 -440.797188)
					(mid 6.992493 -441.307474)
					(end 7.502906 -440.796934)
				)
			)
		)
		(polygon
			(pts
				(arc
					(start 5.59054 -438.335166)
					(mid 5.08 -437.824626)
					(end 4.56946 -438.335166)
				)
				(arc
					(start 4.56946 -439.14822)
					(mid 5.080127 -439.658506)
					(end 5.59054 -439.147966)
				)
			)
		)
		(polygon
			(pts
				(arc
					(start 27.18054 -437.80329)
					(mid 26.669873 -437.293004)
					(end 26.15946 -437.803544)
				)
				(arc
					(start 26.15946 -438.616344)
					(mid 26.67 -439.126884)
					(end 27.18054 -438.616344)
				)
			)
		)
		(polygon
			(pts
				(arc
					(start 7.502906 -436.784242)
					(mid 6.992366 -436.273702)
					(end 6.481826 -436.784242)
				)
				(arc
					(start 6.481826 -437.597296)
					(mid 6.992493 -438.107582)
					(end 7.502906 -437.597042)
				)
			)
		)
		(polygon
			(pts
				(arc
					(start 25.88514 -435.251098)
					(mid 25.272873 -434.639212)
					(end 24.66086 -435.251352)
				)
				(arc
					(start 24.66086 -436.368952)
					(mid 25.273 -436.981092)
					(end 25.88514 -436.368952)
				)
			)
		)
		(polygon
			(pts
				(arc
					(start 5.59054 -435.135274)
					(mid 5.08 -434.624734)
					(end 4.56946 -435.135274)
				)
				(arc
					(start 4.56946 -435.948328)
					(mid 5.080127 -436.458614)
					(end 5.59054 -435.948074)
				)
			)
		)
		(polygon
			(pts
				(arc
					(start 27.18054 -433.003452)
					(mid 26.669873 -432.493166)
					(end 26.15946 -433.003706)
				)
				(arc
					(start 26.15946 -433.816506)
					(mid 26.67 -434.327046)
					(end 27.18054 -433.816506)
				)
			)
		)
		(polygon
			(pts
				(arc
					(start 7.502906 -431.18405)
					(mid 6.992239 -430.673764)
					(end 6.481826 -431.184304)
				)
				(arc
					(start 6.481826 -431.997104)
					(mid 6.992366 -432.507644)
					(end 7.502906 -431.997104)
				)
			)
		)
		(polygon
			(pts
				(arc
					(start 72.90054 -431.139346)
					(mid 72.389873 -430.62906)
					(end 71.87946 -431.1396)
				)
				(arc
					(start 71.87946 -431.9524)
					(mid 72.39 -432.46294)
					(end 72.90054 -431.9524)
				)
			)
		)
		(polygon
			(pts
				(arc
					(start 25.88514 -430.451006)
					(mid 25.272873 -429.83912)
					(end 24.66086 -430.45126)
				)
				(arc
					(start 24.66086 -431.56886)
					(mid 25.273 -432.181)
					(end 25.88514 -431.56886)
				)
			)
		)
		(polygon
			(pts
				(arc
					(start 75.0824 -430.63414)
					(mid 75.59294 -430.1236)
					(end 75.0824 -429.61306)
				)
				(arc
					(start 74.269346 -429.61306)
					(mid 73.75906 -430.123727)
					(end 74.2696 -430.63414)
				)
			)
		)
		(polygon
			(pts
				(arc
					(start 5.59054 -429.534828)
					(mid 5.079873 -429.024542)
					(end 4.56946 -429.535082)
				)
				(arc
					(start 4.56946 -430.347882)
					(mid 5.08 -430.858422)
					(end 5.59054 -430.347882)
				)
			)
		)
		(polygon
			(pts
				(arc
					(start 27.18054 -428.20336)
					(mid 26.669873 -427.693074)
					(end 26.15946 -428.203614)
				)
				(arc
					(start 26.15946 -429.016414)
					(mid 26.67 -429.526954)
					(end 27.18054 -429.016414)
				)
			)
		)
		(polygon
			(pts
				(arc
					(start 7.502906 -427.983904)
					(mid 6.992239 -427.473618)
					(end 6.481826 -427.984158)
				)
				(arc
					(start 6.481826 -428.796958)
					(mid 6.992366 -429.307498)
					(end 7.502906 -428.796958)
				)
			)
		)
		(polygon
			(pts
				(arc
					(start 5.59054 -426.334936)
					(mid 5.079873 -425.82465)
					(end 4.56946 -426.33519)
				)
				(arc
					(start 4.56946 -427.14799)
					(mid 5.08 -427.65853)
					(end 5.59054 -427.14799)
				)
			)
		)
		(polygon
			(pts
				(arc
					(start 25.88514 -425.650914)
					(mid 25.272873 -425.039028)
					(end 24.66086 -425.651168)
				)
				(arc
					(start 24.66086 -426.768768)
					(mid 25.273 -427.380908)
					(end 25.88514 -426.768768)
				)
			)
		)
		(polygon
			(pts
				(arc
					(start 7.502906 -424.784012)
					(mid 6.992239 -424.273726)
					(end 6.481826 -424.784266)
				)
				(arc
					(start 6.481826 -425.597066)
					(mid 6.992366 -426.107606)
					(end 7.502906 -425.597066)
				)
			)
		)
		(polygon
			(pts
				(arc
					(start 7.502906 -415.135568)
					(mid 6.992239 -414.625282)
					(end 6.481826 -415.135822)
				)
				(arc
					(start 6.481826 -415.948622)
					(mid 6.992366 -416.459162)
					(end 7.502906 -415.948622)
				)
			)
		)
		(polygon
			(pts
				(arc
					(start 5.59054 -413.535114)
					(mid 5.08 -413.024574)
					(end 4.56946 -413.535114)
				)
				(arc
					(start 4.56946 -414.348168)
					(mid 5.080127 -414.858454)
					(end 5.59054 -414.347914)
				)
			)
		)
		(polygon
			(pts
				(arc
					(start 7.502906 -411.935676)
					(mid 6.992366 -411.425136)
					(end 6.481826 -411.935676)
				)
				(arc
					(start 6.481826 -412.74873)
					(mid 6.992493 -413.259016)
					(end 7.502906 -412.748476)
				)
			)
		)
		(polygon
			(pts
				(arc
					(start 5.59054 -410.335222)
					(mid 5.08 -409.824682)
					(end 4.56946 -410.335222)
				)
				(arc
					(start 4.56946 -411.148276)
					(mid 5.080127 -411.658562)
					(end 5.59054 -411.148022)
				)
			)
		)
		(polygon
			(pts
				(arc
					(start 7.502906 -408.735784)
					(mid 6.992366 -408.225244)
					(end 6.481826 -408.735784)
				)
				(arc
					(start 6.481826 -409.548838)
					(mid 6.992493 -410.059124)
					(end 7.502906 -409.548584)
				)
			)
		)
		(polygon
			(pts
				(arc
					(start 5.59054 -407.135076)
					(mid 5.08 -406.624536)
					(end 4.56946 -407.135076)
				)
				(arc
					(start 4.56946 -407.94813)
					(mid 5.080127 -408.458416)
					(end 5.59054 -407.947876)
				)
			)
		)
		(polygon
			(pts
				(arc
					(start 7.502906 -405.535638)
					(mid 6.992366 -405.025098)
					(end 6.481826 -405.535638)
				)
				(arc
					(start 6.481826 -406.348692)
					(mid 6.992493 -406.858978)
					(end 7.502906 -406.348438)
				)
			)
		)
		(polygon
			(pts
				(arc
					(start 5.59054 -403.935184)
					(mid 5.08 -403.424644)
					(end 4.56946 -403.935184)
				)
				(arc
					(start 4.56946 -404.748238)
					(mid 5.080127 -405.258524)
					(end 5.59054 -404.747984)
				)
			)
		)
		(polygon
			(pts
				(arc
					(start 7.502906 -402.335746)
					(mid 6.992366 -401.825206)
					(end 6.481826 -402.335746)
				)
				(arc
					(start 6.481826 -403.1488)
					(mid 6.992493 -403.659086)
					(end 7.502906 -403.148546)
				)
			)
		)
		(polygon
			(pts
				(arc
					(start 5.59054 -398.334992)
					(mid 5.079873 -397.824706)
					(end 4.56946 -398.335246)
				)
				(arc
					(start 4.56946 -399.148046)
					(mid 5.08 -399.658586)
					(end 5.59054 -399.148046)
				)
			)
		)
		(polygon
			(pts
				(arc
					(start 7.502906 -396.735554)
					(mid 6.992239 -396.225268)
					(end 6.481826 -396.735808)
				)
				(arc
					(start 6.481826 -397.548608)
					(mid 6.992366 -398.059148)
					(end 7.502906 -397.548608)
				)
			)
		)
		(polygon
			(pts
				(arc
					(start 5.59054 -395.134846)
					(mid 5.079873 -394.62456)
					(end 4.56946 -395.1351)
				)
				(arc
					(start 4.56946 -395.9479)
					(mid 5.08 -396.45844)
					(end 5.59054 -395.9479)
				)
			)
		)
		(polygon
			(pts
				(arc
					(start 7.502906 -393.535408)
					(mid 6.992239 -393.025122)
					(end 6.481826 -393.535662)
				)
				(arc
					(start 6.481826 -394.348462)
					(mid 6.992366 -394.859002)
					(end 7.502906 -394.348462)
				)
			)
		)
		(polygon
			(pts
				(arc
					(start 5.59054 -391.934954)
					(mid 5.079873 -391.424668)
					(end 4.56946 -391.935208)
				)
				(arc
					(start 4.56946 -392.748008)
					(mid 5.08 -393.258548)
					(end 5.59054 -392.748008)
				)
			)
		)
		(polygon
			(pts
				(arc
					(start 7.502906 -390.335516)
					(mid 6.992239 -389.82523)
					(end 6.481826 -390.33577)
				)
				(arc
					(start 6.481826 -391.14857)
					(mid 6.992366 -391.65911)
					(end 7.502906 -391.14857)
				)
			)
		)
		(polygon
			(pts
				(arc
					(start 5.59054 -388.735062)
					(mid 5.079873 -388.224776)
					(end 4.56946 -388.735316)
				)
				(arc
					(start 4.56946 -389.548116)
					(mid 5.08 -390.058656)
					(end 5.59054 -389.548116)
				)
			)
		)
		(polygon
			(pts
				(arc
					(start 222.339154 -388.231126)
					(mid 221.726887 -387.61924)
					(end 221.114874 -388.23138)
				)
				(arc
					(start 221.114874 -389.34898)
					(mid 221.727014 -389.96112)
					(end 222.339154 -389.34898)
				)
			)
		)
		(polygon
			(pts
				(arc
					(start 37.33927 -388.231126)
					(mid 36.727003 -387.61924)
					(end 36.11499 -388.23138)
				)
				(arc
					(start 36.11499 -389.34898)
					(mid 36.72713 -389.96112)
					(end 37.33927 -389.34898)
				)
			)
		)
		(polygon
			(pts
				(arc
					(start 7.502906 -387.13537)
					(mid 6.992239 -386.625084)
					(end 6.481826 -387.135624)
				)
				(arc
					(start 6.481826 -387.948424)
					(mid 6.992366 -388.458964)
					(end 7.502906 -387.948424)
				)
			)
		)
		(polygon
			(pts
				(arc
					(start 220.840554 -385.98348)
					(mid 220.329887 -385.473194)
					(end 219.819474 -385.983734)
				)
				(arc
					(start 219.819474 -386.796534)
					(mid 220.330014 -387.307074)
					(end 220.840554 -386.796534)
				)
			)
		)
		(polygon
			(pts
				(arc
					(start 35.84067 -385.98348)
					(mid 35.330003 -385.473194)
					(end 34.81959 -385.983734)
				)
				(arc
					(start 34.81959 -386.796534)
					(mid 35.33013 -387.307074)
					(end 35.84067 -386.796534)
				)
			)
		)
		(polygon
			(pts
				(arc
					(start 9.195308 -386.113782)
					(mid 9.705594 -385.603115)
					(end 9.195054 -385.092702)
				)
				(arc
					(start 8.382254 -385.092702)
					(mid 7.871714 -385.603242)
					(end 8.382254 -386.113782)
				)
			)
		)
		(polygon
			(pts
				(arc
					(start 222.339154 -383.431034)
					(mid 221.726887 -382.819148)
					(end 221.114874 -383.431288)
				)
				(arc
					(start 221.114874 -384.548888)
					(mid 221.727014 -385.161028)
					(end 222.339154 -384.548888)
				)
			)
		)
		(polygon
			(pts
				(arc
					(start 37.33927 -383.431034)
					(mid 36.727003 -382.819148)
					(end 36.11499 -383.431288)
				)
				(arc
					(start 36.11499 -384.548888)
					(mid 36.72713 -385.161028)
					(end 37.33927 -384.548888)
				)
			)
		)
		(polygon
			(pts
				(arc
					(start 220.840554 -381.183388)
					(mid 220.329887 -380.673102)
					(end 219.819474 -381.183642)
				)
				(arc
					(start 219.819474 -381.996442)
					(mid 220.330014 -382.506982)
					(end 220.840554 -381.996442)
				)
			)
		)
		(polygon
			(pts
				(arc
					(start 35.84067 -381.183388)
					(mid 35.330003 -380.673102)
					(end 34.81959 -381.183642)
				)
				(arc
					(start 34.81959 -381.996442)
					(mid 35.33013 -382.506982)
					(end 35.84067 -381.996442)
				)
			)
		)
		(polygon
			(pts
				(arc
					(start 222.339154 -378.630942)
					(mid 221.726887 -378.019056)
					(end 221.114874 -378.631196)
				)
				(arc
					(start 221.114874 -379.748796)
					(mid 221.727014 -380.360936)
					(end 222.339154 -379.748796)
				)
			)
		)
		(polygon
			(pts
				(arc
					(start 37.33927 -378.630942)
					(mid 36.727003 -378.019056)
					(end 36.11499 -378.631196)
				)
				(arc
					(start 36.11499 -379.748796)
					(mid 36.72713 -380.360936)
					(end 37.33927 -379.748796)
				)
			)
		)
		(polygon
			(pts
				(arc
					(start 220.840554 -376.38355)
					(mid 220.329887 -375.873264)
					(end 219.819474 -376.383804)
				)
				(arc
					(start 219.819474 -377.196604)
					(mid 220.330014 -377.707144)
					(end 220.840554 -377.196604)
				)
			)
		)
		(polygon
			(pts
				(arc
					(start 35.84067 -376.38355)
					(mid 35.330003 -375.873264)
					(end 34.81959 -376.383804)
				)
				(arc
					(start 34.81959 -377.196604)
					(mid 35.33013 -377.707144)
					(end 35.84067 -377.196604)
				)
			)
		)
		(polygon
			(pts
				(arc
					(start 233.897424 -369.579398)
					(mid 233.386884 -369.068858)
					(end 232.876344 -369.579398)
				)
				(arc
					(start 232.876344 -370.392452)
					(mid 233.387011 -370.902738)
					(end 233.897424 -370.392198)
				)
			)
		)
		(polygon
			(pts
				(arc
					(start 48.89754 -369.579144)
					(mid 48.386873 -369.068858)
					(end 47.87646 -369.579398)
				)
				(arc
					(start 47.87646 -370.392198)
					(mid 48.387 -370.902738)
					(end 48.89754 -370.392198)
				)
			)
		)
		(polygon
			(pts
				(arc
					(start 230.720138 -369.30076)
					(mid 231.230424 -368.790093)
					(end 230.719884 -368.27968)
				)
				(arc
					(start 229.907084 -368.27968)
					(mid 229.396544 -368.79022)
					(end 229.907084 -369.30076)
				)
			)
		)
		(polygon
			(pts
				(arc
					(start 45.72 -369.30076)
					(mid 46.23054 -368.79022)
					(end 45.72 -368.27968)
				)
				(arc
					(start 44.906946 -368.27968)
					(mid 44.39666 -368.790347)
					(end 44.9072 -369.30076)
				)
			)
		)
		(polygon
			(pts
				(arc
					(start 222.339154 -365.83112)
					(mid 221.726887 -365.219234)
					(end 221.114874 -365.831374)
				)
				(arc
					(start 221.114874 -366.948974)
					(mid 221.727014 -367.561114)
					(end 222.339154 -366.948974)
				)
			)
		)
		(polygon
			(pts
				(arc
					(start 37.33927 -365.83112)
					(mid 36.727003 -365.219234)
					(end 36.11499 -365.831374)
				)
				(arc
					(start 36.11499 -366.948974)
					(mid 36.72713 -367.561114)
					(end 37.33927 -366.948974)
				)
			)
		)
		(polygon
			(pts
				(arc
					(start 220.840554 -363.583474)
					(mid 220.329887 -363.073188)
					(end 219.819474 -363.583728)
				)
				(arc
					(start 219.819474 -364.396528)
					(mid 220.330014 -364.907068)
					(end 220.840554 -364.396528)
				)
			)
		)
		(polygon
			(pts
				(arc
					(start 35.84067 -363.583474)
					(mid 35.330003 -363.073188)
					(end 34.81959 -363.583728)
				)
				(arc
					(start 34.81959 -364.396528)
					(mid 35.33013 -364.907068)
					(end 35.84067 -364.396528)
				)
			)
		)
		(polygon
			(pts
				(arc
					(start 5.59054 -357.935276)
					(mid 5.079873 -357.42499)
					(end 4.56946 -357.93553)
				)
				(arc
					(start 4.56946 -358.74833)
					(mid 5.08 -359.25887)
					(end 5.59054 -358.74833)
				)
			)
		)
		(polygon
			(pts
				(arc
					(start 7.502906 -356.335838)
					(mid 6.992366 -355.825298)
					(end 6.481826 -356.335838)
				)
				(arc
					(start 6.481826 -357.148892)
					(mid 6.992493 -357.659178)
					(end 7.502906 -357.148638)
				)
			)
		)
		(polygon
			(pts
				(arc
					(start 5.59054 -354.73513)
					(mid 5.079873 -354.224844)
					(end 4.56946 -354.735384)
				)
				(arc
					(start 4.56946 -355.548184)
					(mid 5.08 -356.058724)
					(end 5.59054 -355.548184)
				)
			)
		)
		(polygon
			(pts
				(arc
					(start 7.502906 -353.135692)
					(mid 6.992239 -352.625406)
					(end 6.481826 -353.135946)
				)
				(arc
					(start 6.481826 -353.948746)
					(mid 6.992366 -354.459286)
					(end 7.502906 -353.948746)
				)
			)
		)
		(polygon
			(pts
				(arc
					(start 5.59054 -351.535238)
					(mid 5.079873 -351.024952)
					(end 4.56946 -351.535492)
				)
				(arc
					(start 4.56946 -352.348292)
					(mid 5.08 -352.858832)
					(end 5.59054 -352.348292)
				)
			)
		)
		(polygon
			(pts
				(arc
					(start 7.502906 -349.9358)
					(mid 6.992366 -349.42526)
					(end 6.481826 -349.9358)
				)
				(arc
					(start 6.481826 -350.748854)
					(mid 6.992493 -351.25914)
					(end 7.502906 -350.7486)
				)
			)
		)
		(polygon
			(pts
				(arc
					(start 5.59054 -348.335092)
					(mid 5.079873 -347.824806)
					(end 4.56946 -348.335346)
				)
				(arc
					(start 4.56946 -349.148146)
					(mid 5.08 -349.658686)
					(end 5.59054 -349.148146)
				)
			)
		)
		(polygon
			(pts
				(arc
					(start 27.18054 -347.603572)
					(mid 26.67 -347.093032)
					(end 26.15946 -347.603572)
				)
				(arc
					(start 26.15946 -348.416626)
					(mid 26.670127 -348.926912)
					(end 27.18054 -348.416372)
				)
			)
		)
		(polygon
			(pts
				(arc
					(start 7.502906 -346.735908)
					(mid 6.992366 -346.225368)
					(end 6.481826 -346.735908)
				)
				(arc
					(start 6.481826 -347.548962)
					(mid 6.992493 -348.059248)
					(end 7.502906 -347.548708)
				)
			)
		)
		(polygon
			(pts
				(arc
					(start 5.59054 -345.1352)
					(mid 5.079873 -344.624914)
					(end 4.56946 -345.135454)
				)
				(arc
					(start 4.56946 -345.948254)
					(mid 5.08 -346.458794)
					(end 5.59054 -345.948254)
				)
			)
		)
		(polygon
			(pts
				(arc
					(start 25.88514 -345.050872)
					(mid 25.272873 -344.438986)
					(end 24.66086 -345.051126)
				)
				(arc
					(start 24.66086 -346.168726)
					(mid 25.273 -346.780866)
					(end 25.88514 -346.168726)
				)
			)
		)
		(polygon
			(pts
				(arc
					(start 7.502906 -343.586562)
					(mid 6.992239 -343.076276)
					(end 6.481826 -343.586816)
				)
				(arc
					(start 6.481826 -344.399616)
					(mid 6.992366 -344.910156)
					(end 7.502906 -344.399616)
				)
			)
		)
		(polygon
			(pts
				(arc
					(start 5.59054 -341.935054)
					(mid 5.079873 -341.424768)
					(end 4.56946 -341.935308)
				)
				(arc
					(start 4.56946 -342.748108)
					(mid 5.08 -343.258648)
					(end 5.59054 -342.748108)
				)
			)
		)
		(polygon
			(pts
				(arc
					(start 17.78254 -341.60333)
					(mid 17.272 -341.09279)
					(end 16.76146 -341.60333)
				)
				(arc
					(start 16.76146 -342.416384)
					(mid 17.272127 -342.92667)
					(end 17.78254 -342.41613)
				)
			)
		)
		(polygon
			(pts
				(arc
					(start 33.40354 -341.58428)
					(mid 32.892873 -341.073994)
					(end 32.38246 -341.584534)
				)
				(arc
					(start 32.38246 -342.397334)
					(mid 32.893 -342.907874)
					(end 33.40354 -342.397334)
				)
			)
		)
		(polygon
			(pts
				(arc
					(start 7.502906 -340.386416)
					(mid 6.992239 -339.87613)
					(end 6.481826 -340.38667)
				)
				(arc
					(start 6.481826 -341.19947)
					(mid 6.992366 -341.71001)
					(end 7.502906 -341.19947)
				)
			)
		)
		(polygon
			(pts
				(arc
					(start 5.59054 -338.735162)
					(mid 5.079873 -338.224876)
					(end 4.56946 -338.735416)
				)
				(arc
					(start 4.56946 -339.548216)
					(mid 5.08 -340.058756)
					(end 5.59054 -339.548216)
				)
			)
		)
		(polygon
			(pts
				(arc
					(start 7.502906 -337.186524)
					(mid 6.992239 -336.676238)
					(end 6.481826 -337.186778)
				)
				(arc
					(start 6.481826 -337.999578)
					(mid 6.992366 -338.510118)
					(end 7.502906 -337.999578)
				)
			)
		)
		(polygon
			(pts
				(arc
					(start 5.59054 -335.53527)
					(mid 5.079873 -335.024984)
					(end 4.56946 -335.535524)
				)
				(arc
					(start 4.56946 -336.348324)
					(mid 5.08 -336.858864)
					(end 5.59054 -336.348324)
				)
			)
		)
		(polygon
			(pts
				(arc
					(start 27.18054 -334.803496)
					(mid 26.67 -334.292956)
					(end 26.15946 -334.803496)
				)
				(arc
					(start 26.15946 -335.61655)
					(mid 26.670127 -336.126836)
					(end 27.18054 -335.616296)
				)
			)
		)
		(polygon
			(pts
				(arc
					(start 7.502906 -333.986378)
					(mid 6.992239 -333.476092)
					(end 6.481826 -333.986632)
				)
				(arc
					(start 6.481826 -334.799432)
					(mid 6.992366 -335.309972)
					(end 7.502906 -334.799432)
				)
			)
		)
		(polygon
			(pts
				(arc
					(start 25.88514 -332.251304)
					(mid 25.273 -331.639164)
					(end 24.66086 -332.251304)
				)
				(arc
					(start 24.66086 -333.369158)
					(mid 25.273127 -333.981044)
					(end 25.88514 -333.368904)
				)
			)
		)
		(polygon
			(pts
				(arc
					(start 27.18054 -330.003658)
					(mid 26.67 -329.493118)
					(end 26.15946 -330.003658)
				)
				(arc
					(start 26.15946 -330.816712)
					(mid 26.670127 -331.326998)
					(end 27.18054 -330.816458)
				)
			)
		)
		(polygon
			(pts
				(arc
					(start 5.59054 -329.935078)
					(mid 5.079873 -329.424792)
					(end 4.56946 -329.935332)
				)
				(arc
					(start 4.56946 -330.748132)
					(mid 5.08 -331.258672)
					(end 5.59054 -330.748132)
				)
			)
		)
		(polygon
			(pts
				(arc
					(start 7.502906 -328.335894)
					(mid 6.992366 -327.825354)
					(end 6.481826 -328.335894)
				)
				(arc
					(start 6.481826 -329.148948)
					(mid 6.992493 -329.659234)
					(end 7.502906 -329.148694)
				)
			)
		)
		(polygon
			(pts
				(arc
					(start 25.88514 -327.451212)
					(mid 25.273 -326.839072)
					(end 24.66086 -327.451212)
				)
				(arc
					(start 24.66086 -328.569066)
					(mid 25.273127 -329.180952)
					(end 25.88514 -328.568812)
				)
			)
		)
		(polygon
			(pts
				(arc
					(start 5.59054 -326.735186)
					(mid 5.079873 -326.2249)
					(end 4.56946 -326.73544)
				)
				(arc
					(start 4.56946 -327.54824)
					(mid 5.08 -328.05878)
					(end 5.59054 -327.54824)
				)
			)
		)
		(polygon
			(pts
				(arc
					(start 27.18054 -325.203566)
					(mid 26.67 -324.693026)
					(end 26.15946 -325.203566)
				)
				(arc
					(start 26.15946 -326.01662)
					(mid 26.670127 -326.526906)
					(end 27.18054 -326.016366)
				)
			)
		)
		(polygon
			(pts
				(arc
					(start 7.502906 -325.136002)
					(mid 6.992366 -324.625462)
					(end 6.481826 -325.136002)
				)
				(arc
					(start 6.481826 -325.949056)
					(mid 6.992493 -326.459342)
					(end 7.502906 -325.948802)
				)
			)
		)
		(polygon
			(pts
				(arc
					(start 5.59054 -323.53504)
					(mid 5.079873 -323.024754)
					(end 4.56946 -323.535294)
				)
				(arc
					(start 4.56946 -324.348094)
					(mid 5.08 -324.858634)
					(end 5.59054 -324.348094)
				)
			)
		)
		(polygon
			(pts
				(arc
					(start 25.88514 -322.65112)
					(mid 25.273 -322.03898)
					(end 24.66086 -322.65112)
				)
				(arc
					(start 24.66086 -323.768974)
					(mid 25.273127 -324.38086)
					(end 25.88514 -323.76872)
				)
			)
		)
		(polygon
			(pts
				(arc
					(start 7.502906 -321.935856)
					(mid 6.992366 -321.425316)
					(end 6.481826 -321.935856)
				)
				(arc
					(start 6.481826 -322.74891)
					(mid 6.992493 -323.259196)
					(end 7.502906 -322.748656)
				)
			)
		)
		(polygon
			(pts
				(arc
					(start 5.59054 -320.335148)
					(mid 5.079873 -319.824862)
					(end 4.56946 -320.335402)
				)
				(arc
					(start 4.56946 -321.148202)
					(mid 5.08 -321.658742)
					(end 5.59054 -321.148202)
				)
			)
		)
		(polygon
			(pts
				(arc
					(start 7.502906 -318.735964)
					(mid 6.992366 -318.225424)
					(end 6.481826 -318.735964)
				)
				(arc
					(start 6.481826 -319.549018)
					(mid 6.992493 -320.059304)
					(end 7.502906 -319.548764)
				)
			)
		)
		(polygon
			(pts
				(arc
					(start 7.502906 -310.73598)
					(mid 6.992366 -310.22544)
					(end 6.481826 -310.73598)
				)
				(arc
					(start 6.481826 -311.549034)
					(mid 6.992493 -312.05932)
					(end 7.502906 -311.54878)
				)
			)
		)
		(polygon
			(pts
				(arc
					(start 5.59054 -309.135272)
					(mid 5.079873 -308.624986)
					(end 4.56946 -309.135526)
				)
				(arc
					(start 4.56946 -309.948326)
					(mid 5.08 -310.458866)
					(end 5.59054 -309.948326)
				)
			)
		)
		(polygon
			(pts
				(arc
					(start 7.502906 -307.535834)
					(mid 6.992366 -307.025294)
					(end 6.481826 -307.535834)
				)
				(arc
					(start 6.481826 -308.348888)
					(mid 6.992493 -308.859174)
					(end 7.502906 -308.348634)
				)
			)
		)
		(polygon
			(pts
				(arc
					(start 5.59054 -305.935126)
					(mid 5.079873 -305.42484)
					(end 4.56946 -305.93538)
				)
				(arc
					(start 4.56946 -306.74818)
					(mid 5.08 -307.25872)
					(end 5.59054 -306.74818)
				)
			)
		)
		(polygon
			(pts
				(arc
					(start 7.502906 -304.335942)
					(mid 6.992366 -303.825402)
					(end 6.481826 -304.335942)
				)
				(arc
					(start 6.481826 -305.148996)
					(mid 6.992493 -305.659282)
					(end 7.502906 -305.148742)
				)
			)
		)
		(polygon
			(pts
				(arc
					(start 5.59054 -302.735234)
					(mid 5.079873 -302.224948)
					(end 4.56946 -302.735488)
				)
				(arc
					(start 4.56946 -303.548288)
					(mid 5.08 -304.058828)
					(end 5.59054 -303.548288)
				)
			)
		)
		(polygon
			(pts
				(arc
					(start 7.502906 -301.135796)
					(mid 6.992366 -300.625256)
					(end 6.481826 -301.135796)
				)
				(arc
					(start 6.481826 -301.94885)
					(mid 6.992493 -302.459136)
					(end 7.502906 -301.948596)
				)
			)
		)
		(polygon
			(pts
				(arc
					(start 5.59054 -299.535088)
					(mid 5.079873 -299.024802)
					(end 4.56946 -299.535342)
				)
				(arc
					(start 4.56946 -300.348142)
					(mid 5.08 -300.858682)
					(end 5.59054 -300.348142)
				)
			)
		)
		(polygon
			(pts
				(arc
					(start 7.502906 -297.935904)
					(mid 6.992366 -297.425364)
					(end 6.481826 -297.935904)
				)
				(arc
					(start 6.481826 -298.748958)
					(mid 6.992493 -299.259244)
					(end 7.502906 -298.748704)
				)
			)
		)
		(polygon
			(pts
				(arc
					(start 5.59054 -296.335196)
					(mid 5.079873 -295.82491)
					(end 4.56946 -296.33545)
				)
				(arc
					(start 4.56946 -297.14825)
					(mid 5.08 -297.65879)
					(end 5.59054 -297.14825)
				)
			)
		)
		(polygon
			(pts
				(arc
					(start 7.502906 -294.736012)
					(mid 6.992366 -294.225472)
					(end 6.481826 -294.736012)
				)
				(arc
					(start 6.481826 -295.549066)
					(mid 6.992493 -296.059352)
					(end 7.502906 -295.548812)
				)
			)
		)
		(polygon
			(pts
				(arc
					(start 5.59054 -293.13505)
					(mid 5.079873 -292.624764)
					(end 4.56946 -293.135304)
				)
				(arc
					(start 4.56946 -293.948104)
					(mid 5.08 -294.458644)
					(end 5.59054 -293.948104)
				)
			)
		)
		(polygon
			(pts
				(arc
					(start 7.502906 -291.535866)
					(mid 6.992366 -291.025326)
					(end 6.481826 -291.535866)
				)
				(arc
					(start 6.481826 -292.34892)
					(mid 6.992493 -292.859206)
					(end 7.502906 -292.348666)
				)
			)
		)
		(polygon
			(pts
				(arc
					(start 5.59054 -289.935158)
					(mid 5.079873 -289.424872)
					(end 4.56946 -289.935412)
				)
				(arc
					(start 4.56946 -290.748212)
					(mid 5.08 -291.258752)
					(end 5.59054 -290.748212)
				)
			)
		)
		(polygon
			(pts
				(arc
					(start 7.502906 -288.33572)
					(mid 6.992239 -287.825434)
					(end 6.481826 -288.335974)
				)
				(arc
					(start 6.481826 -289.148774)
					(mid 6.992366 -289.659314)
					(end 7.502906 -289.148774)
				)
			)
		)
		(polygon
			(pts
				(arc
					(start 222.339154 -285.231078)
					(mid 221.726887 -284.619192)
					(end 221.114874 -285.231332)
				)
				(arc
					(start 221.114874 -286.348932)
					(mid 221.727014 -286.961072)
					(end 222.339154 -286.348932)
				)
			)
		)
		(polygon
			(pts
				(arc
					(start 37.33927 -285.231078)
					(mid 36.727003 -284.619192)
					(end 36.11499 -285.231332)
				)
				(arc
					(start 36.11499 -286.348932)
					(mid 36.72713 -286.961072)
					(end 37.33927 -286.348932)
				)
			)
		)
		(polygon
			(pts
				(arc
					(start 5.59054 -283.53512)
					(mid 5.079873 -283.024834)
					(end 4.56946 -283.535374)
				)
				(arc
					(start 4.56946 -284.348174)
					(mid 5.08 -284.858714)
					(end 5.59054 -284.348174)
				)
			)
		)
		(polygon
			(pts
				(arc
					(start 220.840554 -282.983432)
					(mid 220.329887 -282.473146)
					(end 219.819474 -282.983686)
				)
				(arc
					(start 219.819474 -283.796486)
					(mid 220.330014 -284.307026)
					(end 220.840554 -283.796486)
				)
			)
		)
		(polygon
			(pts
				(arc
					(start 35.84067 -282.983432)
					(mid 35.330003 -282.473146)
					(end 34.81959 -282.983686)
				)
				(arc
					(start 34.81959 -283.796486)
					(mid 35.33013 -284.307026)
					(end 35.84067 -283.796486)
				)
			)
		)
		(polygon
			(pts
				(arc
					(start 7.502906 -281.986482)
					(mid 6.992239 -281.476196)
					(end 6.481826 -281.986736)
				)
				(arc
					(start 6.481826 -282.799536)
					(mid 6.992366 -283.310076)
					(end 7.502906 -282.799536)
				)
			)
		)
		(polygon
			(pts
				(arc
					(start 5.59054 -280.335228)
					(mid 5.079873 -279.824942)
					(end 4.56946 -280.335482)
				)
				(arc
					(start 4.56946 -281.148282)
					(mid 5.08 -281.658822)
					(end 5.59054 -281.148282)
				)
			)
		)
		(polygon
			(pts
				(arc
					(start 222.339154 -280.430986)
					(mid 221.726887 -279.8191)
					(end 221.114874 -280.43124)
				)
				(arc
					(start 221.114874 -281.54884)
					(mid 221.727014 -282.16098)
					(end 222.339154 -281.54884)
				)
			)
		)
		(polygon
			(pts
				(arc
					(start 37.33927 -280.430986)
					(mid 36.727003 -279.8191)
					(end 36.11499 -280.43124)
				)
				(arc
					(start 36.11499 -281.54884)
					(mid 36.72713 -282.16098)
					(end 37.33927 -281.54884)
				)
			)
		)
		(polygon
			(pts
				(arc
					(start 7.502906 -278.786336)
					(mid 6.992239 -278.27605)
					(end 6.481826 -278.78659)
				)
				(arc
					(start 6.481826 -279.59939)
					(mid 6.992366 -280.10993)
					(end 7.502906 -279.59939)
				)
			)
		)
		(polygon
			(pts
				(arc
					(start 220.840554 -278.18334)
					(mid 220.329887 -277.673054)
					(end 219.819474 -278.183594)
				)
				(arc
					(start 219.819474 -278.996394)
					(mid 220.330014 -279.506934)
					(end 220.840554 -278.996394)
				)
			)
		)
		(polygon
			(pts
				(arc
					(start 35.84067 -278.18334)
					(mid 35.330003 -277.673054)
					(end 34.81959 -278.183594)
				)
				(arc
					(start 34.81959 -278.996394)
					(mid 35.33013 -279.506934)
					(end 35.84067 -278.996394)
				)
			)
		)
		(polygon
			(pts
				(arc
					(start 222.339154 -275.630894)
					(mid 221.726887 -275.019008)
					(end 221.114874 -275.631148)
				)
				(arc
					(start 221.114874 -276.748748)
					(mid 221.727014 -277.360888)
					(end 222.339154 -276.748748)
				)
			)
		)
		(polygon
			(pts
				(arc
					(start 37.33927 -275.630894)
					(mid 36.727003 -275.019008)
					(end 36.11499 -275.631148)
				)
				(arc
					(start 36.11499 -276.748748)
					(mid 36.72713 -277.360888)
					(end 37.33927 -276.748748)
				)
			)
		)
		(polygon
			(pts
				(arc
					(start 220.840554 -273.383502)
					(mid 220.329887 -272.873216)
					(end 219.819474 -273.383756)
				)
				(arc
					(start 219.819474 -274.196556)
					(mid 220.330014 -274.707096)
					(end 220.840554 -274.196556)
				)
			)
		)
		(polygon
			(pts
				(arc
					(start 35.84067 -273.383502)
					(mid 35.330003 -272.873216)
					(end 34.81959 -273.383756)
				)
				(arc
					(start 34.81959 -274.196556)
					(mid 35.33013 -274.707096)
					(end 35.84067 -274.196556)
				)
			)
		)
		(polygon
			(pts
				(arc
					(start 233.897424 -266.57935)
					(mid 233.386884 -266.06881)
					(end 232.876344 -266.57935)
				)
				(arc
					(start 232.876344 -267.392404)
					(mid 233.387011 -267.90269)
					(end 233.897424 -267.39215)
				)
			)
		)
		(polygon
			(pts
				(arc
					(start 48.89754 -266.579096)
					(mid 48.386873 -266.06881)
					(end 47.87646 -266.57935)
				)
				(arc
					(start 47.87646 -267.39215)
					(mid 48.387 -267.90269)
					(end 48.89754 -267.39215)
				)
			)
		)
		(polygon
			(pts
				(arc
					(start 230.720138 -266.300712)
					(mid 231.230424 -265.790045)
					(end 230.719884 -265.279632)
				)
				(arc
					(start 229.907084 -265.279632)
					(mid 229.396544 -265.790172)
					(end 229.907084 -266.300712)
				)
			)
		)
		(polygon
			(pts
				(arc
					(start 45.72 -266.300712)
					(mid 46.23054 -265.790172)
					(end 45.72 -265.279632)
				)
				(arc
					(start 44.906946 -265.279632)
					(mid 44.39666 -265.790299)
					(end 44.9072 -266.300712)
				)
			)
		)
		(polygon
			(pts
				(arc
					(start 222.339154 -262.831072)
					(mid 221.726887 -262.219186)
					(end 221.114874 -262.831326)
				)
				(arc
					(start 221.114874 -263.948926)
					(mid 221.727014 -264.561066)
					(end 222.339154 -263.948926)
				)
			)
		)
		(polygon
			(pts
				(arc
					(start 37.33927 -262.831072)
					(mid 36.727003 -262.219186)
					(end 36.11499 -262.831326)
				)
				(arc
					(start 36.11499 -263.948926)
					(mid 36.72713 -264.561066)
					(end 37.33927 -263.948926)
				)
			)
		)
		(polygon
			(pts
				(arc
					(start 220.840554 -260.583426)
					(mid 220.329887 -260.07314)
					(end 219.819474 -260.58368)
				)
				(arc
					(start 219.819474 -261.39648)
					(mid 220.330014 -261.90702)
					(end 220.840554 -261.39648)
				)
			)
		)
		(polygon
			(pts
				(arc
					(start 35.84067 -260.583426)
					(mid 35.330003 -260.07314)
					(end 34.81959 -260.58368)
				)
				(arc
					(start 34.81959 -261.39648)
					(mid 35.33013 -261.90702)
					(end 35.84067 -261.39648)
				)
			)
		)
		(polygon
			(pts
				(arc
					(start 27.18054 -244.603524)
					(mid 26.67 -244.092984)
					(end 26.15946 -244.603524)
				)
				(arc
					(start 26.15946 -245.416578)
					(mid 26.670127 -245.926864)
					(end 27.18054 -245.416324)
				)
			)
		)
		(polygon
			(pts
				(arc
					(start 25.88514 -242.051078)
					(mid 25.273 -241.438938)
					(end 24.66086 -242.051078)
				)
				(arc
					(start 24.66086 -243.168932)
					(mid 25.273127 -243.780818)
					(end 25.88514 -243.168678)
				)
			)
		)
		(polygon
			(pts
				(arc
					(start 17.78254 -238.603282)
					(mid 17.272 -238.092742)
					(end 16.76146 -238.603282)
				)
				(arc
					(start 16.76146 -239.416336)
					(mid 17.272127 -239.926622)
					(end 17.78254 -239.416082)
				)
			)
		)
		(polygon
			(pts
				(arc
					(start 42.92854 -238.584232)
					(mid 42.417873 -238.073946)
					(end 41.90746 -238.584486)
				)
				(arc
					(start 41.90746 -239.397286)
					(mid 42.418 -239.907826)
					(end 42.92854 -239.397286)
				)
			)
		)
		(polygon
			(pts
				(arc
					(start 5.59054 -231.935274)
					(mid 5.079873 -231.424988)
					(end 4.56946 -231.935528)
				)
				(arc
					(start 4.56946 -232.748328)
					(mid 5.08 -233.258868)
					(end 5.59054 -232.748328)
				)
			)
		)
		(polygon
			(pts
				(arc
					(start 27.18054 -231.803448)
					(mid 26.67 -231.292908)
					(end 26.15946 -231.803448)
				)
				(arc
					(start 26.15946 -232.616502)
					(mid 26.670127 -233.126788)
					(end 27.18054 -232.616248)
				)
			)
		)
		(polygon
			(pts
				(arc
					(start 7.502906 -230.335582)
					(mid 6.992239 -229.825296)
					(end 6.481826 -230.335836)
				)
				(arc
					(start 6.481826 -231.148636)
					(mid 6.992366 -231.659176)
					(end 7.502906 -231.148636)
				)
			)
		)
		(polygon
			(pts
				(arc
					(start 25.88514 -229.251256)
					(mid 25.273 -228.639116)
					(end 24.66086 -229.251256)
				)
				(arc
					(start 24.66086 -230.36911)
					(mid 25.273127 -230.980996)
					(end 25.88514 -230.368856)
				)
			)
		)
		(polygon
			(pts
				(arc
					(start 5.59054 -228.735128)
					(mid 5.079873 -228.224842)
					(end 4.56946 -228.735382)
				)
				(arc
					(start 4.56946 -229.548182)
					(mid 5.08 -230.058722)
					(end 5.59054 -229.548182)
				)
			)
		)
		(polygon
			(pts
				(arc
					(start 7.502906 -227.13569)
					(mid 6.992239 -226.625404)
					(end 6.481826 -227.135944)
				)
				(arc
					(start 6.481826 -227.948744)
					(mid 6.992366 -228.459284)
					(end 7.502906 -227.948744)
				)
			)
		)
		(polygon
			(pts
				(arc
					(start 27.18054 -227.00361)
					(mid 26.67 -226.49307)
					(end 26.15946 -227.00361)
				)
				(arc
					(start 26.15946 -227.816664)
					(mid 26.670127 -228.32695)
					(end 27.18054 -227.81641)
				)
			)
		)
		(polygon
			(pts
				(arc
					(start 25.88514 -224.451164)
					(mid 25.273 -223.839024)
					(end 24.66086 -224.451164)
				)
				(arc
					(start 24.66086 -225.569018)
					(mid 25.273127 -226.180904)
					(end 25.88514 -225.568764)
				)
			)
		)
		(polygon
			(pts
				(arc
					(start 7.502906 -223.897444)
					(mid 6.992239 -223.387158)
					(end 6.481826 -223.897698)
				)
				(arc
					(start 6.481826 -224.710498)
					(mid 6.992366 -225.221038)
					(end 7.502906 -224.710498)
				)
			)
		)
		(polygon
			(pts
				(arc
					(start 5.59054 -222.33509)
					(mid 5.079873 -221.824804)
					(end 4.56946 -222.335344)
				)
				(arc
					(start 4.56946 -223.148144)
					(mid 5.08 -223.658684)
					(end 5.59054 -223.148144)
				)
			)
		)
		(polygon
			(pts
				(arc
					(start 27.18054 -222.203518)
					(mid 26.67 -221.692978)
					(end 26.15946 -222.203518)
				)
				(arc
					(start 26.15946 -223.016572)
					(mid 26.670127 -223.526858)
					(end 27.18054 -223.016318)
				)
			)
		)
		(polygon
			(pts
				(arc
					(start 7.502906 -220.685106)
					(mid 6.992366 -220.174566)
					(end 6.481826 -220.685106)
				)
				(arc
					(start 6.481826 -221.49816)
					(mid 6.992493 -222.008446)
					(end 7.502906 -221.497906)
				)
			)
		)
		(polygon
			(pts
				(arc
					(start 25.88514 -219.650818)
					(mid 25.272873 -219.038932)
					(end 24.66086 -219.651072)
				)
				(arc
					(start 24.66086 -220.768672)
					(mid 25.273 -221.380812)
					(end 25.88514 -220.768672)
				)
			)
		)
		(polygon
			(pts
				(arc
					(start 5.59054 -219.135198)
					(mid 5.079873 -218.624912)
					(end 4.56946 -219.135452)
				)
				(arc
					(start 4.56946 -219.948252)
					(mid 5.08 -220.458792)
					(end 5.59054 -219.948252)
				)
			)
		)
		(polygon
			(pts
				(arc
					(start 7.502906 -217.48496)
					(mid 6.992239 -216.974674)
					(end 6.481826 -217.485214)
				)
				(arc
					(start 6.481826 -218.298014)
					(mid 6.992366 -218.808554)
					(end 7.502906 -218.298014)
				)
			)
		)
		(polygon
			(pts
				(arc
					(start 5.59054 -215.935052)
					(mid 5.079873 -215.424766)
					(end 4.56946 -215.935306)
				)
				(arc
					(start 4.56946 -216.748106)
					(mid 5.08 -217.258646)
					(end 5.59054 -216.748106)
				)
			)
		)
		(polygon
			(pts
				(arc
					(start 7.502906 -214.284814)
					(mid 6.992239 -213.774528)
					(end 6.481826 -214.285068)
				)
				(arc
					(start 6.481826 -215.097868)
					(mid 6.992366 -215.608408)
					(end 7.502906 -215.097868)
				)
			)
		)
		(polygon
			(pts
				(arc
					(start 5.59054 -212.73516)
					(mid 5.079873 -212.224874)
					(end 4.56946 -212.735414)
				)
				(arc
					(start 4.56946 -213.548214)
					(mid 5.08 -214.058754)
					(end 5.59054 -213.548214)
				)
			)
		)
		(polygon
			(pts
				(arc
					(start 7.502906 -211.135722)
					(mid 6.992239 -210.625436)
					(end 6.481826 -211.135976)
				)
				(arc
					(start 6.481826 -211.948776)
					(mid 6.992366 -212.459316)
					(end 7.502906 -211.948776)
				)
			)
		)
		(polygon
			(pts
				(arc
					(start 5.59054 -209.535268)
					(mid 5.079873 -209.024982)
					(end 4.56946 -209.535522)
				)
				(arc
					(start 4.56946 -210.348322)
					(mid 5.08 -210.858862)
					(end 5.59054 -210.348322)
				)
			)
		)
		(polygon
			(pts
				(arc
					(start 7.502906 -207.935576)
					(mid 6.992239 -207.42529)
					(end 6.481826 -207.93583)
				)
				(arc
					(start 6.481826 -208.74863)
					(mid 6.992366 -209.25917)
					(end 7.502906 -208.74863)
				)
			)
		)
		(polygon
			(pts
				(arc
					(start 5.59054 -206.335122)
					(mid 5.079873 -205.824836)
					(end 4.56946 -206.335376)
				)
				(arc
					(start 4.56946 -207.148176)
					(mid 5.08 -207.658716)
					(end 5.59054 -207.148176)
				)
			)
		)
		(polygon
			(pts
				(arc
					(start 7.502906 -204.735684)
					(mid 6.992239 -204.225398)
					(end 6.481826 -204.735938)
				)
				(arc
					(start 6.481826 -205.548738)
					(mid 6.992366 -206.059278)
					(end 7.502906 -205.548738)
				)
			)
		)
		(polygon
			(pts
				(arc
					(start 5.59054 -203.13523)
					(mid 5.079873 -202.624944)
					(end 4.56946 -203.135484)
				)
				(arc
					(start 4.56946 -203.948284)
					(mid 5.08 -204.458824)
					(end 5.59054 -203.948284)
				)
			)
		)
		(polygon
			(pts
				(arc
					(start 7.502906 -201.535538)
					(mid 6.992239 -201.025252)
					(end 6.481826 -201.535792)
				)
				(arc
					(start 6.481826 -202.348592)
					(mid 6.992366 -202.859132)
					(end 7.502906 -202.348592)
				)
			)
		)
		(polygon
			(pts
				(arc
					(start 5.59054 -199.935084)
					(mid 5.079873 -199.424798)
					(end 4.56946 -199.935338)
				)
				(arc
					(start 4.56946 -200.748138)
					(mid 5.08 -201.258678)
					(end 5.59054 -200.748138)
				)
			)
		)
		(polygon
			(pts
				(arc
					(start 7.502906 -195.9356)
					(mid 6.992239 -195.425314)
					(end 6.481826 -195.935854)
				)
				(arc
					(start 6.481826 -196.748654)
					(mid 6.992366 -197.259194)
					(end 7.502906 -196.748654)
				)
			)
		)
		(polygon
			(pts
				(arc
					(start 5.59054 -194.335146)
					(mid 5.079873 -193.82486)
					(end 4.56946 -194.3354)
				)
				(arc
					(start 4.56946 -195.1482)
					(mid 5.08 -195.65874)
					(end 5.59054 -195.1482)
				)
			)
		)
		(polygon
			(pts
				(arc
					(start 7.502906 -192.735708)
					(mid 6.992239 -192.225422)
					(end 6.481826 -192.735962)
				)
				(arc
					(start 6.481826 -193.548762)
					(mid 6.992366 -194.059302)
					(end 7.502906 -193.548762)
				)
			)
		)
		(polygon
			(pts
				(arc
					(start 7.502906 -184.735724)
					(mid 6.992239 -184.225438)
					(end 6.481826 -184.735978)
				)
				(arc
					(start 6.481826 -185.548778)
					(mid 6.992366 -186.059318)
					(end 7.502906 -185.548778)
				)
			)
		)
		(polygon
			(pts
				(arc
					(start 5.59054 -183.13527)
					(mid 5.079873 -182.624984)
					(end 4.56946 -183.135524)
				)
				(arc
					(start 4.56946 -183.948324)
					(mid 5.08 -184.458864)
					(end 5.59054 -183.948324)
				)
			)
		)
		(polygon
			(pts
				(arc
					(start 222.339154 -182.23103)
					(mid 221.726887 -181.619144)
					(end 221.114874 -182.231284)
				)
				(arc
					(start 221.114874 -183.348884)
					(mid 221.727014 -183.961024)
					(end 222.339154 -183.348884)
				)
			)
		)
		(polygon
			(pts
				(arc
					(start 37.33927 -182.23103)
					(mid 36.727003 -181.619144)
					(end 36.11499 -182.231284)
				)
				(arc
					(start 36.11499 -183.348884)
					(mid 36.72713 -183.961024)
					(end 37.33927 -183.348884)
				)
			)
		)
		(polygon
			(pts
				(arc
					(start 7.502906 -181.535578)
					(mid 6.992239 -181.025292)
					(end 6.481826 -181.535832)
				)
				(arc
					(start 6.481826 -182.348632)
					(mid 6.992366 -182.859172)
					(end 7.502906 -182.348632)
				)
			)
		)
		(polygon
			(pts
				(arc
					(start 220.840554 -179.983384)
					(mid 220.329887 -179.473098)
					(end 219.819474 -179.983638)
				)
				(arc
					(start 219.819474 -180.796438)
					(mid 220.330014 -181.306978)
					(end 220.840554 -180.796438)
				)
			)
		)
		(polygon
			(pts
				(arc
					(start 35.84067 -179.983384)
					(mid 35.330003 -179.473098)
					(end 34.81959 -179.983638)
				)
				(arc
					(start 34.81959 -180.796438)
					(mid 35.33013 -181.306978)
					(end 35.84067 -180.796438)
				)
			)
		)
		(polygon
			(pts
				(arc
					(start 5.59054 -179.935124)
					(mid 5.079873 -179.424838)
					(end 4.56946 -179.935378)
				)
				(arc
					(start 4.56946 -180.748178)
					(mid 5.08 -181.258718)
					(end 5.59054 -180.748178)
				)
			)
		)
		(polygon
			(pts
				(arc
					(start 7.502906 -178.386486)
					(mid 6.992239 -177.8762)
					(end 6.481826 -178.38674)
				)
				(arc
					(start 6.481826 -179.19954)
					(mid 6.992366 -179.71008)
					(end 7.502906 -179.19954)
				)
			)
		)
		(polygon
			(pts
				(arc
					(start 222.339154 -177.430938)
					(mid 221.726887 -176.819052)
					(end 221.114874 -177.431192)
				)
				(arc
					(start 221.114874 -178.548792)
					(mid 221.727014 -179.160932)
					(end 222.339154 -178.548792)
				)
			)
		)
		(polygon
			(pts
				(arc
					(start 37.33927 -177.430938)
					(mid 36.727003 -176.819052)
					(end 36.11499 -177.431192)
				)
				(arc
					(start 36.11499 -178.548792)
					(mid 36.72713 -179.160932)
					(end 37.33927 -178.548792)
				)
			)
		)
		(polygon
			(pts
				(arc
					(start 5.59054 -176.735232)
					(mid 5.079873 -176.224946)
					(end 4.56946 -176.735486)
				)
				(arc
					(start 4.56946 -177.548286)
					(mid 5.08 -178.058826)
					(end 5.59054 -177.548286)
				)
			)
		)
		(polygon
			(pts
				(arc
					(start 7.502906 -175.18634)
					(mid 6.992239 -174.676054)
					(end 6.481826 -175.186594)
				)
				(arc
					(start 6.481826 -175.999394)
					(mid 6.992366 -176.509934)
					(end 7.502906 -175.999394)
				)
			)
		)
		(polygon
			(pts
				(arc
					(start 220.840554 -175.183292)
					(mid 220.329887 -174.673006)
					(end 219.819474 -175.183546)
				)
				(arc
					(start 219.819474 -175.996346)
					(mid 220.330014 -176.506886)
					(end 220.840554 -175.996346)
				)
			)
		)
		(polygon
			(pts
				(arc
					(start 35.84067 -175.183292)
					(mid 35.330003 -174.673006)
					(end 34.81959 -175.183546)
				)
				(arc
					(start 34.81959 -175.996346)
					(mid 35.33013 -176.506886)
					(end 35.84067 -175.996346)
				)
			)
		)
		(polygon
			(pts
				(arc
					(start 5.59054 -173.535086)
					(mid 5.079873 -173.0248)
					(end 4.56946 -173.53534)
				)
				(arc
					(start 4.56946 -174.34814)
					(mid 5.08 -174.85868)
					(end 5.59054 -174.34814)
				)
			)
		)
		(polygon
			(pts
				(arc
					(start 222.339154 -172.630846)
					(mid 221.726887 -172.01896)
					(end 221.114874 -172.6311)
				)
				(arc
					(start 221.114874 -173.7487)
					(mid 221.727014 -174.36084)
					(end 222.339154 -173.7487)
				)
			)
		)
		(polygon
			(pts
				(arc
					(start 37.33927 -172.630846)
					(mid 36.727003 -172.01896)
					(end 36.11499 -172.6311)
				)
				(arc
					(start 36.11499 -173.7487)
					(mid 36.72713 -174.36084)
					(end 37.33927 -173.7487)
				)
			)
		)
		(polygon
			(pts
				(arc
					(start 7.502906 -171.986448)
					(mid 6.992239 -171.476162)
					(end 6.481826 -171.986702)
				)
				(arc
					(start 6.481826 -172.799502)
					(mid 6.992366 -173.310042)
					(end 7.502906 -172.799502)
				)
			)
		)
		(polygon
			(pts
				(arc
					(start 220.840554 -170.383454)
					(mid 220.329887 -169.873168)
					(end 219.819474 -170.383708)
				)
				(arc
					(start 219.819474 -171.196508)
					(mid 220.330014 -171.707048)
					(end 220.840554 -171.196508)
				)
			)
		)
		(polygon
			(pts
				(arc
					(start 35.84067 -170.383454)
					(mid 35.330003 -169.873168)
					(end 34.81959 -170.383708)
				)
				(arc
					(start 34.81959 -171.196508)
					(mid 35.33013 -171.707048)
					(end 35.84067 -171.196508)
				)
			)
		)
		(polygon
			(pts
				(arc
					(start 5.59054 -170.335194)
					(mid 5.079873 -169.824908)
					(end 4.56946 -170.335448)
				)
				(arc
					(start 4.56946 -171.148248)
					(mid 5.08 -171.658788)
					(end 5.59054 -171.148248)
				)
			)
		)
		(polygon
			(pts
				(arc
					(start 7.502906 -168.786556)
					(mid 6.992239 -168.27627)
					(end 6.481826 -168.78681)
				)
				(arc
					(start 6.481826 -169.59961)
					(mid 6.992366 -170.11015)
					(end 7.502906 -169.59961)
				)
			)
		)
		(polygon
			(pts
				(arc
					(start 5.59054 -167.135048)
					(mid 5.079873 -166.624762)
					(end 4.56946 -167.135302)
				)
				(arc
					(start 4.56946 -167.948102)
					(mid 5.08 -168.458642)
					(end 5.59054 -167.948102)
				)
			)
		)
		(polygon
			(pts
				(arc
					(start 5.59054 -163.935156)
					(mid 5.079873 -163.42487)
					(end 4.56946 -163.93541)
				)
				(arc
					(start 4.56946 -164.74821)
					(mid 5.08 -165.25875)
					(end 5.59054 -164.74821)
				)
			)
		)
		(polygon
			(pts
				(arc
					(start 233.897424 -163.579302)
					(mid 233.386884 -163.068762)
					(end 232.876344 -163.579302)
				)
				(arc
					(start 232.876344 -164.392356)
					(mid 233.387011 -164.902642)
					(end 233.897424 -164.392102)
				)
			)
		)
		(polygon
			(pts
				(arc
					(start 48.89754 -163.579048)
					(mid 48.386873 -163.068762)
					(end 47.87646 -163.579302)
				)
				(arc
					(start 47.87646 -164.392102)
					(mid 48.387 -164.902642)
					(end 48.89754 -164.392102)
				)
			)
		)
		(polygon
			(pts
				(arc
					(start 230.720138 -163.300664)
					(mid 231.230424 -162.789997)
					(end 230.719884 -162.279584)
				)
				(arc
					(start 229.907084 -162.279584)
					(mid 229.396544 -162.790124)
					(end 229.907084 -163.300664)
				)
			)
		)
		(polygon
			(pts
				(arc
					(start 45.72 -163.300664)
					(mid 46.23054 -162.790124)
					(end 45.72 -162.279584)
				)
				(arc
					(start 44.906946 -162.279584)
					(mid 44.39666 -162.790251)
					(end 44.9072 -163.300664)
				)
			)
		)
		(polygon
			(pts
				(arc
					(start 7.502906 -162.386518)
					(mid 6.992239 -161.876232)
					(end 6.481826 -162.386772)
				)
				(arc
					(start 6.481826 -163.199572)
					(mid 6.992366 -163.710112)
					(end 7.502906 -163.199572)
				)
			)
		)
		(polygon
			(pts
				(arc
					(start 5.59054 -160.735264)
					(mid 5.079873 -160.224978)
					(end 4.56946 -160.735518)
				)
				(arc
					(start 4.56946 -161.548318)
					(mid 5.08 -162.058858)
					(end 5.59054 -161.548318)
				)
			)
		)
		(polygon
			(pts
				(arc
					(start 222.339154 -159.831024)
					(mid 221.726887 -159.219138)
					(end 221.114874 -159.831278)
				)
				(arc
					(start 221.114874 -160.948878)
					(mid 221.727014 -161.561018)
					(end 222.339154 -160.948878)
				)
			)
		)
		(polygon
			(pts
				(arc
					(start 37.33927 -159.831024)
					(mid 36.727003 -159.219138)
					(end 36.11499 -159.831278)
				)
				(arc
					(start 36.11499 -160.948878)
					(mid 36.72713 -161.561018)
					(end 37.33927 -160.948878)
				)
			)
		)
		(polygon
			(pts
				(arc
					(start 7.502906 -159.186372)
					(mid 6.992239 -158.676086)
					(end 6.481826 -159.186626)
				)
				(arc
					(start 6.481826 -159.999426)
					(mid 6.992366 -160.509966)
					(end 7.502906 -159.999426)
				)
			)
		)
		(polygon
			(pts
				(arc
					(start 220.840554 -157.583378)
					(mid 220.329887 -157.073092)
					(end 219.819474 -157.583632)
				)
				(arc
					(start 219.819474 -158.396432)
					(mid 220.330014 -158.906972)
					(end 220.840554 -158.396432)
				)
			)
		)
		(polygon
			(pts
				(arc
					(start 35.84067 -157.583378)
					(mid 35.330003 -157.073092)
					(end 34.81959 -157.583632)
				)
				(arc
					(start 34.81959 -158.396432)
					(mid 35.33013 -158.906972)
					(end 35.84067 -158.396432)
				)
			)
		)
		(polygon
			(pts
				(arc
					(start 5.59054 -157.535118)
					(mid 5.079873 -157.024832)
					(end 4.56946 -157.535372)
				)
				(arc
					(start 4.56946 -158.348172)
					(mid 5.08 -158.858712)
					(end 5.59054 -158.348172)
				)
			)
		)
		(polygon
			(pts
				(arc
					(start 7.502906 -155.97378)
					(mid 6.992239 -155.463494)
					(end 6.481826 -155.974034)
				)
				(arc
					(start 6.481826 -156.786834)
					(mid 6.992366 -157.297374)
					(end 7.502906 -156.786834)
				)
			)
		)
		(polygon
			(pts
				(arc
					(start 5.59054 -154.335226)
					(mid 5.079873 -153.82494)
					(end 4.56946 -154.33548)
				)
				(arc
					(start 4.56946 -155.14828)
					(mid 5.08 -155.65882)
					(end 5.59054 -155.14828)
				)
			)
		)
		(polygon
			(pts
				(arc
					(start 7.502906 -152.786334)
					(mid 6.992239 -152.276048)
					(end 6.481826 -152.786588)
				)
				(arc
					(start 6.481826 -153.599388)
					(mid 6.992366 -154.109928)
					(end 7.502906 -153.599388)
				)
			)
		)
		(polygon
			(pts
				(arc
					(start 27.18054 -141.603476)
					(mid 26.67 -141.092936)
					(end 26.15946 -141.603476)
				)
				(arc
					(start 26.15946 -142.41653)
					(mid 26.670127 -142.926816)
					(end 27.18054 -142.416276)
				)
			)
		)
		(polygon
			(pts
				(arc
					(start 25.88514 -139.050776)
					(mid 25.272873 -138.43889)
					(end 24.66086 -139.05103)
				)
				(arc
					(start 24.66086 -140.16863)
					(mid 25.273 -140.78077)
					(end 25.88514 -140.16863)
				)
			)
		)
		(polygon
			(pts
				(arc
					(start 32.00654 -135.603488)
					(mid 31.495873 -135.093202)
					(end 30.98546 -135.603742)
				)
				(arc
					(start 30.98546 -136.416542)
					(mid 31.496 -136.927082)
					(end 32.00654 -136.416542)
				)
			)
		)
		(polygon
			(pts
				(arc
					(start 17.78254 -135.603234)
					(mid 17.272 -135.092694)
					(end 16.76146 -135.603234)
				)
				(arc
					(start 16.76146 -136.416288)
					(mid 17.272127 -136.926574)
					(end 17.78254 -136.416034)
				)
			)
		)
		(polygon
			(pts
				(arc
					(start 27.18054 -128.8034)
					(mid 26.67 -128.29286)
					(end 26.15946 -128.8034)
				)
				(arc
					(start 26.15946 -129.616454)
					(mid 26.670127 -130.12674)
					(end 27.18054 -129.6162)
				)
			)
		)
		(polygon
			(pts
				(arc
					(start 25.88514 -126.251208)
					(mid 25.273 -125.639068)
					(end 24.66086 -126.251208)
				)
				(arc
					(start 24.66086 -127.369062)
					(mid 25.273127 -127.980948)
					(end 25.88514 -127.368808)
				)
			)
		)
		(polygon
			(pts
				(arc
					(start 27.18054 -124.003562)
					(mid 26.67 -123.493022)
					(end 26.15946 -124.003562)
				)
				(arc
					(start 26.15946 -124.816616)
					(mid 26.670127 -125.326902)
					(end 27.18054 -124.816362)
				)
			)
		)
		(polygon
			(pts
				(arc
					(start 25.88514 -121.451116)
					(mid 25.273 -120.838976)
					(end 24.66086 -121.451116)
				)
				(arc
					(start 24.66086 -122.56897)
					(mid 25.273127 -123.180856)
					(end 25.88514 -122.568716)
				)
			)
		)
		(polygon
			(pts
				(arc
					(start 27.18054 -119.20347)
					(mid 26.67 -118.69293)
					(end 26.15946 -119.20347)
				)
				(arc
					(start 26.15946 -120.016524)
					(mid 26.670127 -120.52681)
					(end 27.18054 -120.01627)
				)
			)
		)
		(polygon
			(pts
				(arc
					(start 25.88514 -116.65077)
					(mid 25.272873 -116.038884)
					(end 24.66086 -116.651024)
				)
				(arc
					(start 24.66086 -117.768624)
					(mid 25.273 -118.380764)
					(end 25.88514 -117.768624)
				)
			)
		)
		(polygon
			(pts
				(arc
					(start 222.339154 -79.230982)
					(mid 221.726887 -78.619096)
					(end 221.114874 -79.231236)
				)
				(arc
					(start 221.114874 -80.348836)
					(mid 221.727014 -80.960976)
					(end 222.339154 -80.348836)
				)
			)
		)
		(polygon
			(pts
				(arc
					(start 37.33927 -79.230982)
					(mid 36.727003 -78.619096)
					(end 36.11499 -79.231236)
				)
				(arc
					(start 36.11499 -80.348836)
					(mid 36.72713 -80.960976)
					(end 37.33927 -80.348836)
				)
			)
		)
		(polygon
			(pts
				(arc
					(start 220.840554 -76.983336)
					(mid 220.329887 -76.47305)
					(end 219.819474 -76.98359)
				)
				(arc
					(start 219.819474 -77.79639)
					(mid 220.330014 -78.30693)
					(end 220.840554 -77.79639)
				)
			)
		)
		(polygon
			(pts
				(arc
					(start 35.84067 -76.983336)
					(mid 35.330003 -76.47305)
					(end 34.81959 -76.98359)
				)
				(arc
					(start 34.81959 -77.79639)
					(mid 35.33013 -78.30693)
					(end 35.84067 -77.79639)
				)
			)
		)
		(polygon
			(pts
				(arc
					(start 222.339154 -74.43089)
					(mid 221.726887 -73.819004)
					(end 221.114874 -74.431144)
				)
				(arc
					(start 221.114874 -75.548744)
					(mid 221.727014 -76.160884)
					(end 222.339154 -75.548744)
				)
			)
		)
		(polygon
			(pts
				(arc
					(start 37.33927 -74.43089)
					(mid 36.727003 -73.819004)
					(end 36.11499 -74.431144)
				)
				(arc
					(start 36.11499 -75.548744)
					(mid 36.72713 -76.160884)
					(end 37.33927 -75.548744)
				)
			)
		)
		(polygon
			(pts
				(arc
					(start 220.840554 -72.183244)
					(mid 220.329887 -71.672958)
					(end 219.819474 -72.183498)
				)
				(arc
					(start 219.819474 -72.996298)
					(mid 220.330014 -73.506838)
					(end 220.840554 -72.996298)
				)
			)
		)
		(polygon
			(pts
				(arc
					(start 35.84067 -72.183244)
					(mid 35.330003 -71.672958)
					(end 34.81959 -72.183498)
				)
				(arc
					(start 34.81959 -72.996298)
					(mid 35.33013 -73.506838)
					(end 35.84067 -72.996298)
				)
			)
		)
		(polygon
			(pts
				(arc
					(start 222.339154 -69.630798)
					(mid 221.726887 -69.018912)
					(end 221.114874 -69.631052)
				)
				(arc
					(start 221.114874 -70.748652)
					(mid 221.727014 -71.360792)
					(end 222.339154 -70.748652)
				)
			)
		)
		(polygon
			(pts
				(arc
					(start 37.33927 -69.630798)
					(mid 36.727003 -69.018912)
					(end 36.11499 -69.631052)
				)
				(arc
					(start 36.11499 -70.748652)
					(mid 36.72713 -71.360792)
					(end 37.33927 -70.748652)
				)
			)
		)
		(polygon
			(pts
				(xy 169.877994 -68.5165) (xy 97.330006 -68.5165) (xy 72.8345 -93.012006) (xy 72.8345 -166.755064)
				(xy 75.007724 -168.928288) (xy 75.007724 -177.325782) (xy 72.8345 -179.499006) (xy 72.8345 -269.755112)
				(xy 75.007724 -271.928336) (xy 75.007724 -278.417782) (xy 72.8345 -280.591006) (xy 72.8345 -343.867994)
				(xy 127.683006 -398.7165) (xy 169.877994 -398.7165) (xy 170.6245 -397.969994) (xy 170.6245 -69.263006)
				(xy 169.9895 -68.628006)
			)
		)
		(polygon
			(pts
				(arc
					(start 220.840554 -67.383406)
					(mid 220.329887 -66.87312)
					(end 219.819474 -67.38366)
				)
				(arc
					(start 219.819474 -68.19646)
					(mid 220.330014 -68.707)
					(end 220.840554 -68.19646)
				)
			)
		)
		(polygon
			(pts
				(arc
					(start 35.84067 -67.383406)
					(mid 35.330003 -66.87312)
					(end 34.81959 -67.38366)
				)
				(arc
					(start 34.81959 -68.19646)
					(mid 35.33013 -68.707)
					(end 35.84067 -68.19646)
				)
			)
		)
		(polygon
			(pts
				(arc
					(start 233.897424 -60.579254)
					(mid 233.386884 -60.068714)
					(end 232.876344 -60.579254)
				)
				(arc
					(start 232.876344 -61.392308)
					(mid 233.387011 -61.902594)
					(end 233.897424 -61.392054)
				)
			)
		)
		(polygon
			(pts
				(arc
					(start 48.89754 -60.579)
					(mid 48.386873 -60.068714)
					(end 47.87646 -60.579254)
				)
				(arc
					(start 47.87646 -61.392054)
					(mid 48.387 -61.902594)
					(end 48.89754 -61.392054)
				)
			)
		)
		(polygon
			(pts
				(arc
					(start 230.720138 -60.300616)
					(mid 231.230424 -59.789949)
					(end 230.719884 -59.279536)
				)
				(arc
					(start 229.907084 -59.279536)
					(mid 229.396544 -59.790076)
					(end 229.907084 -60.300616)
				)
			)
		)
		(polygon
			(pts
				(arc
					(start 45.72 -60.300616)
					(mid 46.23054 -59.790076)
					(end 45.72 -59.279536)
				)
				(arc
					(start 44.906946 -59.279536)
					(mid 44.39666 -59.790203)
					(end 44.9072 -60.300616)
				)
			)
		)
		(polygon
			(pts
				(arc
					(start 222.339154 -56.830976)
					(mid 221.726887 -56.21909)
					(end 221.114874 -56.83123)
				)
				(arc
					(start 221.114874 -57.94883)
					(mid 221.727014 -58.56097)
					(end 222.339154 -57.94883)
				)
			)
		)
		(polygon
			(pts
				(arc
					(start 37.33927 -56.830976)
					(mid 36.727003 -56.21909)
					(end 36.11499 -56.83123)
				)
				(arc
					(start 36.11499 -57.94883)
					(mid 36.72713 -58.56097)
					(end 37.33927 -57.94883)
				)
			)
		)
		(polygon
			(pts
				(arc
					(start 220.840554 -54.58333)
					(mid 220.329887 -54.073044)
					(end 219.819474 -54.583584)
				)
				(arc
					(start 219.819474 -55.396384)
					(mid 220.330014 -55.906924)
					(end 220.840554 -55.396384)
				)
			)
		)
		(polygon
			(pts
				(arc
					(start 35.84067 -54.58333)
					(mid 35.330003 -54.073044)
					(end 34.81959 -54.583584)
				)
				(arc
					(start 34.81959 -55.396384)
					(mid 35.33013 -55.906924)
					(end 35.84067 -55.396384)
				)
			)
		)
		(polygon
			(pts
				(arc
					(start 27.18054 -38.603428)
					(mid 26.67 -38.092888)
					(end 26.15946 -38.603428)
				)
				(arc
					(start 26.15946 -39.416482)
					(mid 26.670127 -39.926768)
					(end 27.18054 -39.416228)
				)
			)
		)
		(polygon
			(pts
				(arc
					(start 25.88514 -36.050982)
					(mid 25.273 -35.438842)
					(end 24.66086 -36.050982)
				)
				(arc
					(start 24.66086 -37.168836)
					(mid 25.273127 -37.780722)
					(end 25.88514 -37.168582)
				)
			)
		)
		(polygon
			(pts
				(arc
					(start 32.00654 -32.602932)
					(mid 31.495873 -32.092646)
					(end 30.98546 -32.603186)
				)
				(arc
					(start 30.98546 -33.415986)
					(mid 31.496 -33.926526)
					(end 32.00654 -33.415986)
				)
			)
		)
		(polygon
			(pts
				(arc
					(start 17.78254 -32.602932)
					(mid 17.271873 -32.092646)
					(end 16.76146 -32.603186)
				)
				(arc
					(start 16.76146 -33.415986)
					(mid 17.272 -33.926526)
					(end 17.78254 -33.415986)
				)
			)
		)
		(polygon
			(pts
				(arc
					(start 27.18054 -25.803352)
					(mid 26.67 -25.292812)
					(end 26.15946 -25.803352)
				)
				(arc
					(start 26.15946 -26.616406)
					(mid 26.670127 -27.126692)
					(end 27.18054 -26.616152)
				)
			)
		)
		(polygon
			(pts
				(arc
					(start 25.88514 -23.25116)
					(mid 25.273 -22.63902)
					(end 24.66086 -23.25116)
				)
				(arc
					(start 24.66086 -24.369014)
					(mid 25.273127 -24.9809)
					(end 25.88514 -24.36876)
				)
			)
		)
		(polygon
			(pts
				(arc
					(start 27.18054 -21.003514)
					(mid 26.67 -20.492974)
					(end 26.15946 -21.003514)
				)
				(arc
					(start 26.15946 -21.816568)
					(mid 26.670127 -22.326854)
					(end 27.18054 -21.816314)
				)
			)
		)
		(polygon
			(pts
				(arc
					(start 25.88514 -18.451068)
					(mid 25.273 -17.838928)
					(end 24.66086 -18.451068)
				)
				(arc
					(start 24.66086 -19.568922)
					(mid 25.273127 -20.180808)
					(end 25.88514 -19.568668)
				)
			)
		)
		(polygon
			(pts
				(arc
					(start 27.18054 -16.203422)
					(mid 26.67 -15.692882)
					(end 26.15946 -16.203422)
				)
				(arc
					(start 26.15946 -17.016476)
					(mid 26.670127 -17.526762)
					(end 27.18054 -17.016222)
				)
			)
		)
		(polygon
			(pts
				(arc
					(start 25.88514 -13.676122)
					(mid 25.272873 -13.064236)
					(end 24.66086 -13.676376)
				)
				(arc
					(start 24.66086 -14.793976)
					(mid 25.273 -15.406116)
					(end 25.88514 -14.793976)
				)
			)
		)
	)
	(zone
		(layer "In4.Cu")
		(hatch none 0.5)
		(connect_pads
			(clearance 0)
		)
		(min_thickness 0.25)
		(keepout
			(tracks not_allowed)
			(vias allowed)
			(pads allowed)
			(copperpour not_allowed)
			(footprints allowed)
		)
		(placement
			(enabled no)
			(sheetname "")
		)
		(fill
			(thermal_gap 0.5)
			(thermal_bridge_width 0.5)
			(island_removal_mode 0)
		)
		(polygon
			(pts
				(arc
					(start 29.99994 -1.000252)
					(mid 33.999932 2.99974)
					(end 37.999924 -1.000252)
				)
				(arc
					(start 37.999924 -4.500118)
					(mid 33.999932 -8.50011)
					(end 29.99994 -4.500118)
				)
			)
		)
	)
	(zone
		(net "P3V3")
		(layer "In4.Cu")
		(hatch none 0.5)
		(connect_pads
			(clearance 0.5)
		)
		(min_thickness 0.25)
		(fill yes
			(thermal_gap 0.5)
			(thermal_bridge_width 0.5)
			(island_removal_mode 0)
		)
		(polygon
			(pts
				(xy 97.487994 -68.8975) (xy 73.2155 -93.169994) (xy 73.2155 -166.597076) (xy 75.388724 -168.7703)
				(xy 75.388724 -177.48377) (xy 73.2155 -179.656994) (xy 73.2155 -269.597124) (xy 75.388724 -271.770348)
				(xy 75.388724 -278.57577) (xy 73.2155 -280.748994) (xy 73.2155 -343.710006) (xy 127.840994 -398.3355)
				(xy 169.720006 -398.3355) (xy 170.2435 -397.812006) (xy 170.2435 -69.420994) (xy 169.720006 -68.8975)
			)
		)
	)
	(zone
		(layer "In5.Cu")
		(hatch none 0.5)
		(connect_pads
			(clearance 0)
		)
		(min_thickness 0.25)
		(keepout
			(tracks not_allowed)
			(vias allowed)
			(pads allowed)
			(copperpour not_allowed)
			(footprints allowed)
		)
		(placement
			(enabled no)
			(sheetname "")
		)
		(fill
			(thermal_gap 0.5)
			(thermal_bridge_width 0.5)
			(island_removal_mode 0)
		)
		(polygon
			(pts
				(arc
					(start 35.84067 -157.583886)
					(mid 35.330257 -157.073092)
					(end 34.81959 -157.583632)
				)
				(xy 34.81959 -157.717236) (xy 35.061906 -157.717236)
				(arc
					(start 35.086544 -157.692344)
					(mid 35.518747 -157.395015)
					(end 35.221418 -157.827218)
				)
				(xy 35.140646 -157.907736) (xy 34.81959 -157.907736) (xy 34.81959 -158.072836) (xy 35.141154 -158.072836)
				(arc
					(start 35.221418 -158.152846)
					(mid 35.518747 -158.585049)
					(end 35.086544 -158.28772)
				)
				(xy 35.062414 -158.263336) (xy 34.81959 -158.263336)
				(arc
					(start 34.81959 -158.396432)
					(mid 35.33013 -158.906972)
					(end 35.84067 -158.396432)
				)
			)
		)
	)
	(zone
		(net "P12V")
		(layer "In5.Cu")
		(hatch none 0.5)
		(connect_pads
			(clearance 0.5)
		)
		(min_thickness 0.25)
		(fill yes
			(thermal_gap 0.5)
			(thermal_bridge_width 0.5)
			(island_removal_mode 0)
		)
		(polygon
			(pts
				(xy 256.818892 -362.356146) (xy 255.930146 -361.4674) (xy 253.7206 -361.4674) (xy 253.5682 -361.315)
				(xy 237.363 -361.315) (xy 237.089442 -361.588558) (xy 237.089442 -383.375408) (xy 237.304834 -383.5908)
				(xy 256.678176 -383.5908) (xy 256.818892 -383.450084)
			)
		)
	)
	(zone
		(layer "In5.Cu")
		(hatch none 0.5)
		(connect_pads
			(clearance 0)
		)
		(min_thickness 0.25)
		(keepout
			(tracks not_allowed)
			(vias allowed)
			(pads allowed)
			(copperpour not_allowed)
			(footprints allowed)
		)
		(placement
			(enabled no)
			(sheetname "")
		)
		(fill
			(thermal_gap 0.5)
			(thermal_bridge_width 0.5)
			(island_removal_mode 0)
		)
		(polygon
			(pts
				(arc
					(start 35.84067 -363.583982)
					(mid 35.330257 -363.073188)
					(end 34.81959 -363.583728)
				)
				(xy 34.81959 -363.717332) (xy 35.061906 -363.717332)
				(arc
					(start 35.086544 -363.69244)
					(mid 35.518747 -363.395111)
					(end 35.221418 -363.827314)
				)
				(xy 35.140646 -363.907832) (xy 34.81959 -363.907832) (xy 34.81959 -364.072932) (xy 35.141154 -364.072932)
				(arc
					(start 35.221418 -364.152942)
					(mid 35.518747 -364.585145)
					(end 35.086544 -364.287816)
				)
				(xy 35.062414 -364.263432) (xy 34.81959 -364.263432)
				(arc
					(start 34.81959 -364.396528)
					(mid 35.33013 -364.907068)
					(end 35.84067 -364.396528)
				)
			)
		)
	)
	(zone
		(layer "In5.Cu")
		(hatch none 0.5)
		(connect_pads
			(clearance 0)
		)
		(min_thickness 0.25)
		(keepout
			(tracks not_allowed)
			(vias allowed)
			(pads allowed)
			(copperpour not_allowed)
			(footprints allowed)
		)
		(placement
			(enabled no)
			(sheetname "")
		)
		(fill
			(thermal_gap 0.5)
			(thermal_bridge_width 0.5)
			(island_removal_mode 0)
		)
		(polygon
			(pts
				(arc
					(start 7.502906 -443.18428)
					(mid 6.992366 -442.67374)
					(end 6.481826 -443.18428)
				)
				(arc
					(start 6.481826 -443.996826)
					(mid 6.992239 -444.50762)
					(end 7.502906 -443.99708)
				)
				(xy 7.502906 -443.86373) (xy 7.260336 -443.86373)
				(arc
					(start 7.235952 -443.888368)
					(mid 6.803749 -444.185697)
					(end 7.101078 -443.753494)
				)
				(xy 7.181596 -443.67323) (xy 7.502906 -443.67323) (xy 7.502906 -443.50813) (xy 7.181596 -443.50813)
				(arc
					(start 7.101078 -443.427866)
					(mid 6.803749 -442.995663)
					(end 7.235952 -443.292992)
				)
				(xy 7.260336 -443.31763) (xy 7.502906 -443.31763)
			)
		)
	)
	(zone
		(layer "In5.Cu")
		(hatch none 0.5)
		(connect_pads
			(clearance 0)
		)
		(min_thickness 0.25)
		(keepout
			(tracks not_allowed)
			(vias allowed)
			(pads allowed)
			(copperpour not_allowed)
			(footprints allowed)
		)
		(placement
			(enabled no)
			(sheetname "")
		)
		(fill
			(thermal_gap 0.5)
			(thermal_bridge_width 0.5)
			(island_removal_mode 0)
		)
		(polygon
			(pts
				(arc
					(start 27.18054 -450.603874)
					(mid 26.670127 -450.09308)
					(end 26.15946 -450.60362)
				)
				(arc
					(start 26.15946 -451.41642)
					(mid 26.67 -451.92696)
					(end 27.18054 -451.41642)
				)
				(xy 27.18054 -451.282816) (xy 26.938224 -451.282816)
				(arc
					(start 26.913586 -451.307708)
					(mid 26.481383 -451.605037)
					(end 26.778712 -451.172834)
				)
				(xy 26.859484 -451.092316) (xy 27.18054 -451.092316) (xy 27.18054 -450.927216) (xy 26.858976 -450.927216)
				(arc
					(start 26.778712 -450.847206)
					(mid 26.481383 -450.415003)
					(end 26.913586 -450.712332)
				)
				(xy 26.937716 -450.736716) (xy 27.18054 -450.736716)
			)
		)
	)
	(zone
		(layer "In5.Cu")
		(hatch none 0.5)
		(connect_pads
			(clearance 0)
		)
		(min_thickness 0.25)
		(keepout
			(tracks not_allowed)
			(vias allowed)
			(pads allowed)
			(copperpour not_allowed)
			(footprints allowed)
		)
		(placement
			(enabled no)
			(sheetname "")
		)
		(fill
			(thermal_gap 0.5)
			(thermal_bridge_width 0.5)
			(island_removal_mode 0)
		)
		(polygon
			(pts
				(arc
					(start 7.502906 -195.936108)
					(mid 6.992493 -195.425314)
					(end 6.481826 -195.935854)
				)
				(arc
					(start 6.481826 -196.748654)
					(mid 6.992366 -197.259194)
					(end 7.502906 -196.748654)
				)
				(xy 7.502906 -196.615304) (xy 7.260336 -196.615304)
				(arc
					(start 7.235952 -196.639942)
					(mid 6.803749 -196.937271)
					(end 7.101078 -196.505068)
				)
				(xy 7.181596 -196.424804) (xy 7.502906 -196.424804) (xy 7.502906 -196.259704) (xy 7.181596 -196.259704)
				(arc
					(start 7.101078 -196.17944)
					(mid 6.803749 -195.747237)
					(end 7.235952 -196.044566)
				)
				(xy 7.260336 -196.069204) (xy 7.502906 -196.069204)
			)
		)
	)
	(zone
		(layer "In5.Cu")
		(hatch none 0.5)
		(connect_pads
			(clearance 0)
		)
		(min_thickness 0.25)
		(keepout
			(tracks not_allowed)
			(vias allowed)
			(pads allowed)
			(copperpour not_allowed)
			(footprints allowed)
		)
		(placement
			(enabled no)
			(sheetname "")
		)
		(fill
			(thermal_gap 0.5)
			(thermal_bridge_width 0.5)
			(island_removal_mode 0)
		)
		(polygon
			(pts
				(xy 7.502906 -175.288448)
				(arc
					(start 7.502906 -175.186848)
					(mid 6.992493 -174.676054)
					(end 6.481826 -175.186594)
				)
				(arc
					(start 6.481826 -175.999394)
					(mid 6.992366 -176.509934)
					(end 7.502906 -175.999394)
				)
				(xy 7.502906 -175.84293) (xy 7.409688 -175.85944) (xy 7.40283 -175.866044) (xy 7.371842 -175.866044)
				(xy 7.341108 -175.871378) (xy 7.333488 -175.866044) (xy 7.260336 -175.866044)
				(arc
					(start 7.235952 -175.890682)
					(mid 6.803749 -176.188011)
					(end 7.101078 -175.755808)
				)
				(xy 7.181596 -175.675544) (xy 7.355078 -175.675544) (xy 7.502906 -175.649382) (xy 7.502906 -175.481742)
				(xy 7.378446 -175.50384) (xy 7.371588 -175.510444) (xy 7.3406 -175.510444) (xy 7.309866 -175.515778)
				(xy 7.302246 -175.510444) (xy 7.181596 -175.510444)
				(arc
					(start 7.101078 -175.43018)
					(mid 6.803749 -174.997977)
					(end 7.235952 -175.295306)
				)
				(xy 7.260336 -175.319944) (xy 7.323836 -175.319944)
			)
		)
	)
	(zone
		(layer "In5.Cu")
		(hatch none 0.5)
		(connect_pads
			(clearance 0)
		)
		(min_thickness 0.25)
		(keepout
			(tracks not_allowed)
			(vias allowed)
			(pads allowed)
			(copperpour not_allowed)
			(footprints allowed)
		)
		(placement
			(enabled no)
			(sheetname "")
		)
		(fill
			(thermal_gap 0.5)
			(thermal_bridge_width 0.5)
			(island_removal_mode 0)
		)
		(polygon
			(pts
				(arc
					(start 7.502906 -405.535638)
					(mid 6.992366 -405.025098)
					(end 6.481826 -405.535638)
				)
				(arc
					(start 6.481826 -406.348184)
					(mid 6.992239 -406.858978)
					(end 7.502906 -406.348438)
				)
				(xy 7.502906 -406.215088) (xy 7.260336 -406.215088)
				(arc
					(start 7.235952 -406.239726)
					(mid 6.803749 -406.537055)
					(end 7.101078 -406.104852)
				)
				(xy 7.181596 -406.024588) (xy 7.502906 -406.024588) (xy 7.502906 -405.859488) (xy 7.181596 -405.859488)
				(arc
					(start 7.101078 -405.779224)
					(mid 6.803749 -405.347021)
					(end 7.235952 -405.64435)
				)
				(xy 7.260336 -405.668988) (xy 7.502906 -405.668988)
			)
		)
	)
	(zone
		(layer "In5.Cu")
		(hatch none 0.5)
		(connect_pads
			(clearance 0)
		)
		(min_thickness 0.25)
		(keepout
			(tracks not_allowed)
			(vias allowed)
			(pads allowed)
			(copperpour not_allowed)
			(footprints allowed)
		)
		(placement
			(enabled no)
			(sheetname "")
		)
		(fill
			(thermal_gap 0.5)
			(thermal_bridge_width 0.5)
			(island_removal_mode 0)
		)
		(polygon
			(pts
				(arc
					(start 35.84067 -76.983844)
					(mid 35.330257 -76.47305)
					(end 34.81959 -76.98359)
				)
				(xy 34.81959 -77.117194) (xy 35.061906 -77.117194)
				(arc
					(start 35.086544 -77.092302)
					(mid 35.518747 -76.794973)
					(end 35.221418 -77.227176)
				)
				(xy 35.140646 -77.307694) (xy 34.81959 -77.307694) (xy 34.81959 -77.472794) (xy 35.141154 -77.472794)
				(arc
					(start 35.221418 -77.552804)
					(mid 35.518747 -77.985007)
					(end 35.086544 -77.687678)
				)
				(xy 35.062414 -77.663294) (xy 34.81959 -77.663294)
				(arc
					(start 34.81959 -77.79639)
					(mid 35.33013 -78.30693)
					(end 35.84067 -77.79639)
				)
			)
		)
	)
	(zone
		(net "VDD_DIFF_2")
		(layer "In5.Cu")
		(hatch none 0.5)
		(connect_pads
			(clearance 0.5)
		)
		(min_thickness 0.25)
		(fill yes
			(thermal_gap 0.5)
			(thermal_bridge_width 0.5)
			(island_removal_mode 0)
		)
		(polygon
			(pts
				(xy 82.423 -316.103) (xy 99.314 -316.103) (xy 104.267 -311.15) (xy 104.267 -302.641) (xy 99.06 -297.434)
				(xy 81.661 -297.434) (xy 78.74 -300.355) (xy 78.74 -312.42)
			)
		)
	)
	(zone
		(layer "In5.Cu")
		(hatch none 0.5)
		(connect_pads
			(clearance 0)
		)
		(min_thickness 0.25)
		(keepout
			(tracks not_allowed)
			(vias allowed)
			(pads allowed)
			(copperpour not_allowed)
			(footprints allowed)
		)
		(placement
			(enabled no)
			(sheetname "")
		)
		(fill
			(thermal_gap 0.5)
			(thermal_bridge_width 0.5)
			(island_removal_mode 0)
		)
		(polygon
			(pts
				(arc
					(start 220.840554 -170.383962)
					(mid 220.330141 -169.873168)
					(end 219.819474 -170.383708)
				)
				(xy 219.819474 -170.517058) (xy 220.062044 -170.517058)
				(arc
					(start 220.086428 -170.49242)
					(mid 220.518631 -170.195091)
					(end 220.221302 -170.627294)
				)
				(xy 220.140784 -170.707558) (xy 219.819474 -170.707558) (xy 219.819474 -170.872658) (xy 220.140784 -170.872658)
				(arc
					(start 220.221302 -170.952922)
					(mid 220.518631 -171.385125)
					(end 220.086428 -171.087796)
				)
				(xy 220.062044 -171.063158) (xy 219.819474 -171.063158)
				(arc
					(start 219.819474 -171.196508)
					(mid 220.330014 -171.707048)
					(end 220.840554 -171.196508)
				)
			)
		)
	)
	(zone
		(layer "In5.Cu")
		(hatch none 0.5)
		(connect_pads
			(clearance 0)
		)
		(min_thickness 0.25)
		(keepout
			(tracks not_allowed)
			(vias allowed)
			(pads allowed)
			(copperpour not_allowed)
			(footprints allowed)
		)
		(placement
			(enabled no)
			(sheetname "")
		)
		(fill
			(thermal_gap 0.5)
			(thermal_bridge_width 0.5)
			(island_removal_mode 0)
		)
		(polygon
			(pts
				(xy 0.763016 -466.852508) (xy 1.521714 -466.852508) (xy 1.521714 -471.47988) (xy 1.67132 -471.629486)
				(xy 1.95199 -471.629486) (xy 2.032 -471.709496) (xy 2.032 -477.427544) (xy 0.763016 -477.427544)
			)
		)
	)
	(zone
		(layer "In5.Cu")
		(hatch none 0.5)
		(connect_pads
			(clearance 0)
		)
		(min_thickness 0.25)
		(keepout
			(tracks not_allowed)
			(vias allowed)
			(pads allowed)
			(copperpour not_allowed)
			(footprints allowed)
		)
		(placement
			(enabled no)
			(sheetname "")
		)
		(fill
			(thermal_gap 0.5)
			(thermal_bridge_width 0.5)
			(island_removal_mode 0)
		)
		(polygon
			(pts
				(arc
					(start 7.502906 -325.136002)
					(mid 6.992366 -324.625462)
					(end 6.481826 -325.136002)
				)
				(arc
					(start 6.481826 -325.948548)
					(mid 6.992239 -326.459342)
					(end 7.502906 -325.948802)
				)
				(xy 7.502906 -325.815452) (xy 7.260336 -325.815452)
				(arc
					(start 7.235952 -325.84009)
					(mid 6.803749 -326.137419)
					(end 7.101078 -325.705216)
				)
				(xy 7.181596 -325.624952) (xy 7.502906 -325.624952) (xy 7.502906 -325.459852) (xy 7.181596 -325.459852)
				(arc
					(start 7.101078 -325.379588)
					(mid 6.803749 -324.947385)
					(end 7.235952 -325.244714)
				)
				(xy 7.260336 -325.269352) (xy 7.502906 -325.269352)
			)
		)
	)
	(zone
		(layer "In5.Cu")
		(hatch none 0.5)
		(connect_pads
			(clearance 0)
		)
		(min_thickness 0.25)
		(keepout
			(tracks not_allowed)
			(vias allowed)
			(pads allowed)
			(copperpour not_allowed)
			(footprints allowed)
		)
		(placement
			(enabled no)
			(sheetname "")
		)
		(fill
			(thermal_gap 0.5)
			(thermal_bridge_width 0.5)
			(island_removal_mode 0)
		)
		(polygon
			(pts
				(arc
					(start 7.502906 -402.335746)
					(mid 6.992366 -401.825206)
					(end 6.481826 -402.335746)
				)
				(arc
					(start 6.481826 -403.148292)
					(mid 6.992239 -403.659086)
					(end 7.502906 -403.148546)
				)
				(xy 7.502906 -403.015196) (xy 7.260336 -403.015196)
				(arc
					(start 7.235952 -403.039834)
					(mid 6.803749 -403.337163)
					(end 7.101078 -402.90496)
				)
				(xy 7.181596 -402.824696) (xy 7.502906 -402.824696) (xy 7.502906 -402.659596) (xy 7.181596 -402.659596)
				(arc
					(start 7.101078 -402.579332)
					(mid 6.803749 -402.147129)
					(end 7.235952 -402.444458)
				)
				(xy 7.260336 -402.469096) (xy 7.502906 -402.469096)
			)
		)
	)
	(zone
		(layer "In5.Cu")
		(hatch none 0.5)
		(connect_pads
			(clearance 0)
		)
		(min_thickness 0.25)
		(keepout
			(tracks not_allowed)
			(vias allowed)
			(pads allowed)
			(copperpour not_allowed)
			(footprints allowed)
		)
		(placement
			(enabled no)
			(sheetname "")
		)
		(fill
			(thermal_gap 0.5)
			(thermal_bridge_width 0.5)
			(island_removal_mode 0)
		)
		(polygon
			(pts
				(arc
					(start 220.840554 -484.183944)
					(mid 220.330141 -483.67315)
					(end 219.819474 -484.18369)
				)
				(xy 219.819474 -484.317294) (xy 220.06179 -484.317294)
				(arc
					(start 220.086428 -484.292402)
					(mid 220.518631 -483.995073)
					(end 220.221302 -484.427276)
				)
				(xy 220.14053 -484.507794) (xy 219.819474 -484.507794) (xy 219.819474 -484.672894) (xy 220.141038 -484.672894)
				(arc
					(start 220.221302 -484.752904)
					(mid 220.518631 -485.185107)
					(end 220.086428 -484.887778)
				)
				(xy 220.062298 -484.863394) (xy 219.819474 -484.863394)
				(arc
					(start 219.819474 -484.99649)
					(mid 220.330014 -485.50703)
					(end 220.840554 -484.99649)
				)
			)
		)
	)
	(zone
		(layer "In5.Cu")
		(hatch none 0.5)
		(connect_pads
			(clearance 0)
		)
		(min_thickness 0.25)
		(keepout
			(tracks not_allowed)
			(vias allowed)
			(pads allowed)
			(copperpour not_allowed)
			(footprints allowed)
		)
		(placement
			(enabled no)
			(sheetname "")
		)
		(fill
			(thermal_gap 0.5)
			(thermal_bridge_width 0.5)
			(island_removal_mode 0)
		)
		(polygon
			(pts
				(arc
					(start 220.840554 -273.38401)
					(mid 220.330141 -272.873216)
					(end 219.819474 -273.383756)
				)
				(xy 219.819474 -273.517106) (xy 220.062044 -273.517106)
				(arc
					(start 220.086428 -273.492468)
					(mid 220.518631 -273.195139)
					(end 220.221302 -273.627342)
				)
				(xy 220.140784 -273.707606) (xy 219.819474 -273.707606) (xy 219.819474 -273.872706) (xy 220.140784 -273.872706)
				(arc
					(start 220.221302 -273.95297)
					(mid 220.518631 -274.385173)
					(end 220.086428 -274.087844)
				)
				(xy 220.062044 -274.063206) (xy 219.819474 -274.063206)
				(arc
					(start 219.819474 -274.196556)
					(mid 220.330014 -274.707096)
					(end 220.840554 -274.196556)
				)
			)
		)
	)
	(zone
		(layer "In5.Cu")
		(hatch none 0.5)
		(connect_pads
			(clearance 0)
		)
		(min_thickness 0.25)
		(keepout
			(tracks not_allowed)
			(vias allowed)
			(pads allowed)
			(copperpour not_allowed)
			(footprints allowed)
		)
		(placement
			(enabled no)
			(sheetname "")
		)
		(fill
			(thermal_gap 0.5)
			(thermal_bridge_width 0.5)
			(island_removal_mode 0)
		)
		(polygon
			(pts
				(arc
					(start 27.18054 -437.803798)
					(mid 26.670127 -437.293004)
					(end 26.15946 -437.803544)
				)
				(arc
					(start 26.15946 -438.616344)
					(mid 26.67 -439.126884)
					(end 27.18054 -438.616344)
				)
				(xy 27.18054 -438.482994) (xy 26.93797 -438.482994)
				(arc
					(start 26.913586 -438.507632)
					(mid 26.481383 -438.804961)
					(end 26.778712 -438.372758)
				)
				(xy 26.85923 -438.292494) (xy 27.18054 -438.292494) (xy 27.18054 -438.127394) (xy 26.85923 -438.127394)
				(arc
					(start 26.778712 -438.04713)
					(mid 26.481383 -437.614927)
					(end 26.913586 -437.912256)
				)
				(xy 26.93797 -437.936894) (xy 27.18054 -437.936894)
			)
		)
	)
	(zone
		(layer "In5.Cu")
		(hatch none 0.5)
		(connect_pads
			(clearance 0)
		)
		(min_thickness 0.25)
		(keepout
			(tracks not_allowed)
			(vias allowed)
			(pads allowed)
			(copperpour not_allowed)
			(footprints allowed)
		)
		(placement
			(enabled no)
			(sheetname "")
		)
		(fill
			(thermal_gap 0.5)
			(thermal_bridge_width 0.5)
			(island_removal_mode 0)
		)
		(polygon
			(pts
				(arc
					(start 7.502906 -201.536046)
					(mid 6.992493 -201.025252)
					(end 6.481826 -201.535792)
				)
				(arc
					(start 6.481826 -202.348592)
					(mid 6.992366 -202.859132)
					(end 7.502906 -202.348592)
				)
				(xy 7.502906 -202.215242) (xy 7.260336 -202.215242)
				(arc
					(start 7.235952 -202.23988)
					(mid 6.803749 -202.537209)
					(end 7.101078 -202.105006)
				)
				(xy 7.181596 -202.024742) (xy 7.502906 -202.024742) (xy 7.502906 -201.859642) (xy 7.181596 -201.859642)
				(arc
					(start 7.101078 -201.779378)
					(mid 6.803749 -201.347175)
					(end 7.235952 -201.644504)
				)
				(xy 7.260336 -201.669142) (xy 7.502906 -201.669142)
			)
		)
	)
	(zone
		(layer "In5.Cu")
		(hatch none 0.5)
		(connect_pads
			(clearance 0)
		)
		(min_thickness 0.25)
		(keepout
			(tracks not_allowed)
			(vias allowed)
			(pads allowed)
			(copperpour not_allowed)
			(footprints allowed)
		)
		(placement
			(enabled no)
			(sheetname "")
		)
		(fill
			(thermal_gap 0.5)
			(thermal_bridge_width 0.5)
			(island_removal_mode 0)
		)
		(polygon
			(pts
				(arc
					(start 7.502906 -439.984134)
					(mid 6.992366 -439.473594)
					(end 6.481826 -439.984134)
				)
				(arc
					(start 6.481826 -440.79668)
					(mid 6.992239 -441.307474)
					(end 7.502906 -440.796934)
				)
				(xy 7.502906 -440.663584) (xy 7.260336 -440.663584)
				(arc
					(start 7.235952 -440.688222)
					(mid 6.803749 -440.985551)
					(end 7.101078 -440.553348)
				)
				(xy 7.181596 -440.473084) (xy 7.502906 -440.473084) (xy 7.502906 -440.307984) (xy 7.181596 -440.307984)
				(arc
					(start 7.101078 -440.22772)
					(mid 6.803749 -439.795517)
					(end 7.235952 -440.092846)
				)
				(xy 7.260336 -440.117484) (xy 7.502906 -440.117484)
			)
		)
	)
	(zone
		(layer "In5.Cu")
		(hatch none 0.5)
		(connect_pads
			(clearance 0)
		)
		(min_thickness 0.25)
		(keepout
			(tracks not_allowed)
			(vias allowed)
			(pads allowed)
			(copperpour not_allowed)
			(footprints allowed)
		)
		(placement
			(enabled no)
			(sheetname "")
		)
		(fill
			(thermal_gap 0.5)
			(thermal_bridge_width 0.5)
			(island_removal_mode 0)
		)
		(polygon
			(pts
				(arc
					(start 7.502906 -346.735908)
					(mid 6.992366 -346.225368)
					(end 6.481826 -346.735908)
				)
				(arc
					(start 6.481826 -347.548454)
					(mid 6.992239 -348.059248)
					(end 7.502906 -347.548708)
				)
				(xy 7.502906 -347.415358) (xy 7.260336 -347.415358)
				(arc
					(start 7.235952 -347.439996)
					(mid 6.803749 -347.737325)
					(end 7.101078 -347.305122)
				)
				(xy 7.181596 -347.224858) (xy 7.502906 -347.224858) (xy 7.502906 -347.059758) (xy 7.181596 -347.059758)
				(arc
					(start 7.101078 -346.979494)
					(mid 6.803749 -346.547291)
					(end 7.235952 -346.84462)
				)
				(xy 7.260336 -346.869258) (xy 7.502906 -346.869258)
			)
		)
	)
	(zone
		(layer "In5.Cu")
		(hatch none 0.5)
		(connect_pads
			(clearance 0)
		)
		(min_thickness 0.25)
		(keepout
			(tracks not_allowed)
			(vias allowed)
			(pads allowed)
			(copperpour not_allowed)
			(footprints allowed)
		)
		(placement
			(enabled no)
			(sheetname "")
		)
		(fill
			(thermal_gap 0.5)
			(thermal_bridge_width 0.5)
			(island_removal_mode 0)
		)
		(polygon
			(pts
				(arc
					(start 7.502906 -343.58707)
					(mid 6.992493 -343.076276)
					(end 6.481826 -343.586816)
				)
				(arc
					(start 6.481826 -344.399616)
					(mid 6.992366 -344.910156)
					(end 7.502906 -344.399616)
				)
				(xy 7.502906 -344.266266) (xy 7.260336 -344.266266)
				(arc
					(start 7.235952 -344.290904)
					(mid 6.803749 -344.588233)
					(end 7.101078 -344.15603)
				)
				(xy 7.181596 -344.075766) (xy 7.502906 -344.075766) (xy 7.502906 -343.910666) (xy 7.181596 -343.910666)
				(arc
					(start 7.101078 -343.830402)
					(mid 6.803749 -343.398199)
					(end 7.235952 -343.695528)
				)
				(xy 7.260336 -343.720166) (xy 7.502906 -343.720166)
			)
		)
	)
	(zone
		(layer "In5.Cu")
		(hatch none 0.5)
		(connect_pads
			(clearance 0)
		)
		(min_thickness 0.25)
		(keepout
			(tracks not_allowed)
			(vias allowed)
			(pads allowed)
			(copperpour not_allowed)
			(footprints allowed)
		)
		(placement
			(enabled no)
			(sheetname "")
		)
		(fill
			(thermal_gap 0.5)
			(thermal_bridge_width 0.5)
			(island_removal_mode 0)
		)
		(polygon
			(pts
				(arc
					(start 220.840554 -67.383914)
					(mid 220.330141 -66.87312)
					(end 219.819474 -67.38366)
				)
				(xy 219.819474 -67.51701) (xy 220.062044 -67.51701)
				(arc
					(start 220.086428 -67.492372)
					(mid 220.518631 -67.195043)
					(end 220.221302 -67.627246)
				)
				(xy 220.140784 -67.70751) (xy 219.819474 -67.70751) (xy 219.819474 -67.87261) (xy 220.140784 -67.87261)
				(arc
					(start 220.221302 -67.952874)
					(mid 220.518631 -68.385077)
					(end 220.086428 -68.087748)
				)
				(xy 220.062044 -68.06311) (xy 219.819474 -68.06311)
				(arc
					(start 219.819474 -68.19646)
					(mid 220.330014 -68.707)
					(end 220.840554 -68.19646)
				)
			)
		)
	)
	(zone
		(layer "In5.Cu")
		(hatch none 0.5)
		(connect_pads
			(clearance 0)
		)
		(min_thickness 0.25)
		(keepout
			(tracks not_allowed)
			(vias allowed)
			(pads allowed)
			(copperpour not_allowed)
			(footprints allowed)
		)
		(placement
			(enabled no)
			(sheetname "")
		)
		(fill
			(thermal_gap 0.5)
			(thermal_bridge_width 0.5)
			(island_removal_mode 0)
		)
		(polygon
			(pts
				(arc
					(start 7.502906 -211.13623)
					(mid 6.992493 -210.625436)
					(end 6.481826 -211.135976)
				)
				(arc
					(start 6.481826 -211.948776)
					(mid 6.992366 -212.459316)
					(end 7.502906 -211.948776)
				)
				(xy 7.502906 -211.815426) (xy 7.260336 -211.815426)
				(arc
					(start 7.235952 -211.840064)
					(mid 6.803749 -212.137393)
					(end 7.101078 -211.70519)
				)
				(xy 7.181596 -211.624926) (xy 7.502906 -211.624926) (xy 7.502906 -211.459826) (xy 7.181596 -211.459826)
				(arc
					(start 7.101078 -211.379562)
					(mid 6.803749 -210.947359)
					(end 7.235952 -211.244688)
				)
				(xy 7.260336 -211.269326) (xy 7.502906 -211.269326)
			)
		)
	)
	(zone
		(layer "In5.Cu")
		(hatch none 0.5)
		(connect_pads
			(clearance 0)
		)
		(min_thickness 0.25)
		(keepout
			(tracks not_allowed)
			(vias allowed)
			(pads allowed)
			(copperpour not_allowed)
			(footprints allowed)
		)
		(placement
			(enabled no)
			(sheetname "")
		)
		(fill
			(thermal_gap 0.5)
			(thermal_bridge_width 0.5)
			(island_removal_mode 0)
		)
		(polygon
			(pts
				(xy 7.502906 -152.888188)
				(arc
					(start 7.502906 -152.786842)
					(mid 6.992493 -152.276048)
					(end 6.481826 -152.786588)
				)
				(arc
					(start 6.481826 -153.599388)
					(mid 6.992366 -154.109928)
					(end 7.502906 -153.599388)
				)
				(xy 7.502906 -153.442924) (xy 7.40918 -153.459434) (xy 7.402322 -153.466038) (xy 7.371334 -153.466038)
				(xy 7.3406 -153.471372) (xy 7.33298 -153.466038) (xy 7.260336 -153.466038)
				(arc
					(start 7.235952 -153.490676)
					(mid 6.803749 -153.788005)
					(end 7.101078 -153.355802)
				)
				(xy 7.181596 -153.275538) (xy 7.35457 -153.275538) (xy 7.502906 -153.249376) (xy 7.502906 -153.081736)
				(xy 7.377938 -153.103834) (xy 7.37108 -153.110438) (xy 7.340092 -153.110438) (xy 7.309358 -153.115772)
				(xy 7.301738 -153.110438) (xy 7.181596 -153.110438)
				(arc
					(start 7.101078 -153.030174)
					(mid 6.803749 -152.597971)
					(end 7.235952 -152.8953)
				)
				(xy 7.260336 -152.919938) (xy 7.323328 -152.919938)
			)
		)
	)
	(zone
		(layer "In5.Cu")
		(hatch none 0.5)
		(connect_pads
			(clearance 0)
		)
		(min_thickness 0.25)
		(keepout
			(tracks not_allowed)
			(vias allowed)
			(pads allowed)
			(copperpour not_allowed)
			(footprints allowed)
		)
		(placement
			(enabled no)
			(sheetname "")
		)
		(fill
			(thermal_gap 0.5)
			(thermal_bridge_width 0.5)
			(island_removal_mode 0)
		)
		(polygon
			(pts
				(arc
					(start 27.18054 -433.00396)
					(mid 26.670127 -432.493166)
					(end 26.15946 -433.003706)
				)
				(arc
					(start 26.15946 -433.816506)
					(mid 26.67 -434.327046)
					(end 27.18054 -433.816506)
				)
				(xy 27.18054 -433.682902) (xy 26.938224 -433.682902)
				(arc
					(start 26.913586 -433.707794)
					(mid 26.481383 -434.005123)
					(end 26.778712 -433.57292)
				)
				(xy 26.859484 -433.492402) (xy 27.18054 -433.492402) (xy 27.18054 -433.327302) (xy 26.858976 -433.327302)
				(arc
					(start 26.778712 -433.247292)
					(mid 26.481383 -432.815089)
					(end 26.913586 -433.112418)
				)
				(xy 26.937716 -433.136802) (xy 27.18054 -433.136802)
			)
		)
	)
	(zone
		(layer "In5.Cu")
		(hatch none 0.5)
		(connect_pads
			(clearance 0)
		)
		(min_thickness 0.25)
		(keepout
			(tracks not_allowed)
			(vias allowed)
			(pads allowed)
			(copperpour not_allowed)
			(footprints allowed)
		)
		(placement
			(enabled no)
			(sheetname "")
		)
		(fill
			(thermal_gap 0.5)
			(thermal_bridge_width 0.5)
			(island_removal_mode 0)
		)
		(polygon
			(pts
				(xy 7.502906 -178.48834)
				(arc
					(start 7.502906 -178.386994)
					(mid 6.992493 -177.8762)
					(end 6.481826 -178.38674)
				)
				(arc
					(start 6.481826 -179.19954)
					(mid 6.992366 -179.71008)
					(end 7.502906 -179.19954)
				)
				(xy 7.502906 -179.043076) (xy 7.40918 -179.059586) (xy 7.402322 -179.06619) (xy 7.371334 -179.06619)
				(xy 7.3406 -179.071524) (xy 7.33298 -179.06619) (xy 7.260336 -179.06619)
				(arc
					(start 7.235952 -179.090828)
					(mid 6.803749 -179.388157)
					(end 7.101078 -178.955954)
				)
				(xy 7.181596 -178.87569) (xy 7.35457 -178.87569) (xy 7.502906 -178.849528) (xy 7.502906 -178.681888)
				(xy 7.377938 -178.703986) (xy 7.37108 -178.71059) (xy 7.340092 -178.71059) (xy 7.309358 -178.715924)
				(xy 7.301738 -178.71059) (xy 7.181596 -178.71059)
				(arc
					(start 7.101078 -178.630326)
					(mid 6.803749 -178.198123)
					(end 7.235952 -178.495452)
				)
				(xy 7.260336 -178.52009) (xy 7.323328 -178.52009)
			)
		)
	)
	(zone
		(layer "In5.Cu")
		(hatch none 0.5)
		(connect_pads
			(clearance 0)
		)
		(min_thickness 0.25)
		(keepout
			(tracks not_allowed)
			(vias allowed)
			(pads allowed)
			(copperpour not_allowed)
			(footprints allowed)
		)
		(placement
			(enabled no)
			(sheetname "")
		)
		(fill
			(thermal_gap 0.5)
			(thermal_bridge_width 0.5)
			(island_removal_mode 0)
		)
		(polygon
			(pts
				(arc
					(start 7.502906 -181.536086)
					(mid 6.992493 -181.025292)
					(end 6.481826 -181.535832)
				)
				(arc
					(start 6.481826 -182.348632)
					(mid 6.992366 -182.859172)
					(end 7.502906 -182.348632)
				)
				(xy 7.502906 -182.215282) (xy 7.260336 -182.215282)
				(arc
					(start 7.235952 -182.23992)
					(mid 6.803749 -182.537249)
					(end 7.101078 -182.105046)
				)
				(xy 7.181596 -182.024782) (xy 7.502906 -182.024782) (xy 7.502906 -181.859682) (xy 7.181596 -181.859682)
				(arc
					(start 7.101078 -181.779418)
					(mid 6.803749 -181.347215)
					(end 7.235952 -181.644544)
				)
				(xy 7.260336 -181.669182) (xy 7.502906 -181.669182)
			)
		)
	)
	(zone
		(layer "In5.Cu")
		(hatch none 0.5)
		(connect_pads
			(clearance 0)
		)
		(min_thickness 0.25)
		(keepout
			(tracks not_allowed)
			(vias allowed)
			(pads allowed)
			(copperpour not_allowed)
			(footprints allowed)
		)
		(placement
			(enabled no)
			(sheetname "")
		)
		(fill
			(thermal_gap 0.5)
			(thermal_bridge_width 0.5)
			(island_removal_mode 0)
		)
		(polygon
			(pts
				(arc
					(start 7.502906 -192.736216)
					(mid 6.992493 -192.225422)
					(end 6.481826 -192.735962)
				)
				(arc
					(start 6.481826 -193.548762)
					(mid 6.992366 -194.059302)
					(end 7.502906 -193.548762)
				)
				(xy 7.502906 -193.415412) (xy 7.260336 -193.415412)
				(arc
					(start 7.235952 -193.44005)
					(mid 6.803749 -193.737379)
					(end 7.101078 -193.305176)
				)
				(xy 7.181596 -193.224912) (xy 7.502906 -193.224912) (xy 7.502906 -193.059812) (xy 7.181596 -193.059812)
				(arc
					(start 7.101078 -192.979548)
					(mid 6.803749 -192.547345)
					(end 7.235952 -192.844674)
				)
				(xy 7.260336 -192.869312) (xy 7.502906 -192.869312)
			)
		)
	)
	(zone
		(layer "In5.Cu")
		(hatch none 0.5)
		(connect_pads
			(clearance 0)
		)
		(min_thickness 0.25)
		(keepout
			(tracks not_allowed)
			(vias allowed)
			(pads allowed)
			(copperpour not_allowed)
			(footprints allowed)
		)
		(placement
			(enabled no)
			(sheetname "")
		)
		(fill
			(thermal_gap 0.5)
			(thermal_bridge_width 0.5)
			(island_removal_mode 0)
		)
		(polygon
			(pts
				(arc
					(start 220.840554 -157.583886)
					(mid 220.330141 -157.073092)
					(end 219.819474 -157.583632)
				)
				(xy 219.819474 -157.717236) (xy 220.06179 -157.717236)
				(arc
					(start 220.086428 -157.692344)
					(mid 220.518631 -157.395015)
					(end 220.221302 -157.827218)
				)
				(xy 220.14053 -157.907736) (xy 219.819474 -157.907736) (xy 219.819474 -158.072836) (xy 220.141038 -158.072836)
				(arc
					(start 220.221302 -158.152846)
					(mid 220.518631 -158.585049)
					(end 220.086428 -158.28772)
				)
				(xy 220.062298 -158.263336) (xy 219.819474 -158.263336)
				(arc
					(start 219.819474 -158.396432)
					(mid 220.330014 -158.906972)
					(end 220.840554 -158.396432)
				)
			)
		)
	)
	(zone
		(layer "In5.Cu")
		(hatch none 0.5)
		(connect_pads
			(clearance 0)
		)
		(min_thickness 0.25)
		(keepout
			(tracks not_allowed)
			(vias allowed)
			(pads allowed)
			(copperpour not_allowed)
			(footprints allowed)
		)
		(placement
			(enabled no)
			(sheetname "")
		)
		(fill
			(thermal_gap 0.5)
			(thermal_bridge_width 0.5)
			(island_removal_mode 0)
		)
		(polygon
			(pts
				(arc
					(start 220.840554 -466.58403)
					(mid 220.330141 -466.073236)
					(end 219.819474 -466.583776)
				)
				(xy 219.819474 -466.71738) (xy 220.06179 -466.71738)
				(arc
					(start 220.086428 -466.692488)
					(mid 220.518631 -466.395159)
					(end 220.221302 -466.827362)
				)
				(xy 220.14053 -466.90788) (xy 219.819474 -466.90788) (xy 219.819474 -467.07298) (xy 220.141038 -467.07298)
				(arc
					(start 220.221302 -467.15299)
					(mid 220.518631 -467.585193)
					(end 220.086428 -467.287864)
				)
				(xy 220.062298 -467.26348) (xy 219.819474 -467.26348)
				(arc
					(start 219.819474 -467.396576)
					(mid 220.330014 -467.907116)
					(end 220.840554 -467.396576)
				)
			)
		)
	)
	(zone
		(layer "In5.Cu")
		(hatch none 0.5)
		(connect_pads
			(clearance 0)
		)
		(min_thickness 0.25)
		(keepout
			(tracks not_allowed)
			(vias allowed)
			(pads allowed)
			(copperpour not_allowed)
			(footprints allowed)
		)
		(placement
			(enabled no)
			(sheetname "")
		)
		(fill
			(thermal_gap 0.5)
			(thermal_bridge_width 0.5)
			(island_removal_mode 0)
		)
		(polygon
			(pts
				(arc
					(start 7.502906 -349.9358)
					(mid 6.992366 -349.42526)
					(end 6.481826 -349.9358)
				)
				(arc
					(start 6.481826 -350.748346)
					(mid 6.992239 -351.25914)
					(end 7.502906 -350.7486)
				)
				(xy 7.502906 -350.61525) (xy 7.260336 -350.61525)
				(arc
					(start 7.235952 -350.639888)
					(mid 6.803749 -350.937217)
					(end 7.101078 -350.505014)
				)
				(xy 7.181596 -350.42475) (xy 7.502906 -350.42475) (xy 7.502906 -350.25965) (xy 7.181596 -350.25965)
				(arc
					(start 7.101078 -350.179386)
					(mid 6.803749 -349.747183)
					(end 7.235952 -350.044512)
				)
				(xy 7.260336 -350.06915) (xy 7.502906 -350.06915)
			)
		)
	)
	(zone
		(layer "In5.Cu")
		(hatch none 0.5)
		(connect_pads
			(clearance 0)
		)
		(min_thickness 0.25)
		(keepout
			(tracks not_allowed)
			(vias allowed)
			(pads allowed)
			(copperpour not_allowed)
			(footprints allowed)
		)
		(placement
			(enabled no)
			(sheetname "")
		)
		(fill
			(thermal_gap 0.5)
			(thermal_bridge_width 0.5)
			(island_removal_mode 0)
		)
		(polygon
			(pts
				(arc
					(start 7.502906 -318.735964)
					(mid 6.992366 -318.225424)
					(end 6.481826 -318.735964)
				)
				(arc
					(start 6.481826 -319.54851)
					(mid 6.992239 -320.059304)
					(end 7.502906 -319.548764)
				)
				(xy 7.502906 -319.415414) (xy 7.260336 -319.415414)
				(arc
					(start 7.235952 -319.440052)
					(mid 6.803749 -319.737381)
					(end 7.101078 -319.305178)
				)
				(xy 7.181596 -319.224914) (xy 7.502906 -319.224914) (xy 7.502906 -319.059814) (xy 7.181596 -319.059814)
				(arc
					(start 7.101078 -318.97955)
					(mid 6.803749 -318.547347)
					(end 7.235952 -318.844676)
				)
				(xy 7.260336 -318.869314) (xy 7.502906 -318.869314)
			)
		)
	)
	(zone
		(layer "In5.Cu")
		(hatch none 0.5)
		(connect_pads
			(clearance 0)
		)
		(min_thickness 0.25)
		(keepout
			(tracks not_allowed)
			(vias allowed)
			(pads allowed)
			(copperpour not_allowed)
			(footprints allowed)
		)
		(placement
			(enabled no)
			(sheetname "")
		)
		(fill
			(thermal_gap 0.5)
			(thermal_bridge_width 0.5)
			(island_removal_mode 0)
		)
		(polygon
			(pts
				(arc
					(start 7.502906 -387.135878)
					(mid 6.992493 -386.625084)
					(end 6.481826 -387.135624)
				)
				(arc
					(start 6.481826 -387.948424)
					(mid 6.992366 -388.458964)
					(end 7.502906 -387.948424)
				)
				(xy 7.502906 -387.815074) (xy 7.260336 -387.815074)
				(arc
					(start 7.235952 -387.839712)
					(mid 6.803749 -388.137041)
					(end 7.101078 -387.704838)
				)
				(xy 7.181596 -387.624574) (xy 7.502906 -387.624574) (xy 7.502906 -387.459474) (xy 7.181596 -387.459474)
				(arc
					(start 7.101078 -387.37921)
					(mid 6.803749 -386.947007)
					(end 7.235952 -387.244336)
				)
				(xy 7.260336 -387.268974) (xy 7.502906 -387.268974)
			)
		)
	)
	(zone
		(layer "In5.Cu")
		(hatch none 0.5)
		(connect_pads
			(clearance 0)
		)
		(min_thickness 0.25)
		(keepout
			(tracks not_allowed)
			(vias allowed)
			(pads allowed)
			(copperpour not_allowed)
			(footprints allowed)
		)
		(placement
			(enabled no)
			(sheetname "")
		)
		(fill
			(thermal_gap 0.5)
			(thermal_bridge_width 0.5)
			(island_removal_mode 0)
		)
		(polygon
			(pts
				(arc
					(start 27.18054 -428.203868)
					(mid 26.670127 -427.693074)
					(end 26.15946 -428.203614)
				)
				(arc
					(start 26.15946 -429.016414)
					(mid 26.67 -429.526954)
					(end 27.18054 -429.016414)
				)
				(xy 27.18054 -428.88281) (xy 26.938224 -428.88281)
				(arc
					(start 26.913586 -428.907702)
					(mid 26.481383 -429.205031)
					(end 26.778712 -428.772828)
				)
				(xy 26.859484 -428.69231) (xy 27.18054 -428.69231) (xy 27.18054 -428.52721) (xy 26.858976 -428.52721)
				(arc
					(start 26.778712 -428.4472)
					(mid 26.481383 -428.014997)
					(end 26.913586 -428.312326)
				)
				(xy 26.937716 -428.33671) (xy 27.18054 -428.33671)
			)
		)
	)
	(zone
		(layer "In5.Cu")
		(hatch none 0.5)
		(connect_pads
			(clearance 0)
		)
		(min_thickness 0.25)
		(keepout
			(tracks not_allowed)
			(vias allowed)
			(pads allowed)
			(copperpour not_allowed)
			(footprints allowed)
		)
		(placement
			(enabled no)
			(sheetname "")
		)
		(fill
			(thermal_gap 0.5)
			(thermal_bridge_width 0.5)
			(island_removal_mode 0)
		)
		(polygon
			(pts
				(arc
					(start 35.84067 -179.983892)
					(mid 35.330257 -179.473098)
					(end 34.81959 -179.983638)
				)
				(xy 34.81959 -180.117242) (xy 35.061906 -180.117242)
				(arc
					(start 35.086544 -180.09235)
					(mid 35.518747 -179.795021)
					(end 35.221418 -180.227224)
				)
				(xy 35.140646 -180.307742) (xy 34.81959 -180.307742) (xy 34.81959 -180.472842) (xy 35.141154 -180.472842)
				(arc
					(start 35.221418 -180.552852)
					(mid 35.518747 -180.985055)
					(end 35.086544 -180.687726)
				)
				(xy 35.062414 -180.663342) (xy 34.81959 -180.663342)
				(arc
					(start 34.81959 -180.796438)
					(mid 35.33013 -181.306978)
					(end 35.84067 -180.796438)
				)
			)
		)
	)
	(zone
		(layer "In5.Cu")
		(hatch none 0.5)
		(connect_pads
			(clearance 0)
		)
		(min_thickness 0.25)
		(keepout
			(tracks not_allowed)
			(vias allowed)
			(pads allowed)
			(copperpour not_allowed)
			(footprints allowed)
		)
		(placement
			(enabled no)
			(sheetname "")
		)
		(fill
			(thermal_gap 0.5)
			(thermal_bridge_width 0.5)
			(island_removal_mode 0)
		)
		(polygon
			(pts
				(arc
					(start 220.840554 -76.983844)
					(mid 220.330141 -76.47305)
					(end 219.819474 -76.98359)
				)
				(xy 219.819474 -77.117194) (xy 220.06179 -77.117194)
				(arc
					(start 220.086428 -77.092302)
					(mid 220.518631 -76.794973)
					(end 220.221302 -77.227176)
				)
				(xy 220.14053 -77.307694) (xy 219.819474 -77.307694) (xy 219.819474 -77.472794) (xy 220.141038 -77.472794)
				(arc
					(start 220.221302 -77.552804)
					(mid 220.518631 -77.985007)
					(end 220.086428 -77.687678)
				)
				(xy 220.062298 -77.663294) (xy 219.819474 -77.663294)
				(arc
					(start 219.819474 -77.79639)
					(mid 220.330014 -78.30693)
					(end 220.840554 -77.79639)
				)
			)
		)
	)
	(zone
		(layer "In5.Cu")
		(hatch none 0.5)
		(connect_pads
			(clearance 0)
		)
		(min_thickness 0.25)
		(keepout
			(tracks not_allowed)
			(vias allowed)
			(pads allowed)
			(copperpour not_allowed)
			(footprints allowed)
		)
		(placement
			(enabled no)
			(sheetname "")
		)
		(fill
			(thermal_gap 0.5)
			(thermal_bridge_width 0.5)
			(island_removal_mode 0)
		)
		(polygon
			(pts
				(arc
					(start 220.840554 -175.1838)
					(mid 220.330141 -174.673006)
					(end 219.819474 -175.183546)
				)
				(xy 219.819474 -175.31715) (xy 220.06179 -175.31715)
				(arc
					(start 220.086428 -175.292258)
					(mid 220.518631 -174.994929)
					(end 220.221302 -175.427132)
				)
				(xy 220.14053 -175.50765) (xy 219.819474 -175.50765) (xy 219.819474 -175.67275) (xy 220.141038 -175.67275)
				(arc
					(start 220.221302 -175.75276)
					(mid 220.518631 -176.184963)
					(end 220.086428 -175.887634)
				)
				(xy 220.062298 -175.86325) (xy 219.819474 -175.86325)
				(arc
					(start 219.819474 -175.996346)
					(mid 220.330014 -176.506886)
					(end 220.840554 -175.996346)
				)
			)
		)
	)
	(zone
		(layer "In5.Cu")
		(hatch none 0.5)
		(connect_pads
			(clearance 0)
		)
		(min_thickness 0.25)
		(keepout
			(tracks not_allowed)
			(vias allowed)
			(pads allowed)
			(copperpour not_allowed)
			(footprints allowed)
		)
		(placement
			(enabled no)
			(sheetname "")
		)
		(fill
			(thermal_gap 0.5)
			(thermal_bridge_width 0.5)
			(island_removal_mode 0)
		)
		(polygon
			(pts
				(arc
					(start 27.18054 -141.603476)
					(mid 26.67 -141.092936)
					(end 26.15946 -141.603476)
				)
				(arc
					(start 26.15946 -142.416022)
					(mid 26.669873 -142.926816)
					(end 27.18054 -142.416276)
				)
				(xy 27.18054 -142.282672) (xy 26.938224 -142.282672)
				(arc
					(start 26.913586 -142.307564)
					(mid 26.481383 -142.604893)
					(end 26.778712 -142.17269)
				)
				(xy 26.859484 -142.092172) (xy 27.18054 -142.092172) (xy 27.18054 -141.927072) (xy 26.858976 -141.927072)
				(arc
					(start 26.778712 -141.847062)
					(mid 26.481383 -141.414859)
					(end 26.913586 -141.712188)
				)
				(xy 26.937716 -141.736572) (xy 27.18054 -141.736572)
			)
		)
	)
	(zone
		(layer "In5.Cu")
		(hatch none 0.5)
		(connect_pads
			(clearance 0)
		)
		(min_thickness 0.25)
		(keepout
			(tracks not_allowed)
			(vias allowed)
			(pads allowed)
			(copperpour not_allowed)
			(footprints allowed)
		)
		(placement
			(enabled no)
			(sheetname "")
		)
		(fill
			(thermal_gap 0.5)
			(thermal_bridge_width 0.5)
			(island_removal_mode 0)
		)
		(polygon
			(pts
				(arc
					(start 7.502906 -301.135796)
					(mid 6.992366 -300.625256)
					(end 6.481826 -301.135796)
				)
				(arc
					(start 6.481826 -301.948342)
					(mid 6.992239 -302.459136)
					(end 7.502906 -301.948596)
				)
				(xy 7.502906 -301.815246) (xy 7.260336 -301.815246)
				(arc
					(start 7.235952 -301.839884)
					(mid 6.803749 -302.137213)
					(end 7.101078 -301.70501)
				)
				(xy 7.181596 -301.624746) (xy 7.502906 -301.624746) (xy 7.502906 -301.459646) (xy 7.181596 -301.459646)
				(arc
					(start 7.101078 -301.379382)
					(mid 6.803749 -300.947179)
					(end 7.235952 -301.244508)
				)
				(xy 7.260336 -301.269146) (xy 7.502906 -301.269146)
			)
		)
	)
	(zone
		(layer "In5.Cu")
		(hatch none 0.5)
		(connect_pads
			(clearance 0)
		)
		(min_thickness 0.25)
		(keepout
			(tracks not_allowed)
			(vias allowed)
			(pads allowed)
			(copperpour not_allowed)
			(footprints allowed)
		)
		(placement
			(enabled no)
			(sheetname "")
		)
		(fill
			(thermal_gap 0.5)
			(thermal_bridge_width 0.5)
			(island_removal_mode 0)
		)
		(polygon
			(pts
				(arc
					(start 35.84067 -376.384058)
					(mid 35.330257 -375.873264)
					(end 34.81959 -376.383804)
				)
				(xy 34.81959 -376.517154) (xy 35.06216 -376.517154)
				(arc
					(start 35.086544 -376.492516)
					(mid 35.518747 -376.195187)
					(end 35.221418 -376.62739)
				)
				(xy 35.1409 -376.707654) (xy 34.81959 -376.707654) (xy 34.81959 -376.872754) (xy 35.1409 -376.872754)
				(arc
					(start 35.221418 -376.953018)
					(mid 35.518747 -377.385221)
					(end 35.086544 -377.087892)
				)
				(xy 35.06216 -377.063254) (xy 34.81959 -377.063254)
				(arc
					(start 34.81959 -377.196604)
					(mid 35.33013 -377.707144)
					(end 35.84067 -377.196604)
				)
			)
		)
	)
	(zone
		(layer "In5.Cu")
		(hatch none 0.5)
		(connect_pads
			(clearance 0)
		)
		(min_thickness 0.25)
		(keepout
			(tracks not_allowed)
			(vias allowed)
			(pads allowed)
			(copperpour not_allowed)
			(footprints allowed)
		)
		(placement
			(enabled no)
			(sheetname "")
		)
		(fill
			(thermal_gap 0.5)
			(thermal_bridge_width 0.5)
			(island_removal_mode 0)
		)
		(polygon
			(pts
				(arc
					(start 27.18054 -231.803448)
					(mid 26.67 -231.292908)
					(end 26.15946 -231.803448)
				)
				(arc
					(start 26.15946 -232.615994)
					(mid 26.669873 -233.126788)
					(end 27.18054 -232.616248)
				)
				(xy 27.18054 -232.482898) (xy 26.93797 -232.482898)
				(arc
					(start 26.913586 -232.507536)
					(mid 26.481383 -232.804865)
					(end 26.778712 -232.372662)
				)
				(xy 26.85923 -232.292398) (xy 27.18054 -232.292398) (xy 27.18054 -232.127298) (xy 26.85923 -232.127298)
				(arc
					(start 26.778712 -232.047034)
					(mid 26.481383 -231.614831)
					(end 26.913586 -231.91216)
				)
				(xy 26.93797 -231.936798) (xy 27.18054 -231.936798)
			)
		)
	)
	(zone
		(layer "In5.Cu")
		(hatch none 0.5)
		(connect_pads
			(clearance 0)
		)
		(min_thickness 0.25)
		(keepout
			(tracks not_allowed)
			(vias allowed)
			(pads allowed)
			(copperpour not_allowed)
			(footprints allowed)
		)
		(placement
			(enabled no)
			(sheetname "")
		)
		(fill
			(thermal_gap 0.5)
			(thermal_bridge_width 0.5)
			(island_removal_mode 0)
		)
		(polygon
			(pts
				(arc
					(start 27.18054 -244.603524)
					(mid 26.67 -244.092984)
					(end 26.15946 -244.603524)
				)
				(arc
					(start 26.15946 -245.41607)
					(mid 26.669873 -245.926864)
					(end 27.18054 -245.416324)
				)
				(xy 27.18054 -245.28272) (xy 26.938224 -245.28272)
				(arc
					(start 26.913586 -245.307612)
					(mid 26.481383 -245.604941)
					(end 26.778712 -245.172738)
				)
				(xy 26.859484 -245.09222) (xy 27.18054 -245.09222) (xy 27.18054 -244.92712) (xy 26.858976 -244.92712)
				(arc
					(start 26.778712 -244.84711)
					(mid 26.481383 -244.414907)
					(end 26.913586 -244.712236)
				)
				(xy 26.937716 -244.73662) (xy 27.18054 -244.73662)
			)
		)
	)
	(zone
		(layer "In5.Cu")
		(hatch none 0.5)
		(connect_pads
			(clearance 0)
		)
		(min_thickness 0.25)
		(keepout
			(tracks not_allowed)
			(vias allowed)
			(pads allowed)
			(copperpour not_allowed)
			(footprints allowed)
		)
		(placement
			(enabled no)
			(sheetname "")
		)
		(fill
			(thermal_gap 0.5)
			(thermal_bridge_width 0.5)
			(island_removal_mode 0)
		)
		(polygon
			(pts
				(arc
					(start 7.502906 -411.935676)
					(mid 6.992366 -411.425136)
					(end 6.481826 -411.935676)
				)
				(arc
					(start 6.481826 -412.748222)
					(mid 6.992239 -413.259016)
					(end 7.502906 -412.748476)
				)
				(xy 7.502906 -412.615126) (xy 7.260336 -412.615126)
				(arc
					(start 7.235952 -412.639764)
					(mid 6.803749 -412.937093)
					(end 7.101078 -412.50489)
				)
				(xy 7.181596 -412.424626) (xy 7.502906 -412.424626) (xy 7.502906 -412.259526) (xy 7.181596 -412.259526)
				(arc
					(start 7.101078 -412.179262)
					(mid 6.803749 -411.747059)
					(end 7.235952 -412.044388)
				)
				(xy 7.260336 -412.069026) (xy 7.502906 -412.069026)
			)
		)
	)
	(zone
		(net "GND")
		(layer "In5.Cu")
		(hatch none 0.5)
		(connect_pads
			(clearance 0.5)
		)
		(min_thickness 0.25)
		(fill yes
			(thermal_gap 0.5)
			(thermal_bridge_width 0.5)
			(island_removal_mode 0)
		)
		(polygon
			(pts
				(arc
					(start 0.999998 -0.763016)
					(mid 0.832426 -0.832426)
					(end 0.763016 -0.999998)
				)
				(xy 0.763016 -186.379104)
				(arc
					(start 4.299966 -186.379104)
					(mid 6.262878 -188.342016)
					(end 4.299966 -190.304928)
				)
				(xy 0.763016 -190.304928) (xy 0.763016 -312.379106)
				(arc
					(start 4.299966 -312.379106)
					(mid 6.262878 -314.342018)
					(end 4.299966 -316.30493)
				)
				(xy 0.763016 -316.30493) (xy 0.763016 -418.378894)
				(arc
					(start 4.299966 -418.378894)
					(mid 6.263132 -420.34206)
					(end 4.299966 -422.304972)
				)
				(xy 0.763016 -422.304972)
				(arc
					(start 0.763016 -505.000006)
					(mid 0.832426 -505.167578)
					(end 0.999998 -505.236988)
				)
				(arc
					(start 262.50011 -505.236988)
					(mid 262.667682 -505.167578)
					(end 262.737092 -505.000006)
				)
				(xy 262.737092 -428.396146) (xy 262.18388 -427.842934)
				(arc
					(start 261.2898 -427.842934)
					(mid 259.702077 -427.277753)
					(end 259.136896 -425.69003)
				)
				(xy 259.136896 -411.80131) (xy 258.583684 -411.248098)
				(arc
					(start 252.394974 -411.248098)
					(mid 251.097034 -409.950158)
					(end 252.394974 -408.651964)
				)
				(xy 258.583684 -408.651964) (xy 259.136896 -408.098752)
				(arc
					(start 259.136896 -364.309914)
					(mid 259.693836 -362.71395)
					(end 261.2898 -362.15701)
				)
				(xy 262.18388 -362.15701) (xy 262.737092 -361.603798) (xy 262.737092 -185.17362) (xy 261.468108 -185.17362)
				(xy 261.468108 -360.888026)
				(arc
					(start 261.2898 -360.888026)
					(mid 258.870234 -361.890348)
					(end 257.867912 -364.309914)
				)
				(xy 257.867912 -407.38298)
				(arc
					(start 252.394974 -407.38298)
					(mid 249.827796 -409.950158)
					(end 252.394974 -412.517082)
				)
				(xy 257.867912 -412.517082)
				(arc
					(start 257.867912 -425.69003)
					(mid 258.87016 -428.10967)
					(end 261.2898 -429.111918)
				)
				(xy 261.468108 -429.111918) (xy 261.468108 -503.968004) (xy 2.032 -503.968004) (xy 2.032 -477.969834)
				(xy 1.479296 -477.41713) (xy 1.479296 -477.045274) (xy 2.032 -476.49257) (xy 2.032 -472.088464)
				(xy 1.446784 -471.503248) (xy 1.446784 -466.82279) (xy 2.032 -466.237574) (xy 2.032 -462.82102)
				(xy 3.16357 -461.68945) (xy 3.486658 -461.68945) (xy 3.569208 -461.772) (xy 6.59638 -461.772) (xy 7.507732 -460.860648)
				(xy 9.877298 -460.860648) (xy 10.217658 -460.520288) (xy 10.217658 -458.331062) (xy 4.572 -452.685404)
				(arc
					(start 4.572 -423.562526)
					(mid 7.531901 -420.342049)
					(end 4.572 -417.12134)
				)
				(arc
					(start 4.572 -317.562484)
					(mid 7.532134 -314.342018)
					(end 4.572 -311.121552)
				)
				(xy 4.572 -276.479) (xy 2.032 -273.939) (xy 2.032 -237.236) (xy 4.572 -234.696)
				(arc
					(start 4.572 -191.562482)
					(mid 7.526625 -188.526615)
					(end 4.937506 -185.17362)
				)
				(xy 4.572 -185.17362) (xy 4.572 -149.479) (xy 2.032 -146.939) (xy 2.032 -2.032) (xy 261.468108 -2.032)
				(xy 261.468108 -185.04662) (xy 262.737092 -185.04662)
				(arc
					(start 262.737092 -0.999998)
					(mid 262.667682 -0.832426)
					(end 262.50011 -0.763016)
				)
			)
		)
	)
	(zone
		(layer "In5.Cu")
		(hatch none 0.5)
		(connect_pads
			(clearance 0)
		)
		(min_thickness 0.25)
		(keepout
			(tracks not_allowed)
			(vias allowed)
			(pads allowed)
			(copperpour not_allowed)
			(footprints allowed)
		)
		(placement
			(enabled no)
			(sheetname "")
		)
		(fill
			(thermal_gap 0.5)
			(thermal_bridge_width 0.5)
			(island_removal_mode 0)
		)
		(polygon
			(pts
				(arc
					(start 220.840554 -179.983892)
					(mid 220.330141 -179.473098)
					(end 219.819474 -179.983638)
				)
				(xy 219.819474 -180.117242) (xy 220.06179 -180.117242)
				(arc
					(start 220.086428 -180.09235)
					(mid 220.518631 -179.795021)
					(end 220.221302 -180.227224)
				)
				(xy 220.14053 -180.307742) (xy 219.819474 -180.307742) (xy 219.819474 -180.472842) (xy 220.141038 -180.472842)
				(arc
					(start 220.221302 -180.552852)
					(mid 220.518631 -180.985055)
					(end 220.086428 -180.687726)
				)
				(xy 220.062298 -180.663342) (xy 219.819474 -180.663342)
				(arc
					(start 219.819474 -180.796438)
					(mid 220.330014 -181.306978)
					(end 220.840554 -180.796438)
				)
			)
		)
	)
	(zone
		(layer "In5.Cu")
		(hatch none 0.5)
		(connect_pads
			(clearance 0)
		)
		(min_thickness 0.25)
		(keepout
			(tracks not_allowed)
			(vias allowed)
			(pads allowed)
			(copperpour not_allowed)
			(footprints allowed)
		)
		(placement
			(enabled no)
			(sheetname "")
		)
		(fill
			(thermal_gap 0.5)
			(thermal_bridge_width 0.5)
			(island_removal_mode 0)
		)
		(polygon
			(pts
				(arc
					(start 35.84067 -381.183896)
					(mid 35.330257 -380.673102)
					(end 34.81959 -381.183642)
				)
				(xy 34.81959 -381.317246) (xy 35.061906 -381.317246)
				(arc
					(start 35.086544 -381.292354)
					(mid 35.518747 -380.995025)
					(end 35.221418 -381.427228)
				)
				(xy 35.140646 -381.507746) (xy 34.81959 -381.507746) (xy 34.81959 -381.672846) (xy 35.141154 -381.672846)
				(arc
					(start 35.221418 -381.752856)
					(mid 35.518747 -382.185059)
					(end 35.086544 -381.88773)
				)
				(xy 35.062414 -381.863346) (xy 34.81959 -381.863346)
				(arc
					(start 34.81959 -381.996442)
					(mid 35.33013 -382.506982)
					(end 35.84067 -381.996442)
				)
			)
		)
	)
	(zone
		(layer "In5.Cu")
		(hatch none 0.5)
		(connect_pads
			(clearance 0)
		)
		(min_thickness 0.25)
		(keepout
			(tracks not_allowed)
			(vias allowed)
			(pads allowed)
			(copperpour not_allowed)
			(footprints allowed)
		)
		(placement
			(enabled no)
			(sheetname "")
		)
		(fill
			(thermal_gap 0.5)
			(thermal_bridge_width 0.5)
			(island_removal_mode 0)
		)
		(polygon
			(pts
				(arc
					(start 7.502906 -227.136198)
					(mid 6.992493 -226.625404)
					(end 6.481826 -227.135944)
				)
				(arc
					(start 6.481826 -227.948744)
					(mid 6.992366 -228.459284)
					(end 7.502906 -227.948744)
				)
				(xy 7.502906 -227.815394) (xy 7.260336 -227.815394)
				(arc
					(start 7.235952 -227.840032)
					(mid 6.803749 -228.137361)
					(end 7.101078 -227.705158)
				)
				(xy 7.181596 -227.624894) (xy 7.502906 -227.624894) (xy 7.502906 -227.459794) (xy 7.181596 -227.459794)
				(arc
					(start 7.101078 -227.37953)
					(mid 6.803749 -226.947327)
					(end 7.235952 -227.244656)
				)
				(xy 7.260336 -227.269294) (xy 7.502906 -227.269294)
			)
		)
	)
	(zone
		(layer "In5.Cu")
		(hatch none 0.5)
		(connect_pads
			(clearance 0)
		)
		(min_thickness 0.25)
		(keepout
			(tracks not_allowed)
			(vias allowed)
			(pads allowed)
			(copperpour not_allowed)
			(footprints allowed)
		)
		(placement
			(enabled no)
			(sheetname "")
		)
		(fill
			(thermal_gap 0.5)
			(thermal_bridge_width 0.5)
			(island_removal_mode 0)
		)
		(polygon
			(pts
				(arc
					(start 27.18054 -16.203422)
					(mid 26.67 -15.692882)
					(end 26.15946 -16.203422)
				)
				(arc
					(start 26.15946 -17.015968)
					(mid 26.669873 -17.526762)
					(end 27.18054 -17.016222)
				)
				(xy 27.18054 -16.882618) (xy 26.938224 -16.882618)
				(arc
					(start 26.913586 -16.90751)
					(mid 26.481383 -17.204839)
					(end 26.778712 -16.772636)
				)
				(xy 26.859484 -16.692118) (xy 27.18054 -16.692118) (xy 27.18054 -16.527018) (xy 26.858976 -16.527018)
				(arc
					(start 26.778712 -16.447008)
					(mid 26.481383 -16.014805)
					(end 26.913586 -16.312134)
				)
				(xy 26.937716 -16.336518) (xy 27.18054 -16.336518)
			)
		)
	)
	(zone
		(layer "In5.Cu")
		(hatch none 0.5)
		(connect_pads
			(clearance 0)
		)
		(min_thickness 0.25)
		(keepout
			(tracks not_allowed)
			(vias allowed)
			(pads allowed)
			(copperpour not_allowed)
			(footprints allowed)
		)
		(placement
			(enabled no)
			(sheetname "")
		)
		(fill
			(thermal_gap 0.5)
			(thermal_bridge_width 0.5)
			(island_removal_mode 0)
		)
		(polygon
			(pts
				(arc
					(start 220.840554 -488.984036)
					(mid 220.330141 -488.473242)
					(end 219.819474 -488.983782)
				)
				(xy 219.819474 -489.117386) (xy 220.06179 -489.117386)
				(arc
					(start 220.086428 -489.092494)
					(mid 220.518631 -488.795165)
					(end 220.221302 -489.227368)
				)
				(xy 220.14053 -489.307886) (xy 219.819474 -489.307886) (xy 219.819474 -489.472986) (xy 220.141038 -489.472986)
				(arc
					(start 220.221302 -489.552996)
					(mid 220.518631 -489.985199)
					(end 220.086428 -489.68787)
				)
				(xy 220.062298 -489.663486) (xy 219.819474 -489.663486)
				(arc
					(start 219.819474 -489.796582)
					(mid 220.330014 -490.307122)
					(end 220.840554 -489.796582)
				)
			)
		)
	)
	(zone
		(layer "In5.Cu")
		(hatch none 0.5)
		(connect_pads
			(clearance 0)
		)
		(min_thickness 0.25)
		(keepout
			(tracks not_allowed)
			(vias allowed)
			(pads allowed)
			(copperpour not_allowed)
			(footprints allowed)
		)
		(placement
			(enabled no)
			(sheetname "")
		)
		(fill
			(thermal_gap 0.5)
			(thermal_bridge_width 0.5)
			(island_removal_mode 0)
		)
		(polygon
			(pts
				(arc
					(start 220.840554 -72.183752)
					(mid 220.330141 -71.672958)
					(end 219.819474 -72.183498)
				)
				(xy 219.819474 -72.317102) (xy 220.06179 -72.317102)
				(arc
					(start 220.086428 -72.29221)
					(mid 220.518631 -71.994881)
					(end 220.221302 -72.427084)
				)
				(xy 220.14053 -72.507602) (xy 219.819474 -72.507602) (xy 219.819474 -72.672702) (xy 220.141038 -72.672702)
				(arc
					(start 220.221302 -72.752712)
					(mid 220.518631 -73.184915)
					(end 220.086428 -72.887586)
				)
				(xy 220.062298 -72.863202) (xy 219.819474 -72.863202)
				(arc
					(start 219.819474 -72.996298)
					(mid 220.330014 -73.506838)
					(end 220.840554 -72.996298)
				)
			)
		)
	)
	(zone
		(layer "In5.Cu")
		(hatch none 0.5)
		(connect_pads
			(clearance 0)
		)
		(min_thickness 0.25)
		(keepout
			(tracks not_allowed)
			(vias allowed)
			(pads allowed)
			(copperpour not_allowed)
			(footprints allowed)
		)
		(placement
			(enabled no)
			(sheetname "")
		)
		(fill
			(thermal_gap 0.5)
			(thermal_bridge_width 0.5)
			(island_removal_mode 0)
		)
		(polygon
			(pts
				(arc
					(start 27.18054 -347.603572)
					(mid 26.67 -347.093032)
					(end 26.15946 -347.603572)
				)
				(arc
					(start 26.15946 -348.416118)
					(mid 26.669873 -348.926912)
					(end 27.18054 -348.416372)
				)
				(xy 27.18054 -348.282768) (xy 26.938224 -348.282768)
				(arc
					(start 26.913586 -348.30766)
					(mid 26.481383 -348.604989)
					(end 26.778712 -348.172786)
				)
				(xy 26.859484 -348.092268) (xy 27.18054 -348.092268) (xy 27.18054 -347.927168) (xy 26.858976 -347.927168)
				(arc
					(start 26.778712 -347.847158)
					(mid 26.481383 -347.414955)
					(end 26.913586 -347.712284)
				)
				(xy 26.937716 -347.736668) (xy 27.18054 -347.736668)
			)
		)
	)
	(zone
		(layer "In5.Cu")
		(hatch none 0.5)
		(connect_pads
			(clearance 0)
		)
		(min_thickness 0.25)
		(keepout
			(tracks not_allowed)
			(vias allowed)
			(pads allowed)
			(copperpour not_allowed)
			(footprints allowed)
		)
		(placement
			(enabled no)
			(sheetname "")
		)
		(fill
			(thermal_gap 0.5)
			(thermal_bridge_width 0.5)
			(island_removal_mode 0)
		)
		(polygon
			(pts
				(arc
					(start 7.502906 -415.136076)
					(mid 6.992493 -414.625282)
					(end 6.481826 -415.135822)
				)
				(arc
					(start 6.481826 -415.948622)
					(mid 6.992366 -416.459162)
					(end 7.502906 -415.948622)
				)
				(xy 7.502906 -415.815272) (xy 7.260336 -415.815272)
				(arc
					(start 7.235952 -415.83991)
					(mid 6.803749 -416.137239)
					(end 7.101078 -415.705036)
				)
				(xy 7.181596 -415.624772) (xy 7.502906 -415.624772) (xy 7.502906 -415.459672) (xy 7.181596 -415.459672)
				(arc
					(start 7.101078 -415.379408)
					(mid 6.803749 -414.947205)
					(end 7.235952 -415.244534)
				)
				(xy 7.260336 -415.269172) (xy 7.502906 -415.269172)
			)
		)
	)
	(zone
		(layer "In5.Cu")
		(hatch none 0.5)
		(connect_pads
			(clearance 0)
		)
		(min_thickness 0.25)
		(keepout
			(tracks not_allowed)
			(vias allowed)
			(pads allowed)
			(copperpour not_allowed)
			(footprints allowed)
		)
		(placement
			(enabled no)
			(sheetname "")
		)
		(fill
			(thermal_gap 0.5)
			(thermal_bridge_width 0.5)
			(island_removal_mode 0)
		)
		(polygon
			(pts
				(arc
					(start 35.84067 -488.983782)
					(mid 35.33013 -488.473242)
					(end 34.81959 -488.983782)
				)
				(xy 34.81959 -489.117386) (xy 35.061906 -489.117386)
				(arc
					(start 35.086544 -489.092494)
					(mid 35.518747 -488.795165)
					(end 35.221418 -489.227368)
				)
				(xy 35.140646 -489.307886) (xy 34.81959 -489.307886) (xy 34.81959 -489.472986) (xy 35.141154 -489.472986)
				(arc
					(start 35.221418 -489.552996)
					(mid 35.518747 -489.985199)
					(end 35.086544 -489.68787)
				)
				(xy 35.062414 -489.663486) (xy 34.81959 -489.663486)
				(arc
					(start 34.81959 -489.796328)
					(mid 35.330003 -490.307122)
					(end 35.84067 -489.796582)
				)
			)
		)
	)
	(zone
		(layer "In5.Cu")
		(hatch none 0.5)
		(connect_pads
			(clearance 0)
		)
		(min_thickness 0.25)
		(keepout
			(tracks not_allowed)
			(vias allowed)
			(pads allowed)
			(copperpour not_allowed)
			(footprints allowed)
		)
		(placement
			(enabled no)
			(sheetname "")
		)
		(fill
			(thermal_gap 0.5)
			(thermal_bridge_width 0.5)
			(island_removal_mode 0)
		)
		(polygon
			(pts
				(arc
					(start 7.502906 -446.384172)
					(mid 6.992366 -445.873632)
					(end 6.481826 -446.384172)
				)
				(arc
					(start 6.481826 -447.196718)
					(mid 6.992239 -447.707512)
					(end 7.502906 -447.196972)
				)
				(xy 7.502906 -447.063622) (xy 7.260336 -447.063622)
				(arc
					(start 7.235952 -447.08826)
					(mid 6.803749 -447.385589)
					(end 7.101078 -446.953386)
				)
				(xy 7.181596 -446.873122) (xy 7.502906 -446.873122) (xy 7.502906 -446.708022) (xy 7.181596 -446.708022)
				(arc
					(start 7.101078 -446.627758)
					(mid 6.803749 -446.195555)
					(end 7.235952 -446.492884)
				)
				(xy 7.260336 -446.517522) (xy 7.502906 -446.517522)
			)
		)
	)
	(zone
		(net "VDD_DIFF_4")
		(layer "In5.Cu")
		(hatch none 0.5)
		(connect_pads
			(clearance 0.5)
		)
		(min_thickness 0.25)
		(fill yes
			(thermal_gap 0.5)
			(thermal_bridge_width 0.5)
			(island_removal_mode 0)
		)
		(polygon
			(pts
				(xy 82.423 -112.522) (xy 99.314 -112.522) (xy 104.267 -107.569) (xy 104.267 -99.06) (xy 99.06 -93.853)
				(xy 81.661 -93.853) (xy 78.74 -96.774) (xy 78.74 -108.839)
			)
		)
	)
	(zone
		(layer "In5.Cu")
		(hatch none 0.5)
		(connect_pads
			(clearance 0)
		)
		(min_thickness 0.25)
		(keepout
			(tracks not_allowed)
			(vias allowed)
			(pads allowed)
			(copperpour not_allowed)
			(footprints allowed)
		)
		(placement
			(enabled no)
			(sheetname "")
		)
		(fill
			(thermal_gap 0.5)
			(thermal_bridge_width 0.5)
			(island_removal_mode 0)
		)
		(polygon
			(pts
				(arc
					(start 7.502906 -291.535866)
					(mid 6.992366 -291.025326)
					(end 6.481826 -291.535866)
				)
				(arc
					(start 6.481826 -292.348412)
					(mid 6.992239 -292.859206)
					(end 7.502906 -292.348666)
				)
				(xy 7.502906 -292.215316) (xy 7.260336 -292.215316)
				(arc
					(start 7.235952 -292.239954)
					(mid 6.803749 -292.537283)
					(end 7.101078 -292.10508)
				)
				(xy 7.181596 -292.024816) (xy 7.502906 -292.024816) (xy 7.502906 -291.859716) (xy 7.181596 -291.859716)
				(arc
					(start 7.101078 -291.779452)
					(mid 6.803749 -291.347249)
					(end 7.235952 -291.644578)
				)
				(xy 7.260336 -291.669216) (xy 7.502906 -291.669216)
			)
		)
	)
	(zone
		(layer "In5.Cu")
		(hatch none 0.5)
		(connect_pads
			(clearance 0)
		)
		(min_thickness 0.25)
		(keepout
			(tracks not_allowed)
			(vias allowed)
			(pads allowed)
			(copperpour not_allowed)
			(footprints allowed)
		)
		(placement
			(enabled no)
			(sheetname "")
		)
		(fill
			(thermal_gap 0.5)
			(thermal_bridge_width 0.5)
			(island_removal_mode 0)
		)
		(polygon
			(pts
				(arc
					(start 7.502906 -304.335942)
					(mid 6.992366 -303.825402)
					(end 6.481826 -304.335942)
				)
				(arc
					(start 6.481826 -305.148488)
					(mid 6.992239 -305.659282)
					(end 7.502906 -305.148742)
				)
				(xy 7.502906 -305.015392) (xy 7.260336 -305.015392)
				(arc
					(start 7.235952 -305.04003)
					(mid 6.803749 -305.337359)
					(end 7.101078 -304.905156)
				)
				(xy 7.181596 -304.824892) (xy 7.502906 -304.824892) (xy 7.502906 -304.659792) (xy 7.181596 -304.659792)
				(arc
					(start 7.101078 -304.579528)
					(mid 6.803749 -304.147325)
					(end 7.235952 -304.444654)
				)
				(xy 7.260336 -304.469292) (xy 7.502906 -304.469292)
			)
		)
	)
	(zone
		(layer "In5.Cu")
		(hatch none 0.5)
		(connect_pads
			(clearance 0)
		)
		(min_thickness 0.25)
		(keepout
			(tracks not_allowed)
			(vias allowed)
			(pads allowed)
			(copperpour not_allowed)
			(footprints allowed)
		)
		(placement
			(enabled no)
			(sheetname "")
		)
		(fill
			(thermal_gap 0.5)
			(thermal_bridge_width 0.5)
			(island_removal_mode 0)
		)
		(polygon
			(pts
				(arc
					(start 220.840554 -282.98394)
					(mid 220.330141 -282.473146)
					(end 219.819474 -282.983686)
				)
				(xy 219.819474 -283.11729) (xy 220.06179 -283.11729)
				(arc
					(start 220.086428 -283.092398)
					(mid 220.518631 -282.795069)
					(end 220.221302 -283.227272)
				)
				(xy 220.14053 -283.30779) (xy 219.819474 -283.30779) (xy 219.819474 -283.47289) (xy 220.141038 -283.47289)
				(arc
					(start 220.221302 -283.5529)
					(mid 220.518631 -283.985103)
					(end 220.086428 -283.687774)
				)
				(xy 220.062298 -283.66339) (xy 219.819474 -283.66339)
				(arc
					(start 219.819474 -283.796486)
					(mid 220.330014 -284.307026)
					(end 220.840554 -283.796486)
				)
			)
		)
	)
	(zone
		(layer "In5.Cu")
		(hatch none 0.5)
		(connect_pads
			(clearance 0)
		)
		(min_thickness 0.25)
		(keepout
			(tracks not_allowed)
			(vias allowed)
			(pads allowed)
			(copperpour not_allowed)
			(footprints allowed)
		)
		(placement
			(enabled no)
			(sheetname "")
		)
		(fill
			(thermal_gap 0.5)
			(thermal_bridge_width 0.5)
			(island_removal_mode 0)
		)
		(polygon
			(pts
				(arc
					(start 7.502906 -321.935856)
					(mid 6.992366 -321.425316)
					(end 6.481826 -321.935856)
				)
				(arc
					(start 6.481826 -322.748402)
					(mid 6.992239 -323.259196)
					(end 7.502906 -322.748656)
				)
				(xy 7.502906 -322.615306) (xy 7.260336 -322.615306)
				(arc
					(start 7.235952 -322.639944)
					(mid 6.803749 -322.937273)
					(end 7.101078 -322.50507)
				)
				(xy 7.181596 -322.424806) (xy 7.502906 -322.424806) (xy 7.502906 -322.259706) (xy 7.181596 -322.259706)
				(arc
					(start 7.101078 -322.179442)
					(mid 6.803749 -321.747239)
					(end 7.235952 -322.044568)
				)
				(xy 7.260336 -322.069206) (xy 7.502906 -322.069206)
			)
		)
	)
	(zone
		(layer "In5.Cu")
		(hatch none 0.5)
		(connect_pads
			(clearance 0)
		)
		(min_thickness 0.25)
		(keepout
			(tracks not_allowed)
			(vias allowed)
			(pads allowed)
			(copperpour not_allowed)
			(footprints allowed)
		)
		(placement
			(enabled no)
			(sheetname "")
		)
		(fill
			(thermal_gap 0.5)
			(thermal_bridge_width 0.5)
			(island_removal_mode 0)
		)
		(polygon
			(pts
				(arc
					(start 7.502906 -207.936084)
					(mid 6.992493 -207.42529)
					(end 6.481826 -207.93583)
				)
				(arc
					(start 6.481826 -208.74863)
					(mid 6.992366 -209.25917)
					(end 7.502906 -208.74863)
				)
				(xy 7.502906 -208.61528) (xy 7.260336 -208.61528)
				(arc
					(start 7.235952 -208.639918)
					(mid 6.803749 -208.937247)
					(end 7.101078 -208.505044)
				)
				(xy 7.181596 -208.42478) (xy 7.502906 -208.42478) (xy 7.502906 -208.25968) (xy 7.181596 -208.25968)
				(arc
					(start 7.101078 -208.179416)
					(mid 6.803749 -207.747213)
					(end 7.235952 -208.044542)
				)
				(xy 7.260336 -208.06918) (xy 7.502906 -208.06918)
			)
		)
	)
	(zone
		(layer "In5.Cu")
		(hatch none 0.5)
		(connect_pads
			(clearance 0)
		)
		(min_thickness 0.25)
		(keepout
			(tracks not_allowed)
			(vias allowed)
			(pads allowed)
			(copperpour not_allowed)
			(footprints allowed)
		)
		(placement
			(enabled no)
			(sheetname "")
		)
		(fill
			(thermal_gap 0.5)
			(thermal_bridge_width 0.5)
			(island_removal_mode 0)
		)
		(polygon
			(pts
				(arc
					(start 7.502906 -333.986886)
					(mid 6.992493 -333.476092)
					(end 6.481826 -333.986632)
				)
				(arc
					(start 6.481826 -334.799432)
					(mid 6.992366 -335.309972)
					(end 7.502906 -334.799432)
				)
				(xy 7.502906 -334.666082) (xy 7.260336 -334.666082)
				(arc
					(start 7.235952 -334.69072)
					(mid 6.803749 -334.988049)
					(end 7.101078 -334.555846)
				)
				(xy 7.181596 -334.475582) (xy 7.502906 -334.475582) (xy 7.502906 -334.310482) (xy 7.181596 -334.310482)
				(arc
					(start 7.101078 -334.230218)
					(mid 6.803749 -333.798015)
					(end 7.235952 -334.095344)
				)
				(xy 7.260336 -334.119982) (xy 7.502906 -334.119982)
			)
		)
	)
	(zone
		(layer "In5.Cu")
		(hatch none 0.5)
		(connect_pads
			(clearance 0)
		)
		(min_thickness 0.25)
		(keepout
			(tracks not_allowed)
			(vias allowed)
			(pads allowed)
			(copperpour not_allowed)
			(footprints allowed)
		)
		(placement
			(enabled no)
			(sheetname "")
		)
		(fill
			(thermal_gap 0.5)
			(thermal_bridge_width 0.5)
			(island_removal_mode 0)
		)
		(polygon
			(pts
				(arc
					(start 35.84067 -385.983988)
					(mid 35.330257 -385.473194)
					(end 34.81959 -385.983734)
				)
				(xy 34.81959 -386.117338) (xy 35.061906 -386.117338)
				(arc
					(start 35.086544 -386.092446)
					(mid 35.518747 -385.795117)
					(end 35.221418 -386.22732)
				)
				(xy 35.140646 -386.307838) (xy 34.81959 -386.307838) (xy 34.81959 -386.472938) (xy 35.141154 -386.472938)
				(arc
					(start 35.221418 -386.552948)
					(mid 35.518747 -386.985151)
					(end 35.086544 -386.687822)
				)
				(xy 35.062414 -386.663438) (xy 34.81959 -386.663438)
				(arc
					(start 34.81959 -386.796534)
					(mid 35.33013 -387.307074)
					(end 35.84067 -386.796534)
				)
			)
		)
	)
	(zone
		(layer "In5.Cu")
		(hatch none 0.5)
		(connect_pads
			(clearance 0)
		)
		(min_thickness 0.25)
		(keepout
			(tracks not_allowed)
			(vias allowed)
			(pads allowed)
			(copperpour not_allowed)
			(footprints allowed)
		)
		(placement
			(enabled no)
			(sheetname "")
		)
		(fill
			(thermal_gap 0.5)
			(thermal_bridge_width 0.5)
			(island_removal_mode 0)
		)
		(polygon
			(pts
				(arc
					(start 35.84067 -278.183848)
					(mid 35.330257 -277.673054)
					(end 34.81959 -278.183594)
				)
				(xy 34.81959 -278.317198) (xy 35.061906 -278.317198)
				(arc
					(start 35.086544 -278.292306)
					(mid 35.518747 -277.994977)
					(end 35.221418 -278.42718)
				)
				(xy 35.140646 -278.507698) (xy 34.81959 -278.507698) (xy 34.81959 -278.672798) (xy 35.141154 -278.672798)
				(arc
					(start 35.221418 -278.752808)
					(mid 35.518747 -279.185011)
					(end 35.086544 -278.887682)
				)
				(xy 35.062414 -278.863298) (xy 34.81959 -278.863298)
				(arc
					(start 34.81959 -278.996394)
					(mid 35.33013 -279.506934)
					(end 35.84067 -278.996394)
				)
			)
		)
	)
	(zone
		(layer "In5.Cu")
		(hatch none 0.5)
		(connect_pads
			(clearance 0)
		)
		(min_thickness 0.25)
		(keepout
			(tracks not_allowed)
			(vias allowed)
			(pads allowed)
			(copperpour not_allowed)
			(footprints allowed)
		)
		(placement
			(enabled no)
			(sheetname "")
		)
		(fill
			(thermal_gap 0.5)
			(thermal_bridge_width 0.5)
			(island_removal_mode 0)
		)
		(polygon
			(pts
				(arc
					(start 7.502906 -353.1362)
					(mid 6.992493 -352.625406)
					(end 6.481826 -353.135946)
				)
				(arc
					(start 6.481826 -353.948746)
					(mid 6.992366 -354.459286)
					(end 7.502906 -353.948746)
				)
				(xy 7.502906 -353.815396) (xy 7.260336 -353.815396)
				(arc
					(start 7.235952 -353.840034)
					(mid 6.803749 -354.137363)
					(end 7.101078 -353.70516)
				)
				(xy 7.181596 -353.624896) (xy 7.502906 -353.624896) (xy 7.502906 -353.459796) (xy 7.181596 -353.459796)
				(arc
					(start 7.101078 -353.379532)
					(mid 6.803749 -352.947329)
					(end 7.235952 -353.244658)
				)
				(xy 7.260336 -353.269296) (xy 7.502906 -353.269296)
			)
		)
	)
	(zone
		(layer "In5.Cu")
		(hatch none 0.5)
		(connect_pads
			(clearance 0)
		)
		(min_thickness 0.25)
		(keepout
			(tracks not_allowed)
			(vias allowed)
			(pads allowed)
			(copperpour not_allowed)
			(footprints allowed)
		)
		(placement
			(enabled no)
			(sheetname "")
		)
		(fill
			(thermal_gap 0.5)
			(thermal_bridge_width 0.5)
			(island_removal_mode 0)
		)
		(polygon
			(pts
				(xy 7.502906 -162.488626)
				(arc
					(start 7.502906 -162.387026)
					(mid 6.992493 -161.876232)
					(end 6.481826 -162.386772)
				)
				(arc
					(start 6.481826 -163.199572)
					(mid 6.992366 -163.710112)
					(end 7.502906 -163.199572)
				)
				(xy 7.502906 -163.043108) (xy 7.409434 -163.059618) (xy 7.402576 -163.066222) (xy 7.371588 -163.066222)
				(xy 7.340854 -163.071556) (xy 7.333234 -163.066222) (xy 7.260336 -163.066222)
				(arc
					(start 7.235952 -163.09086)
					(mid 6.803749 -163.388189)
					(end 7.101078 -162.955986)
				)
				(xy 7.181596 -162.875722) (xy 7.354824 -162.875722) (xy 7.502906 -162.84956) (xy 7.502906 -162.68192)
				(xy 7.378192 -162.704018) (xy 7.371334 -162.710622) (xy 7.340346 -162.710622) (xy 7.309612 -162.715956)
				(xy 7.301992 -162.710622) (xy 7.181596 -162.710622)
				(arc
					(start 7.101078 -162.630358)
					(mid 6.803749 -162.198155)
					(end 7.235952 -162.495484)
				)
				(xy 7.260336 -162.520122) (xy 7.323582 -162.520122)
			)
		)
	)
	(zone
		(layer "In5.Cu")
		(hatch none 0.5)
		(connect_pads
			(clearance 0)
		)
		(min_thickness 0.25)
		(keepout
			(tracks not_allowed)
			(vias allowed)
			(pads allowed)
			(copperpour not_allowed)
			(footprints allowed)
		)
		(placement
			(enabled no)
			(sheetname "")
		)
		(fill
			(thermal_gap 0.5)
			(thermal_bridge_width 0.5)
			(island_removal_mode 0)
		)
		(polygon
			(pts
				(arc
					(start 35.84067 -273.38401)
					(mid 35.330257 -272.873216)
					(end 34.81959 -273.383756)
				)
				(xy 34.81959 -273.517106) (xy 35.06216 -273.517106)
				(arc
					(start 35.086544 -273.492468)
					(mid 35.518747 -273.195139)
					(end 35.221418 -273.627342)
				)
				(xy 35.1409 -273.707606) (xy 34.81959 -273.707606) (xy 34.81959 -273.872706) (xy 35.1409 -273.872706)
				(arc
					(start 35.221418 -273.95297)
					(mid 35.518747 -274.385173)
					(end 35.086544 -274.087844)
				)
				(xy 35.06216 -274.063206) (xy 34.81959 -274.063206)
				(arc
					(start 34.81959 -274.196556)
					(mid 35.33013 -274.707096)
					(end 35.84067 -274.196556)
				)
			)
		)
	)
	(zone
		(layer "In5.Cu")
		(hatch none 0.5)
		(connect_pads
			(clearance 0)
		)
		(min_thickness 0.25)
		(keepout
			(tracks not_allowed)
			(vias allowed)
			(pads allowed)
			(copperpour not_allowed)
			(footprints allowed)
		)
		(placement
			(enabled no)
			(sheetname "")
		)
		(fill
			(thermal_gap 0.5)
			(thermal_bridge_width 0.5)
			(island_removal_mode 0)
		)
		(polygon
			(pts
				(arc
					(start 35.84067 -282.98394)
					(mid 35.330257 -282.473146)
					(end 34.81959 -282.983686)
				)
				(xy 34.81959 -283.11729) (xy 35.061906 -283.11729)
				(arc
					(start 35.086544 -283.092398)
					(mid 35.518747 -282.795069)
					(end 35.221418 -283.227272)
				)
				(xy 35.140646 -283.30779) (xy 34.81959 -283.30779) (xy 34.81959 -283.47289) (xy 35.141154 -283.47289)
				(arc
					(start 35.221418 -283.5529)
					(mid 35.518747 -283.985103)
					(end 35.086544 -283.687774)
				)
				(xy 35.062414 -283.66339) (xy 34.81959 -283.66339)
				(arc
					(start 34.81959 -283.796486)
					(mid 35.33013 -284.307026)
					(end 35.84067 -283.796486)
				)
			)
		)
	)
	(zone
		(layer "In5.Cu")
		(hatch none 0.5)
		(connect_pads
			(clearance 0)
		)
		(min_thickness 0.25)
		(keepout
			(tracks not_allowed)
			(vias allowed)
			(pads allowed)
			(copperpour not_allowed)
			(footprints allowed)
		)
		(placement
			(enabled no)
			(sheetname "")
		)
		(fill
			(thermal_gap 0.5)
			(thermal_bridge_width 0.5)
			(island_removal_mode 0)
		)
		(polygon
			(pts
				(arc
					(start 35.84067 -175.1838)
					(mid 35.330257 -174.673006)
					(end 34.81959 -175.183546)
				)
				(xy 34.81959 -175.31715) (xy 35.061906 -175.31715)
				(arc
					(start 35.086544 -175.292258)
					(mid 35.518747 -174.994929)
					(end 35.221418 -175.427132)
				)
				(xy 35.140646 -175.50765) (xy 34.81959 -175.50765) (xy 34.81959 -175.67275) (xy 35.141154 -175.67275)
				(arc
					(start 35.221418 -175.75276)
					(mid 35.518747 -176.184963)
					(end 35.086544 -175.887634)
				)
				(xy 35.062414 -175.86325) (xy 34.81959 -175.86325)
				(arc
					(start 34.81959 -175.996346)
					(mid 35.33013 -176.506886)
					(end 35.84067 -175.996346)
				)
			)
		)
	)
	(zone
		(layer "In5.Cu")
		(hatch none 0.5)
		(connect_pads
			(clearance 0)
		)
		(min_thickness 0.25)
		(keepout
			(tracks not_allowed)
			(vias allowed)
			(pads allowed)
			(copperpour not_allowed)
			(footprints allowed)
		)
		(placement
			(enabled no)
			(sheetname "")
		)
		(fill
			(thermal_gap 0.5)
			(thermal_bridge_width 0.5)
			(island_removal_mode 0)
		)
		(polygon
			(pts
				(arc
					(start 7.502906 -214.285322)
					(mid 6.992493 -213.774528)
					(end 6.481826 -214.285068)
				)
				(arc
					(start 6.481826 -215.097868)
					(mid 6.992366 -215.608408)
					(end 7.502906 -215.097868)
				)
				(xy 7.502906 -214.964518) (xy 7.260336 -214.964518)
				(arc
					(start 7.235952 -214.989156)
					(mid 6.803749 -215.286485)
					(end 7.101078 -214.854282)
				)
				(xy 7.181596 -214.774018) (xy 7.502906 -214.774018) (xy 7.502906 -214.608918) (xy 7.181596 -214.608918)
				(arc
					(start 7.101078 -214.528654)
					(mid 6.803749 -214.096451)
					(end 7.235952 -214.39378)
				)
				(xy 7.260336 -214.418418) (xy 7.502906 -214.418418)
			)
		)
	)
	(zone
		(layer "In5.Cu")
		(hatch none 0.5)
		(connect_pads
			(clearance 0)
		)
		(min_thickness 0.25)
		(keepout
			(tracks not_allowed)
			(vias allowed)
			(pads allowed)
			(copperpour not_allowed)
			(footprints allowed)
		)
		(placement
			(enabled no)
			(sheetname "")
		)
		(fill
			(thermal_gap 0.5)
			(thermal_bridge_width 0.5)
			(island_removal_mode 0)
		)
		(polygon
			(pts
				(arc
					(start 220.840554 -278.183848)
					(mid 220.330141 -277.673054)
					(end 219.819474 -278.183594)
				)
				(xy 219.819474 -278.317198) (xy 220.06179 -278.317198)
				(arc
					(start 220.086428 -278.292306)
					(mid 220.518631 -277.994977)
					(end 220.221302 -278.42718)
				)
				(xy 220.14053 -278.507698) (xy 219.819474 -278.507698) (xy 219.819474 -278.672798) (xy 220.141038 -278.672798)
				(arc
					(start 220.221302 -278.752808)
					(mid 220.518631 -279.185011)
					(end 220.086428 -278.887682)
				)
				(xy 220.062298 -278.863298) (xy 219.819474 -278.863298)
				(arc
					(start 219.819474 -278.996394)
					(mid 220.330014 -279.506934)
					(end 220.840554 -278.996394)
				)
			)
		)
	)
	(zone
		(layer "In5.Cu")
		(hatch none 0.5)
		(connect_pads
			(clearance 0)
		)
		(min_thickness 0.25)
		(keepout
			(tracks not_allowed)
			(vias allowed)
			(pads allowed)
			(copperpour not_allowed)
			(footprints allowed)
		)
		(placement
			(enabled no)
			(sheetname "")
		)
		(fill
			(thermal_gap 0.5)
			(thermal_bridge_width 0.5)
			(island_removal_mode 0)
		)
		(polygon
			(pts
				(arc
					(start 7.502906 -356.335838)
					(mid 6.992366 -355.825298)
					(end 6.481826 -356.335838)
				)
				(arc
					(start 6.481826 -357.148384)
					(mid 6.992239 -357.659178)
					(end 7.502906 -357.148638)
				)
				(xy 7.502906 -357.015288) (xy 7.260336 -357.015288)
				(arc
					(start 7.235952 -357.039926)
					(mid 6.803749 -357.337255)
					(end 7.101078 -356.905052)
				)
				(xy 7.181596 -356.824788) (xy 7.502906 -356.824788) (xy 7.502906 -356.659688) (xy 7.181596 -356.659688)
				(arc
					(start 7.101078 -356.579424)
					(mid 6.803749 -356.147221)
					(end 7.235952 -356.44455)
				)
				(xy 7.260336 -356.469188) (xy 7.502906 -356.469188)
			)
		)
	)
	(zone
		(layer "In5.Cu")
		(hatch none 0.5)
		(connect_pads
			(clearance 0)
		)
		(min_thickness 0.25)
		(keepout
			(tracks not_allowed)
			(vias allowed)
			(pads allowed)
			(copperpour not_allowed)
			(footprints allowed)
		)
		(placement
			(enabled no)
			(sheetname "")
		)
		(fill
			(thermal_gap 0.5)
			(thermal_bridge_width 0.5)
			(island_removal_mode 0)
		)
		(polygon
			(pts
				(arc
					(start 7.502906 -393.535916)
					(mid 6.992493 -393.025122)
					(end 6.481826 -393.535662)
				)
				(arc
					(start 6.481826 -394.348462)
					(mid 6.992366 -394.859002)
					(end 7.502906 -394.348462)
				)
				(xy 7.502906 -394.215112) (xy 7.260336 -394.215112)
				(arc
					(start 7.235952 -394.23975)
					(mid 6.803749 -394.537079)
					(end 7.101078 -394.104876)
				)
				(xy 7.181596 -394.024612) (xy 7.502906 -394.024612) (xy 7.502906 -393.859512) (xy 7.181596 -393.859512)
				(arc
					(start 7.101078 -393.779248)
					(mid 6.803749 -393.347045)
					(end 7.235952 -393.644374)
				)
				(xy 7.260336 -393.669012) (xy 7.502906 -393.669012)
			)
		)
	)
	(zone
		(layer "In5.Cu")
		(hatch none 0.5)
		(connect_pads
			(clearance 0)
		)
		(min_thickness 0.25)
		(keepout
			(tracks not_allowed)
			(vias allowed)
			(pads allowed)
			(copperpour not_allowed)
			(footprints allowed)
		)
		(placement
			(enabled no)
			(sheetname "")
		)
		(fill
			(thermal_gap 0.5)
			(thermal_bridge_width 0.5)
			(island_removal_mode 0)
		)
		(polygon
			(pts
				(arc
					(start 35.84067 -484.18369)
					(mid 35.33013 -483.67315)
					(end 34.81959 -484.18369)
				)
				(xy 34.81959 -484.317294) (xy 35.061906 -484.317294)
				(arc
					(start 35.086544 -484.292402)
					(mid 35.518747 -483.995073)
					(end 35.221418 -484.427276)
				)
				(xy 35.140646 -484.507794) (xy 34.81959 -484.507794) (xy 34.81959 -484.672894) (xy 35.141154 -484.672894)
				(arc
					(start 35.221418 -484.752904)
					(mid 35.518747 -485.185107)
					(end 35.086544 -484.887778)
				)
				(xy 35.062414 -484.863394) (xy 34.81959 -484.863394)
				(arc
					(start 34.81959 -484.996236)
					(mid 35.330003 -485.50703)
					(end 35.84067 -484.99649)
				)
			)
		)
	)
	(zone
		(layer "In5.Cu")
		(hatch none 0.5)
		(connect_pads
			(clearance 0)
		)
		(min_thickness 0.25)
		(keepout
			(tracks not_allowed)
			(vias allowed)
			(pads allowed)
			(copperpour not_allowed)
			(footprints allowed)
		)
		(placement
			(enabled no)
			(sheetname "")
		)
		(fill
			(thermal_gap 0.5)
			(thermal_bridge_width 0.5)
			(island_removal_mode 0)
		)
		(polygon
			(pts
				(arc
					(start 220.840554 -479.384106)
					(mid 220.330141 -478.873312)
					(end 219.819474 -479.383852)
				)
				(xy 219.819474 -479.517202) (xy 220.062044 -479.517202)
				(arc
					(start 220.086428 -479.492564)
					(mid 220.518631 -479.195235)
					(end 220.221302 -479.627438)
				)
				(xy 220.140784 -479.707702) (xy 219.819474 -479.707702) (xy 219.819474 -479.872802) (xy 220.140784 -479.872802)
				(arc
					(start 220.221302 -479.953066)
					(mid 220.518631 -480.385269)
					(end 220.086428 -480.08794)
				)
				(xy 220.062044 -480.063302) (xy 219.819474 -480.063302)
				(arc
					(start 219.819474 -480.196652)
					(mid 220.330014 -480.707192)
					(end 220.840554 -480.196652)
				)
			)
		)
	)
	(zone
		(layer "In5.Cu")
		(hatch none 0.5)
		(connect_pads
			(clearance 0)
		)
		(min_thickness 0.25)
		(keepout
			(tracks not_allowed)
			(vias allowed)
			(pads allowed)
			(copperpour not_allowed)
			(footprints allowed)
		)
		(placement
			(enabled no)
			(sheetname "")
		)
		(fill
			(thermal_gap 0.5)
			(thermal_bridge_width 0.5)
			(island_removal_mode 0)
		)
		(polygon
			(pts
				(arc
					(start 27.18054 -38.603428)
					(mid 26.67 -38.092888)
					(end 26.15946 -38.603428)
				)
				(arc
					(start 26.15946 -39.415974)
					(mid 26.669873 -39.926768)
					(end 27.18054 -39.416228)
				)
				(xy 27.18054 -39.282624) (xy 26.938224 -39.282624)
				(arc
					(start 26.913586 -39.307516)
					(mid 26.481383 -39.604845)
					(end 26.778712 -39.172642)
				)
				(xy 26.859484 -39.092124) (xy 27.18054 -39.092124) (xy 27.18054 -38.927024) (xy 26.858976 -38.927024)
				(arc
					(start 26.778712 -38.847014)
					(mid 26.481383 -38.414811)
					(end 26.913586 -38.71214)
				)
				(xy 26.937716 -38.736524) (xy 27.18054 -38.736524)
			)
		)
	)
	(zone
		(layer "In5.Cu")
		(hatch none 0.5)
		(connect_pads
			(clearance 0)
		)
		(min_thickness 0.25)
		(keepout
			(tracks not_allowed)
			(vias allowed)
			(pads allowed)
			(copperpour not_allowed)
			(footprints allowed)
		)
		(placement
			(enabled no)
			(sheetname "")
		)
		(fill
			(thermal_gap 0.5)
			(thermal_bridge_width 0.5)
			(island_removal_mode 0)
		)
		(polygon
			(pts
				(arc
					(start 7.502906 -396.736062)
					(mid 6.992493 -396.225268)
					(end 6.481826 -396.735808)
				)
				(arc
					(start 6.481826 -397.548608)
					(mid 6.992366 -398.059148)
					(end 7.502906 -397.548608)
				)
				(xy 7.502906 -397.415258) (xy 7.260336 -397.415258)
				(arc
					(start 7.235952 -397.439896)
					(mid 6.803749 -397.737225)
					(end 7.101078 -397.305022)
				)
				(xy 7.181596 -397.224758) (xy 7.502906 -397.224758) (xy 7.502906 -397.059658) (xy 7.181596 -397.059658)
				(arc
					(start 7.101078 -396.979394)
					(mid 6.803749 -396.547191)
					(end 7.235952 -396.84452)
				)
				(xy 7.260336 -396.869158) (xy 7.502906 -396.869158)
			)
		)
	)
	(zone
		(layer "In5.Cu")
		(hatch none 0.5)
		(connect_pads
			(clearance 0)
		)
		(min_thickness 0.25)
		(keepout
			(tracks not_allowed)
			(vias allowed)
			(pads allowed)
			(copperpour not_allowed)
			(footprints allowed)
		)
		(placement
			(enabled no)
			(sheetname "")
		)
		(fill
			(thermal_gap 0.5)
			(thermal_bridge_width 0.5)
			(island_removal_mode 0)
		)
		(polygon
			(pts
				(arc
					(start 220.840554 -385.983988)
					(mid 220.330141 -385.473194)
					(end 219.819474 -385.983734)
				)
				(xy 219.819474 -386.117338) (xy 220.06179 -386.117338)
				(arc
					(start 220.086428 -386.092446)
					(mid 220.518631 -385.795117)
					(end 220.221302 -386.22732)
				)
				(xy 220.14053 -386.307838) (xy 219.819474 -386.307838) (xy 219.819474 -386.472938) (xy 220.141038 -386.472938)
				(arc
					(start 220.221302 -386.552948)
					(mid 220.518631 -386.985151)
					(end 220.086428 -386.687822)
				)
				(xy 220.062298 -386.663438) (xy 219.819474 -386.663438)
				(arc
					(start 219.819474 -386.796534)
					(mid 220.330014 -387.307074)
					(end 220.840554 -386.796534)
				)
			)
		)
	)
	(zone
		(layer "In5.Cu")
		(hatch none 0.5)
		(connect_pads
			(clearance 0)
		)
		(min_thickness 0.25)
		(keepout
			(tracks not_allowed)
			(vias allowed)
			(pads allowed)
			(copperpour not_allowed)
			(footprints allowed)
		)
		(placement
			(enabled no)
			(sheetname "")
		)
		(fill
			(thermal_gap 0.5)
			(thermal_bridge_width 0.5)
			(island_removal_mode 0)
		)
		(polygon
			(pts
				(arc
					(start 35.84067 -54.583838)
					(mid 35.330257 -54.073044)
					(end 34.81959 -54.583584)
				)
				(xy 34.81959 -54.717188) (xy 35.061906 -54.717188)
				(arc
					(start 35.086544 -54.692296)
					(mid 35.518747 -54.394967)
					(end 35.221418 -54.82717)
				)
				(xy 35.140646 -54.907688) (xy 34.81959 -54.907688) (xy 34.81959 -55.072788) (xy 35.141154 -55.072788)
				(arc
					(start 35.221418 -55.152798)
					(mid 35.518747 -55.585001)
					(end 35.086544 -55.287672)
				)
				(xy 35.062414 -55.263288) (xy 34.81959 -55.263288)
				(arc
					(start 34.81959 -55.396384)
					(mid 35.33013 -55.906924)
					(end 35.84067 -55.396384)
				)
			)
		)
	)
	(zone
		(layer "In5.Cu")
		(hatch none 0.5)
		(connect_pads
			(clearance 0)
		)
		(min_thickness 0.25)
		(keepout
			(tracks not_allowed)
			(vias allowed)
			(pads allowed)
			(copperpour not_allowed)
			(footprints allowed)
		)
		(placement
			(enabled no)
			(sheetname "")
		)
		(fill
			(thermal_gap 0.5)
			(thermal_bridge_width 0.5)
			(island_removal_mode 0)
		)
		(polygon
			(pts
				(xy 7.502906 -172.088302)
				(arc
					(start 7.502906 -171.986956)
					(mid 6.992493 -171.476162)
					(end 6.481826 -171.986702)
				)
				(arc
					(start 6.481826 -172.799502)
					(mid 6.992366 -173.310042)
					(end 7.502906 -172.799502)
				)
				(xy 7.502906 -172.643038) (xy 7.40918 -172.659548) (xy 7.402322 -172.666152) (xy 7.371334 -172.666152)
				(xy 7.3406 -172.671486) (xy 7.33298 -172.666152) (xy 7.260336 -172.666152)
				(arc
					(start 7.235952 -172.69079)
					(mid 6.803749 -172.988119)
					(end 7.101078 -172.555916)
				)
				(xy 7.181596 -172.475652) (xy 7.35457 -172.475652) (xy 7.502906 -172.44949) (xy 7.502906 -172.28185)
				(xy 7.377938 -172.303948) (xy 7.37108 -172.310552) (xy 7.340092 -172.310552) (xy 7.309358 -172.315886)
				(xy 7.301738 -172.310552) (xy 7.181596 -172.310552)
				(arc
					(start 7.101078 -172.230288)
					(mid 6.803749 -171.798085)
					(end 7.235952 -172.095414)
				)
				(xy 7.260336 -172.120052) (xy 7.323328 -172.120052)
			)
		)
	)
	(zone
		(layer "In5.Cu")
		(hatch none 0.5)
		(connect_pads
			(clearance 0)
		)
		(min_thickness 0.25)
		(keepout
			(tracks not_allowed)
			(vias allowed)
			(pads allowed)
			(copperpour not_allowed)
			(footprints allowed)
		)
		(placement
			(enabled no)
			(sheetname "")
		)
		(fill
			(thermal_gap 0.5)
			(thermal_bridge_width 0.5)
			(island_removal_mode 0)
		)
		(polygon
			(pts
				(arc
					(start 7.502906 -184.736232)
					(mid 6.992493 -184.225438)
					(end 6.481826 -184.735978)
				)
				(arc
					(start 6.481826 -185.548778)
					(mid 6.992366 -186.059318)
					(end 7.502906 -185.548778)
				)
				(xy 7.502906 -185.415428) (xy 7.260336 -185.415428)
				(arc
					(start 7.235952 -185.440066)
					(mid 6.803749 -185.737395)
					(end 7.101078 -185.305192)
				)
				(xy 7.181596 -185.224928) (xy 7.502906 -185.224928) (xy 7.502906 -185.059828) (xy 7.181596 -185.059828)
				(arc
					(start 7.101078 -184.979564)
					(mid 6.803749 -184.547361)
					(end 7.235952 -184.84469)
				)
				(xy 7.260336 -184.869328) (xy 7.502906 -184.869328)
			)
		)
	)
	(zone
		(layer "In5.Cu")
		(hatch none 0.5)
		(connect_pads
			(clearance 0)
		)
		(min_thickness 0.25)
		(keepout
			(tracks not_allowed)
			(vias allowed)
			(pads allowed)
			(copperpour not_allowed)
			(footprints allowed)
		)
		(placement
			(enabled no)
			(sheetname "")
		)
		(fill
			(thermal_gap 0.5)
			(thermal_bridge_width 0.5)
			(island_removal_mode 0)
		)
		(polygon
			(pts
				(arc
					(start 7.502906 -294.736012)
					(mid 6.992366 -294.225472)
					(end 6.481826 -294.736012)
				)
				(arc
					(start 6.481826 -295.548558)
					(mid 6.992239 -296.059352)
					(end 7.502906 -295.548812)
				)
				(xy 7.502906 -295.415462) (xy 7.260336 -295.415462)
				(arc
					(start 7.235952 -295.4401)
					(mid 6.803749 -295.737429)
					(end 7.101078 -295.305226)
				)
				(xy 7.181596 -295.224962) (xy 7.502906 -295.224962) (xy 7.502906 -295.059862) (xy 7.181596 -295.059862)
				(arc
					(start 7.101078 -294.979598)
					(mid 6.803749 -294.547395)
					(end 7.235952 -294.844724)
				)
				(xy 7.260336 -294.869362) (xy 7.502906 -294.869362)
			)
		)
	)
	(zone
		(layer "In5.Cu")
		(hatch none 0.5)
		(connect_pads
			(clearance 0)
		)
		(min_thickness 0.25)
		(keepout
			(tracks not_allowed)
			(vias allowed)
			(pads allowed)
			(copperpour not_allowed)
			(footprints allowed)
		)
		(placement
			(enabled no)
			(sheetname "")
		)
		(fill
			(thermal_gap 0.5)
			(thermal_bridge_width 0.5)
			(island_removal_mode 0)
		)
		(polygon
			(pts
				(xy 7.502906 -159.28848)
				(arc
					(start 7.502906 -159.18688)
					(mid 6.992493 -158.676086)
					(end 6.481826 -159.186626)
				)
				(arc
					(start 6.481826 -159.999426)
					(mid 6.992366 -160.509966)
					(end 7.502906 -159.999426)
				)
				(xy 7.502906 -159.842962) (xy 7.409434 -159.859472) (xy 7.402576 -159.866076) (xy 7.371588 -159.866076)
				(xy 7.340854 -159.87141) (xy 7.333234 -159.866076) (xy 7.260336 -159.866076)
				(arc
					(start 7.235952 -159.890714)
					(mid 6.803749 -160.188043)
					(end 7.101078 -159.75584)
				)
				(xy 7.181596 -159.675576) (xy 7.354824 -159.675576) (xy 7.502906 -159.649414) (xy 7.502906 -159.481774)
				(xy 7.378192 -159.503872) (xy 7.371334 -159.510476) (xy 7.340346 -159.510476) (xy 7.309612 -159.51581)
				(xy 7.301992 -159.510476) (xy 7.181596 -159.510476)
				(arc
					(start 7.101078 -159.430212)
					(mid 6.803749 -158.998009)
					(end 7.235952 -159.295338)
				)
				(xy 7.260336 -159.319976) (xy 7.323582 -159.319976)
			)
		)
	)
	(zone
		(layer "In5.Cu")
		(hatch none 0.5)
		(connect_pads
			(clearance 0)
		)
		(min_thickness 0.25)
		(keepout
			(tracks not_allowed)
			(vias allowed)
			(pads allowed)
			(copperpour not_allowed)
			(footprints allowed)
		)
		(placement
			(enabled no)
			(sheetname "")
		)
		(fill
			(thermal_gap 0.5)
			(thermal_bridge_width 0.5)
			(island_removal_mode 0)
		)
		(polygon
			(pts
				(arc
					(start 7.502906 -436.784242)
					(mid 6.992366 -436.273702)
					(end 6.481826 -436.784242)
				)
				(arc
					(start 6.481826 -437.596788)
					(mid 6.992239 -438.107582)
					(end 7.502906 -437.597042)
				)
				(xy 7.502906 -437.463692) (xy 7.260336 -437.463692)
				(arc
					(start 7.235952 -437.48833)
					(mid 6.803749 -437.785659)
					(end 7.101078 -437.353456)
				)
				(xy 7.181596 -437.273192) (xy 7.502906 -437.273192) (xy 7.502906 -437.108092) (xy 7.181596 -437.108092)
				(arc
					(start 7.101078 -437.027828)
					(mid 6.803749 -436.595625)
					(end 7.235952 -436.892954)
				)
				(xy 7.260336 -436.917592) (xy 7.502906 -436.917592)
			)
		)
	)
	(zone
		(layer "In5.Cu")
		(hatch none 0.5)
		(connect_pads
			(clearance 0)
		)
		(min_thickness 0.25)
		(keepout
			(tracks not_allowed)
			(vias allowed)
			(pads allowed)
			(copperpour not_allowed)
			(footprints allowed)
		)
		(placement
			(enabled no)
			(sheetname "")
		)
		(fill
			(thermal_gap 0.5)
			(thermal_bridge_width 0.5)
			(island_removal_mode 0)
		)
		(polygon
			(pts
				(arc
					(start 7.502906 -310.73598)
					(mid 6.992366 -310.22544)
					(end 6.481826 -310.73598)
				)
				(arc
					(start 6.481826 -311.548526)
					(mid 6.992239 -312.05932)
					(end 7.502906 -311.54878)
				)
				(xy 7.502906 -311.41543) (xy 7.260336 -311.41543)
				(arc
					(start 7.235952 -311.440068)
					(mid 6.803749 -311.737397)
					(end 7.101078 -311.305194)
				)
				(xy 7.181596 -311.22493) (xy 7.502906 -311.22493) (xy 7.502906 -311.05983) (xy 7.181596 -311.05983)
				(arc
					(start 7.101078 -310.979566)
					(mid 6.803749 -310.547363)
					(end 7.235952 -310.844692)
				)
				(xy 7.260336 -310.86933) (xy 7.502906 -310.86933)
			)
		)
	)
	(zone
		(layer "In5.Cu")
		(hatch none 0.5)
		(connect_pads
			(clearance 0)
		)
		(min_thickness 0.25)
		(keepout
			(tracks not_allowed)
			(vias allowed)
			(pads allowed)
			(copperpour not_allowed)
			(footprints allowed)
		)
		(placement
			(enabled no)
			(sheetname "")
		)
		(fill
			(thermal_gap 0.5)
			(thermal_bridge_width 0.5)
			(island_removal_mode 0)
		)
		(polygon
			(pts
				(arc
					(start 35.84067 -72.183752)
					(mid 35.330257 -71.672958)
					(end 34.81959 -72.183498)
				)
				(xy 34.81959 -72.317102) (xy 35.061906 -72.317102)
				(arc
					(start 35.086544 -72.29221)
					(mid 35.518747 -71.994881)
					(end 35.221418 -72.427084)
				)
				(xy 35.140646 -72.507602) (xy 34.81959 -72.507602) (xy 34.81959 -72.672702) (xy 35.141154 -72.672702)
				(arc
					(start 35.221418 -72.752712)
					(mid 35.518747 -73.184915)
					(end 35.086544 -72.887586)
				)
				(xy 35.062414 -72.863202) (xy 34.81959 -72.863202)
				(arc
					(start 34.81959 -72.996298)
					(mid 35.33013 -73.506838)
					(end 35.84067 -72.996298)
				)
			)
		)
	)
	(zone
		(layer "In5.Cu")
		(hatch none 0.5)
		(connect_pads
			(clearance 0)
		)
		(min_thickness 0.25)
		(keepout
			(tracks not_allowed)
			(vias allowed)
			(pads allowed)
			(copperpour not_allowed)
			(footprints allowed)
		)
		(placement
			(enabled no)
			(sheetname "")
		)
		(fill
			(thermal_gap 0.5)
			(thermal_bridge_width 0.5)
			(island_removal_mode 0)
		)
		(polygon
			(pts
				(arc
					(start 7.502906 -427.984412)
					(mid 6.992493 -427.473618)
					(end 6.481826 -427.984158)
				)
				(arc
					(start 6.481826 -428.796958)
					(mid 6.992366 -429.307498)
					(end 7.502906 -428.796958)
				)
				(xy 7.502906 -428.64405) (xy 7.279894 -428.64405)
				(arc
					(start 7.235952 -428.688246)
					(mid 6.803749 -428.985575)
					(end 7.101078 -428.553372)
				)
				(xy 7.201154 -428.45355) (xy 7.502906 -428.45355) (xy 7.502906 -428.28845) (xy 7.162038 -428.28845)
				(arc
					(start 7.101078 -428.227744)
					(mid 6.803749 -427.795541)
					(end 7.235952 -428.09287)
				)
				(xy 7.240778 -428.09795) (xy 7.502906 -428.09795)
			)
		)
	)
	(zone
		(layer "In5.Cu")
		(hatch none 0.5)
		(connect_pads
			(clearance 0)
		)
		(min_thickness 0.25)
		(keepout
			(tracks not_allowed)
			(vias allowed)
			(pads allowed)
			(copperpour not_allowed)
			(footprints allowed)
		)
		(placement
			(enabled no)
			(sheetname "")
		)
		(fill
			(thermal_gap 0.5)
			(thermal_bridge_width 0.5)
			(island_removal_mode 0)
		)
		(polygon
			(pts
				(arc
					(start 7.502906 -297.935904)
					(mid 6.992366 -297.425364)
					(end 6.481826 -297.935904)
				)
				(arc
					(start 6.481826 -298.74845)
					(mid 6.992239 -299.259244)
					(end 7.502906 -298.748704)
				)
				(xy 7.502906 -298.615354) (xy 7.260336 -298.615354)
				(arc
					(start 7.235952 -298.639992)
					(mid 6.803749 -298.937321)
					(end 7.101078 -298.505118)
				)
				(xy 7.181596 -298.424854) (xy 7.502906 -298.424854) (xy 7.502906 -298.259754) (xy 7.181596 -298.259754)
				(arc
					(start 7.101078 -298.17949)
					(mid 6.803749 -297.747287)
					(end 7.235952 -298.044616)
				)
				(xy 7.260336 -298.069254) (xy 7.502906 -298.069254)
			)
		)
	)
	(zone
		(layer "In5.Cu")
		(hatch none 0.5)
		(connect_pads
			(clearance 0)
		)
		(min_thickness 0.25)
		(keepout
			(tracks not_allowed)
			(vias allowed)
			(pads allowed)
			(copperpour not_allowed)
			(footprints allowed)
		)
		(placement
			(enabled no)
			(sheetname "")
		)
		(fill
			(thermal_gap 0.5)
			(thermal_bridge_width 0.5)
			(island_removal_mode 0)
		)
		(polygon
			(pts
				(arc
					(start 7.502906 -424.78452)
					(mid 6.992493 -424.273726)
					(end 6.481826 -424.784266)
				)
				(arc
					(start 6.481826 -425.597066)
					(mid 6.992366 -426.107606)
					(end 7.502906 -425.597066)
				)
				(xy 7.502906 -425.463716) (xy 7.260336 -425.463716)
				(arc
					(start 7.235952 -425.488354)
					(mid 6.803749 -425.785683)
					(end 7.101078 -425.35348)
				)
				(xy 7.181596 -425.273216) (xy 7.502906 -425.273216) (xy 7.502906 -425.108116) (xy 7.181596 -425.108116)
				(arc
					(start 7.101078 -425.027852)
					(mid 6.803749 -424.595649)
					(end 7.235952 -424.892978)
				)
				(xy 7.260336 -424.917616) (xy 7.502906 -424.917616)
			)
		)
	)
	(zone
		(layer "In5.Cu")
		(hatch none 0.5)
		(connect_pads
			(clearance 0)
		)
		(min_thickness 0.25)
		(keepout
			(tracks not_allowed)
			(vias allowed)
			(pads allowed)
			(copperpour not_allowed)
			(footprints allowed)
		)
		(placement
			(enabled no)
			(sheetname "")
		)
		(fill
			(thermal_gap 0.5)
			(thermal_bridge_width 0.5)
			(island_removal_mode 0)
		)
		(polygon
			(pts
				(arc
					(start 220.840554 -381.183896)
					(mid 220.330141 -380.673102)
					(end 219.819474 -381.183642)
				)
				(xy 219.819474 -381.317246) (xy 220.06179 -381.317246)
				(arc
					(start 220.086428 -381.292354)
					(mid 220.518631 -380.995025)
					(end 220.221302 -381.427228)
				)
				(xy 220.14053 -381.507746) (xy 219.819474 -381.507746) (xy 219.819474 -381.672846) (xy 220.141038 -381.672846)
				(arc
					(start 220.221302 -381.752856)
					(mid 220.518631 -382.185059)
					(end 220.086428 -381.88773)
				)
				(xy 220.062298 -381.863346) (xy 219.819474 -381.863346)
				(arc
					(start 219.819474 -381.996442)
					(mid 220.330014 -382.506982)
					(end 220.840554 -381.996442)
				)
			)
		)
	)
	(zone
		(layer "In5.Cu")
		(hatch none 0.5)
		(connect_pads
			(clearance 0)
		)
		(min_thickness 0.25)
		(keepout
			(tracks not_allowed)
			(vias allowed)
			(pads allowed)
			(copperpour not_allowed)
			(footprints allowed)
		)
		(placement
			(enabled no)
			(sheetname "")
		)
		(fill
			(thermal_gap 0.5)
			(thermal_bridge_width 0.5)
			(island_removal_mode 0)
		)
		(polygon
			(pts
				(arc
					(start 27.18054 -25.803352)
					(mid 26.67 -25.292812)
					(end 26.15946 -25.803352)
				)
				(arc
					(start 26.15946 -26.615898)
					(mid 26.669873 -27.126692)
					(end 27.18054 -26.616152)
				)
				(xy 27.18054 -26.482802) (xy 26.93797 -26.482802)
				(arc
					(start 26.913586 -26.50744)
					(mid 26.481383 -26.804769)
					(end 26.778712 -26.372566)
				)
				(xy 26.85923 -26.292302) (xy 27.18054 -26.292302) (xy 27.18054 -26.127202) (xy 26.85923 -26.127202)
				(arc
					(start 26.778712 -26.046938)
					(mid 26.481383 -25.614735)
					(end 26.913586 -25.912064)
				)
				(xy 26.93797 -25.936702) (xy 27.18054 -25.936702)
			)
		)
	)
	(zone
		(layer "In5.Cu")
		(hatch none 0.5)
		(connect_pads
			(clearance 0)
		)
		(min_thickness 0.25)
		(keepout
			(tracks not_allowed)
			(vias allowed)
			(pads allowed)
			(copperpour not_allowed)
			(footprints allowed)
		)
		(placement
			(enabled no)
			(sheetname "")
		)
		(fill
			(thermal_gap 0.5)
			(thermal_bridge_width 0.5)
			(island_removal_mode 0)
		)
		(polygon
			(pts
				(arc
					(start 7.502906 -390.336024)
					(mid 6.992493 -389.82523)
					(end 6.481826 -390.33577)
				)
				(arc
					(start 6.481826 -391.14857)
					(mid 6.992366 -391.65911)
					(end 7.502906 -391.14857)
				)
				(xy 7.502906 -391.01522) (xy 7.260336 -391.01522)
				(arc
					(start 7.235952 -391.039858)
					(mid 6.803749 -391.337187)
					(end 7.101078 -390.904984)
				)
				(xy 7.181596 -390.82472) (xy 7.502906 -390.82472) (xy 7.502906 -390.65962) (xy 7.181596 -390.65962)
				(arc
					(start 7.101078 -390.579356)
					(mid 6.803749 -390.147153)
					(end 7.235952 -390.444482)
				)
				(xy 7.260336 -390.46912) (xy 7.502906 -390.46912)
			)
		)
	)
	(zone
		(net "VDD_DIFF_1")
		(layer "In5.Cu")
		(hatch none 0.5)
		(connect_pads
			(clearance 0.5)
		)
		(min_thickness 0.25)
		(fill yes
			(thermal_gap 0.5)
			(thermal_bridge_width 0.5)
			(island_removal_mode 0)
		)
		(polygon
			(pts
				(xy 81.505806 -441.804806) (xy 100.231194 -441.804806) (xy 104.267 -437.769) (xy 104.267 -429.26)
				(xy 99.06 -424.053) (xy 81.661 -424.053) (xy 78.74 -426.974) (xy 78.74 -439.039)
			)
		)
	)
	(zone
		(layer "In5.Cu")
		(hatch none 0.5)
		(connect_pads
			(clearance 0)
		)
		(min_thickness 0.25)
		(keepout
			(tracks not_allowed)
			(vias allowed)
			(pads allowed)
			(copperpour not_allowed)
			(footprints allowed)
		)
		(placement
			(enabled no)
			(sheetname "")
		)
		(fill
			(thermal_gap 0.5)
			(thermal_bridge_width 0.5)
			(island_removal_mode 0)
		)
		(polygon
			(pts
				(arc
					(start 27.18054 -21.003514)
					(mid 26.67 -20.492974)
					(end 26.15946 -21.003514)
				)
				(arc
					(start 26.15946 -21.81606)
					(mid 26.669873 -22.326854)
					(end 27.18054 -21.816314)
				)
				(xy 27.18054 -21.68271) (xy 26.938224 -21.68271)
				(arc
					(start 26.913586 -21.707602)
					(mid 26.481383 -22.004931)
					(end 26.778712 -21.572728)
				)
				(xy 26.859484 -21.49221) (xy 27.18054 -21.49221) (xy 27.18054 -21.32711) (xy 26.858976 -21.32711)
				(arc
					(start 26.778712 -21.2471)
					(mid 26.481383 -20.814897)
					(end 26.913586 -21.112226)
				)
				(xy 26.937716 -21.13661) (xy 27.18054 -21.13661)
			)
		)
	)
	(zone
		(layer "In5.Cu")
		(hatch none 0.5)
		(connect_pads
			(clearance 0)
		)
		(min_thickness 0.25)
		(keepout
			(tracks not_allowed)
			(vias allowed)
			(pads allowed)
			(copperpour not_allowed)
			(footprints allowed)
		)
		(placement
			(enabled no)
			(sheetname "")
		)
		(fill
			(thermal_gap 0.5)
			(thermal_bridge_width 0.5)
			(island_removal_mode 0)
		)
		(polygon
			(pts
				(arc
					(start 35.84067 -170.383962)
					(mid 35.330257 -169.873168)
					(end 34.81959 -170.383708)
				)
				(xy 34.81959 -170.517058) (xy 35.06216 -170.517058)
				(arc
					(start 35.086544 -170.49242)
					(mid 35.518747 -170.195091)
					(end 35.221418 -170.627294)
				)
				(xy 35.1409 -170.707558) (xy 34.81959 -170.707558) (xy 34.81959 -170.872658) (xy 35.1409 -170.872658)
				(arc
					(start 35.221418 -170.952922)
					(mid 35.518747 -171.385125)
					(end 35.086544 -171.087796)
				)
				(xy 35.06216 -171.063158) (xy 34.81959 -171.063158)
				(arc
					(start 34.81959 -171.196508)
					(mid 35.33013 -171.707048)
					(end 35.84067 -171.196508)
				)
			)
		)
	)
	(zone
		(layer "In5.Cu")
		(hatch none 0.5)
		(connect_pads
			(clearance 0)
		)
		(min_thickness 0.25)
		(keepout
			(tracks not_allowed)
			(vias allowed)
			(pads allowed)
			(copperpour not_allowed)
			(footprints allowed)
		)
		(placement
			(enabled no)
			(sheetname "")
		)
		(fill
			(thermal_gap 0.5)
			(thermal_bridge_width 0.5)
			(island_removal_mode 0)
		)
		(polygon
			(pts
				(arc
					(start 7.502906 -204.736192)
					(mid 6.992493 -204.225398)
					(end 6.481826 -204.735938)
				)
				(arc
					(start 6.481826 -205.548738)
					(mid 6.992366 -206.059278)
					(end 7.502906 -205.548738)
				)
				(xy 7.502906 -205.415388) (xy 7.260336 -205.415388)
				(arc
					(start 7.235952 -205.440026)
					(mid 6.803749 -205.737355)
					(end 7.101078 -205.305152)
				)
				(xy 7.181596 -205.224888) (xy 7.502906 -205.224888) (xy 7.502906 -205.059788) (xy 7.181596 -205.059788)
				(arc
					(start 7.101078 -204.979524)
					(mid 6.803749 -204.547321)
					(end 7.235952 -204.84465)
				)
				(xy 7.260336 -204.869288) (xy 7.502906 -204.869288)
			)
		)
	)
	(zone
		(layer "In5.Cu")
		(hatch none 0.5)
		(connect_pads
			(clearance 0)
		)
		(min_thickness 0.25)
		(keepout
			(tracks not_allowed)
			(vias allowed)
			(pads allowed)
			(copperpour not_allowed)
			(footprints allowed)
		)
		(placement
			(enabled no)
			(sheetname "")
		)
		(fill
			(thermal_gap 0.5)
			(thermal_bridge_width 0.5)
			(island_removal_mode 0)
		)
		(polygon
			(pts
				(arc
					(start 7.502906 -328.335894)
					(mid 6.992366 -327.825354)
					(end 6.481826 -328.335894)
				)
				(arc
					(start 6.481826 -329.14844)
					(mid 6.992239 -329.659234)
					(end 7.502906 -329.148694)
				)
				(xy 7.502906 -329.015344) (xy 7.260336 -329.015344)
				(arc
					(start 7.235952 -329.039982)
					(mid 6.803749 -329.337311)
					(end 7.101078 -328.905108)
				)
				(xy 7.181596 -328.824844) (xy 7.502906 -328.824844) (xy 7.502906 -328.659744) (xy 7.181596 -328.659744)
				(arc
					(start 7.101078 -328.57948)
					(mid 6.803749 -328.147277)
					(end 7.235952 -328.444606)
				)
				(xy 7.260336 -328.469244) (xy 7.502906 -328.469244)
			)
		)
	)
	(zone
		(layer "In5.Cu")
		(hatch none 0.5)
		(connect_pads
			(clearance 0)
		)
		(min_thickness 0.25)
		(keepout
			(tracks not_allowed)
			(vias allowed)
			(pads allowed)
			(copperpour not_allowed)
			(footprints allowed)
		)
		(placement
			(enabled no)
			(sheetname "")
		)
		(fill
			(thermal_gap 0.5)
			(thermal_bridge_width 0.5)
			(island_removal_mode 0)
		)
		(polygon
			(pts
				(arc
					(start 27.18054 -330.003658)
					(mid 26.67 -329.493118)
					(end 26.15946 -330.003658)
				)
				(arc
					(start 26.15946 -330.816204)
					(mid 26.669873 -331.326998)
					(end 27.18054 -330.816458)
				)
				(xy 27.18054 -330.682854) (xy 26.938224 -330.682854)
				(arc
					(start 26.913586 -330.707746)
					(mid 26.481383 -331.005075)
					(end 26.778712 -330.572872)
				)
				(xy 26.859484 -330.492354) (xy 27.18054 -330.492354) (xy 27.18054 -330.327254) (xy 26.858976 -330.327254)
				(arc
					(start 26.778712 -330.247244)
					(mid 26.481383 -329.815041)
					(end 26.913586 -330.11237)
				)
				(xy 26.937716 -330.136754) (xy 27.18054 -330.136754)
			)
		)
	)
	(zone
		(layer "In5.Cu")
		(hatch none 0.5)
		(connect_pads
			(clearance 0)
		)
		(min_thickness 0.25)
		(keepout
			(tracks not_allowed)
			(vias allowed)
			(pads allowed)
			(copperpour not_allowed)
			(footprints allowed)
		)
		(placement
			(enabled no)
			(sheetname "")
		)
		(fill
			(thermal_gap 0.5)
			(thermal_bridge_width 0.5)
			(island_removal_mode 0)
		)
		(polygon
			(pts
				(arc
					(start 7.502906 -307.535834)
					(mid 6.992366 -307.025294)
					(end 6.481826 -307.535834)
				)
				(arc
					(start 6.481826 -308.34838)
					(mid 6.992239 -308.859174)
					(end 7.502906 -308.348634)
				)
				(xy 7.502906 -308.215284) (xy 7.260336 -308.215284)
				(arc
					(start 7.235952 -308.239922)
					(mid 6.803749 -308.537251)
					(end 7.101078 -308.105048)
				)
				(xy 7.181596 -308.024784) (xy 7.502906 -308.024784) (xy 7.502906 -307.859684) (xy 7.181596 -307.859684)
				(arc
					(start 7.101078 -307.77942)
					(mid 6.803749 -307.347217)
					(end 7.235952 -307.644546)
				)
				(xy 7.260336 -307.669184) (xy 7.502906 -307.669184)
			)
		)
	)
	(zone
		(layer "In5.Cu")
		(hatch none 0.5)
		(connect_pads
			(clearance 0)
		)
		(min_thickness 0.25)
		(keepout
			(tracks not_allowed)
			(vias allowed)
			(pads allowed)
			(copperpour not_allowed)
			(footprints allowed)
		)
		(placement
			(enabled no)
			(sheetname "")
		)
		(fill
			(thermal_gap 0.5)
			(thermal_bridge_width 0.5)
			(island_removal_mode 0)
		)
		(polygon
			(pts
				(arc
					(start 27.18054 -128.8034)
					(mid 26.67 -128.29286)
					(end 26.15946 -128.8034)
				)
				(arc
					(start 26.15946 -129.615946)
					(mid 26.669873 -130.12674)
					(end 27.18054 -129.6162)
				)
				(xy 27.18054 -129.48285) (xy 26.93797 -129.48285)
				(arc
					(start 26.913586 -129.507488)
					(mid 26.481383 -129.804817)
					(end 26.778712 -129.372614)
				)
				(xy 26.85923 -129.29235) (xy 27.18054 -129.29235) (xy 27.18054 -129.12725) (xy 26.85923 -129.12725)
				(arc
					(start 26.778712 -129.046986)
					(mid 26.481383 -128.614783)
					(end 26.913586 -128.912112)
				)
				(xy 26.93797 -128.93675) (xy 27.18054 -128.93675)
			)
		)
	)
	(zone
		(layer "In5.Cu")
		(hatch none 0.5)
		(connect_pads
			(clearance 0)
		)
		(min_thickness 0.25)
		(keepout
			(tracks not_allowed)
			(vias allowed)
			(pads allowed)
			(copperpour not_allowed)
			(footprints allowed)
		)
		(placement
			(enabled no)
			(sheetname "")
		)
		(fill
			(thermal_gap 0.5)
			(thermal_bridge_width 0.5)
			(island_removal_mode 0)
		)
		(polygon
			(pts
				(arc
					(start 7.502906 -220.685106)
					(mid 6.992366 -220.174566)
					(end 6.481826 -220.685106)
				)
				(arc
					(start 6.481826 -221.497652)
					(mid 6.992239 -222.008446)
					(end 7.502906 -221.497906)
				)
				(xy 7.502906 -221.364556) (xy 7.260336 -221.364556)
				(arc
					(start 7.235952 -221.389194)
					(mid 6.803749 -221.686523)
					(end 7.101078 -221.25432)
				)
				(xy 7.181596 -221.174056) (xy 7.502906 -221.174056) (xy 7.502906 -221.008956) (xy 7.181596 -221.008956)
				(arc
					(start 7.101078 -220.928692)
					(mid 6.803749 -220.496489)
					(end 7.235952 -220.793818)
				)
				(xy 7.260336 -220.818456) (xy 7.502906 -220.818456)
			)
		)
	)
	(zone
		(layer "In5.Cu")
		(hatch none 0.5)
		(connect_pads
			(clearance 0)
		)
		(min_thickness 0.25)
		(keepout
			(tracks not_allowed)
			(vias allowed)
			(pads allowed)
			(copperpour not_allowed)
			(footprints allowed)
		)
		(placement
			(enabled no)
			(sheetname "")
		)
		(fill
			(thermal_gap 0.5)
			(thermal_bridge_width 0.5)
			(island_removal_mode 0)
		)
		(polygon
			(pts
				(arc
					(start 7.502906 -168.787064)
					(mid 6.992493 -168.27627)
					(end 6.481826 -168.78681)
				)
				(arc
					(start 6.481826 -169.59961)
					(mid 6.992366 -170.11015)
					(end 7.502906 -169.59961)
				)
				(xy 7.502906 -169.46626) (xy 7.260336 -169.46626)
				(arc
					(start 7.235952 -169.490898)
					(mid 6.803749 -169.788227)
					(end 7.101078 -169.356024)
				)
				(xy 7.181596 -169.27576) (xy 7.502906 -169.27576) (xy 7.502906 -169.11066) (xy 7.181596 -169.11066)
				(arc
					(start 7.101078 -169.030396)
					(mid 6.803749 -168.598193)
					(end 7.235952 -168.895522)
				)
				(xy 7.260336 -168.92016) (xy 7.502906 -168.92016)
			)
		)
	)
	(zone
		(layer "In5.Cu")
		(hatch none 0.5)
		(connect_pads
			(clearance 0)
		)
		(min_thickness 0.25)
		(keepout
			(tracks not_allowed)
			(vias allowed)
			(pads allowed)
			(copperpour not_allowed)
			(footprints allowed)
		)
		(placement
			(enabled no)
			(sheetname "")
		)
		(fill
			(thermal_gap 0.5)
			(thermal_bridge_width 0.5)
			(island_removal_mode 0)
		)
		(polygon
			(pts
				(arc
					(start 7.502906 -223.897952)
					(mid 6.992493 -223.387158)
					(end 6.481826 -223.897698)
				)
				(arc
					(start 6.481826 -224.710498)
					(mid 6.992366 -225.221038)
					(end 7.502906 -224.710498)
				)
				(xy 7.502906 -224.577148) (xy 7.260336 -224.577148)
				(arc
					(start 7.235952 -224.601786)
					(mid 6.803749 -224.899115)
					(end 7.101078 -224.466912)
				)
				(xy 7.181596 -224.386648) (xy 7.502906 -224.386648) (xy 7.502906 -224.221548) (xy 7.181596 -224.221548)
				(arc
					(start 7.101078 -224.141284)
					(mid 6.803749 -223.709081)
					(end 7.235952 -224.00641)
				)
				(xy 7.260336 -224.031048) (xy 7.502906 -224.031048)
			)
		)
	)
	(zone
		(layer "In5.Cu")
		(hatch none 0.5)
		(connect_pads
			(clearance 0)
		)
		(min_thickness 0.25)
		(keepout
			(tracks not_allowed)
			(vias allowed)
			(pads allowed)
			(copperpour not_allowed)
			(footprints allowed)
		)
		(placement
			(enabled no)
			(sheetname "")
		)
		(fill
			(thermal_gap 0.5)
			(thermal_bridge_width 0.5)
			(island_removal_mode 0)
		)
		(polygon
			(pts
				(arc
					(start 27.18054 -124.003562)
					(mid 26.67 -123.493022)
					(end 26.15946 -124.003562)
				)
				(arc
					(start 26.15946 -124.816108)
					(mid 26.669873 -125.326902)
					(end 27.18054 -124.816362)
				)
				(xy 27.18054 -124.682758) (xy 26.938224 -124.682758)
				(arc
					(start 26.913586 -124.70765)
					(mid 26.481383 -125.004979)
					(end 26.778712 -124.572776)
				)
				(xy 26.859484 -124.492258) (xy 27.18054 -124.492258) (xy 27.18054 -124.327158) (xy 26.858976 -124.327158)
				(arc
					(start 26.778712 -124.247148)
					(mid 26.481383 -123.814945)
					(end 26.913586 -124.112274)
				)
				(xy 26.937716 -124.136658) (xy 27.18054 -124.136658)
			)
		)
	)
	(zone
		(layer "In5.Cu")
		(hatch none 0.5)
		(connect_pads
			(clearance 0)
		)
		(min_thickness 0.25)
		(keepout
			(tracks not_allowed)
			(vias allowed)
			(pads allowed)
			(copperpour not_allowed)
			(footprints allowed)
		)
		(placement
			(enabled no)
			(sheetname "")
		)
		(fill
			(thermal_gap 0.5)
			(thermal_bridge_width 0.5)
			(island_removal_mode 0)
		)
		(polygon
			(pts
				(arc
					(start 220.840554 -54.583838)
					(mid 220.330141 -54.073044)
					(end 219.819474 -54.583584)
				)
				(xy 219.819474 -54.717188) (xy 220.06179 -54.717188)
				(arc
					(start 220.086428 -54.692296)
					(mid 220.518631 -54.394967)
					(end 220.221302 -54.82717)
				)
				(xy 220.14053 -54.907688) (xy 219.819474 -54.907688) (xy 219.819474 -55.072788) (xy 220.141038 -55.072788)
				(arc
					(start 220.221302 -55.152798)
					(mid 220.518631 -55.585001)
					(end 220.086428 -55.287672)
				)
				(xy 220.062298 -55.263288) (xy 219.819474 -55.263288)
				(arc
					(start 219.819474 -55.396384)
					(mid 220.330014 -55.906924)
					(end 220.840554 -55.396384)
				)
			)
		)
	)
	(zone
		(layer "In5.Cu")
		(hatch none 0.5)
		(connect_pads
			(clearance 0)
		)
		(min_thickness 0.25)
		(keepout
			(tracks not_allowed)
			(vias allowed)
			(pads allowed)
			(copperpour not_allowed)
			(footprints allowed)
		)
		(placement
			(enabled no)
			(sheetname "")
		)
		(fill
			(thermal_gap 0.5)
			(thermal_bridge_width 0.5)
			(island_removal_mode 0)
		)
		(polygon
			(pts
				(arc
					(start 7.502906 -408.735784)
					(mid 6.992366 -408.225244)
					(end 6.481826 -408.735784)
				)
				(arc
					(start 6.481826 -409.54833)
					(mid 6.992239 -410.059124)
					(end 7.502906 -409.548584)
				)
				(xy 7.502906 -409.415234) (xy 7.260336 -409.415234)
				(arc
					(start 7.235952 -409.439872)
					(mid 6.803749 -409.737201)
					(end 7.101078 -409.304998)
				)
				(xy 7.181596 -409.224734) (xy 7.502906 -409.224734) (xy 7.502906 -409.059634) (xy 7.181596 -409.059634)
				(arc
					(start 7.101078 -408.97937)
					(mid 6.803749 -408.547167)
					(end 7.235952 -408.844496)
				)
				(xy 7.260336 -408.869134) (xy 7.502906 -408.869134)
			)
		)
	)
	(zone
		(layer "In5.Cu")
		(hatch none 0.5)
		(connect_pads
			(clearance 0)
		)
		(min_thickness 0.25)
		(keepout
			(tracks not_allowed)
			(vias allowed)
			(pads allowed)
			(copperpour not_allowed)
			(footprints allowed)
		)
		(placement
			(enabled no)
			(sheetname "")
		)
		(fill
			(thermal_gap 0.5)
			(thermal_bridge_width 0.5)
			(island_removal_mode 0)
		)
		(polygon
			(pts
				(arc
					(start 35.84067 -260.583934)
					(mid 35.330257 -260.07314)
					(end 34.81959 -260.58368)
				)
				(xy 34.81959 -260.717284) (xy 35.061906 -260.717284)
				(arc
					(start 35.086544 -260.692392)
					(mid 35.518747 -260.395063)
					(end 35.221418 -260.827266)
				)
				(xy 35.140646 -260.907784) (xy 34.81959 -260.907784) (xy 34.81959 -261.072884) (xy 35.141154 -261.072884)
				(arc
					(start 35.221418 -261.152894)
					(mid 35.518747 -261.585097)
					(end 35.086544 -261.287768)
				)
				(xy 35.062414 -261.263384) (xy 34.81959 -261.263384)
				(arc
					(start 34.81959 -261.39648)
					(mid 35.33013 -261.90702)
					(end 35.84067 -261.39648)
				)
			)
		)
	)
	(zone
		(net "GND")
		(layer "In5.Cu")
		(hatch none 0.5)
		(connect_pads
			(clearance 0.5)
		)
		(min_thickness 0.25)
		(fill yes
			(thermal_gap 0.5)
			(thermal_bridge_width 0.5)
			(island_removal_mode 0)
		)
		(polygon
			(pts
				(xy 237.350554 -384.6576) (xy 256.666492 -384.6576) (xy 256.833624 -384.824732) (xy 256.833624 -405.694642)
				(xy 256.572766 -405.9555) (xy 251.12726 -405.9555) (xy 249.034554 -408.048206) (xy 237.333028 -408.048206)
				(xy 237.088172 -407.80335) (xy 237.088172 -384.919982)
			)
		)
	)
	(zone
		(layer "In5.Cu")
		(hatch none 0.5)
		(connect_pads
			(clearance 0)
		)
		(min_thickness 0.25)
		(keepout
			(tracks not_allowed)
			(vias allowed)
			(pads allowed)
			(copperpour not_allowed)
			(footprints allowed)
		)
		(placement
			(enabled no)
			(sheetname "")
		)
		(fill
			(thermal_gap 0.5)
			(thermal_bridge_width 0.5)
			(island_removal_mode 0)
		)
		(polygon
			(pts
				(arc
					(start 27.18054 -325.203566)
					(mid 26.67 -324.693026)
					(end 26.15946 -325.203566)
				)
				(arc
					(start 26.15946 -326.016112)
					(mid 26.669873 -326.526906)
					(end 27.18054 -326.016366)
				)
				(xy 27.18054 -325.882762) (xy 26.938224 -325.882762)
				(arc
					(start 26.913586 -325.907654)
					(mid 26.481383 -326.204983)
					(end 26.778712 -325.77278)
				)
				(xy 26.859484 -325.692262) (xy 27.18054 -325.692262) (xy 27.18054 -325.527162) (xy 26.858976 -325.527162)
				(arc
					(start 26.778712 -325.447152)
					(mid 26.481383 -325.014949)
					(end 26.913586 -325.312278)
				)
				(xy 26.937716 -325.336662) (xy 27.18054 -325.336662)
			)
		)
	)
	(zone
		(layer "In5.Cu")
		(hatch none 0.5)
		(connect_pads
			(clearance 0)
		)
		(min_thickness 0.25)
		(keepout
			(tracks not_allowed)
			(vias allowed)
			(pads allowed)
			(copperpour not_allowed)
			(footprints allowed)
		)
		(placement
			(enabled no)
			(sheetname "")
		)
		(fill
			(thermal_gap 0.5)
			(thermal_bridge_width 0.5)
			(island_removal_mode 0)
		)
		(polygon
			(pts
				(arc
					(start 7.502906 -340.386924)
					(mid 6.992493 -339.87613)
					(end 6.481826 -340.38667)
				)
				(arc
					(start 6.481826 -341.19947)
					(mid 6.992366 -341.71001)
					(end 7.502906 -341.19947)
				)
				(xy 7.502906 -341.06612) (xy 7.260336 -341.06612)
				(arc
					(start 7.235952 -341.090758)
					(mid 6.803749 -341.388087)
					(end 7.101078 -340.955884)
				)
				(xy 7.181596 -340.87562) (xy 7.502906 -340.87562) (xy 7.502906 -340.71052) (xy 7.181596 -340.71052)
				(arc
					(start 7.101078 -340.630256)
					(mid 6.803749 -340.198053)
					(end 7.235952 -340.495382)
				)
				(xy 7.260336 -340.52002) (xy 7.502906 -340.52002)
			)
		)
	)
	(zone
		(layer "In5.Cu")
		(hatch none 0.5)
		(connect_pads
			(clearance 0)
		)
		(min_thickness 0.25)
		(keepout
			(tracks not_allowed)
			(vias allowed)
			(pads allowed)
			(copperpour not_allowed)
			(footprints allowed)
		)
		(placement
			(enabled no)
			(sheetname "")
		)
		(fill
			(thermal_gap 0.5)
			(thermal_bridge_width 0.5)
			(island_removal_mode 0)
		)
		(polygon
			(pts
				(arc
					(start 35.84067 -466.583776)
					(mid 35.33013 -466.073236)
					(end 34.81959 -466.583776)
				)
				(xy 34.81959 -466.71738) (xy 35.061906 -466.71738)
				(arc
					(start 35.086544 -466.692488)
					(mid 35.518747 -466.395159)
					(end 35.221418 -466.827362)
				)
				(xy 35.140646 -466.90788) (xy 34.81959 -466.90788) (xy 34.81959 -467.07298) (xy 35.141154 -467.07298)
				(arc
					(start 35.221418 -467.15299)
					(mid 35.518747 -467.585193)
					(end 35.086544 -467.287864)
				)
				(xy 35.062414 -467.26348) (xy 34.81959 -467.26348)
				(arc
					(start 34.81959 -467.396322)
					(mid 35.330003 -467.907116)
					(end 35.84067 -467.396576)
				)
			)
		)
	)
	(zone
		(layer "In5.Cu")
		(hatch none 0.5)
		(connect_pads
			(clearance 0)
		)
		(min_thickness 0.25)
		(keepout
			(tracks not_allowed)
			(vias allowed)
			(pads allowed)
			(copperpour not_allowed)
			(footprints allowed)
		)
		(placement
			(enabled no)
			(sheetname "")
		)
		(fill
			(thermal_gap 0.5)
			(thermal_bridge_width 0.5)
			(island_removal_mode 0)
		)
		(polygon
			(pts
				(arc
					(start 7.502906 -155.974288)
					(mid 6.992493 -155.463494)
					(end 6.481826 -155.974034)
				)
				(arc
					(start 6.481826 -156.786834)
					(mid 6.992366 -157.297374)
					(end 7.502906 -156.786834)
				)
				(xy 7.502906 -156.653484) (xy 7.260336 -156.653484)
				(arc
					(start 7.235952 -156.678122)
					(mid 6.803749 -156.975451)
					(end 7.101078 -156.543248)
				)
				(xy 7.181596 -156.462984) (xy 7.502906 -156.462984) (xy 7.502906 -156.297884) (xy 7.181596 -156.297884)
				(arc
					(start 7.101078 -156.21762)
					(mid 6.803749 -155.785417)
					(end 7.235952 -156.082746)
				)
				(xy 7.260336 -156.107384) (xy 7.502906 -156.107384)
			)
		)
	)
	(zone
		(layer "In5.Cu")
		(hatch none 0.5)
		(connect_pads
			(clearance 0)
		)
		(min_thickness 0.25)
		(keepout
			(tracks not_allowed)
			(vias allowed)
			(pads allowed)
			(copperpour not_allowed)
			(footprints allowed)
		)
		(placement
			(enabled no)
			(sheetname "")
		)
		(fill
			(thermal_gap 0.5)
			(thermal_bridge_width 0.5)
			(island_removal_mode 0)
		)
		(polygon
			(pts
				(xy 7.502906 -282.088336)
				(arc
					(start 7.502906 -281.98699)
					(mid 6.992493 -281.476196)
					(end 6.481826 -281.986736)
				)
				(arc
					(start 6.481826 -282.799536)
					(mid 6.992366 -283.310076)
					(end 7.502906 -282.799536)
				)
				(xy 7.502906 -282.643072) (xy 7.40918 -282.659582) (xy 7.402322 -282.666186) (xy 7.371334 -282.666186)
				(xy 7.3406 -282.67152) (xy 7.33298 -282.666186) (xy 7.260336 -282.666186)
				(arc
					(start 7.235952 -282.690824)
					(mid 6.803749 -282.988153)
					(end 7.101078 -282.55595)
				)
				(xy 7.181596 -282.475686) (xy 7.35457 -282.475686) (xy 7.502906 -282.449524) (xy 7.502906 -282.281884)
				(xy 7.377938 -282.303982) (xy 7.37108 -282.310586) (xy 7.340092 -282.310586) (xy 7.309358 -282.31592)
				(xy 7.301738 -282.310586) (xy 7.181596 -282.310586)
				(arc
					(start 7.101078 -282.230322)
					(mid 6.803749 -281.798119)
					(end 7.235952 -282.095448)
				)
				(xy 7.260336 -282.120086) (xy 7.323328 -282.120086)
			)
		)
	)
	(zone
		(layer "In5.Cu")
		(hatch none 0.5)
		(connect_pads
			(clearance 0)
		)
		(min_thickness 0.25)
		(keepout
			(tracks not_allowed)
			(vias allowed)
			(pads allowed)
			(copperpour not_allowed)
			(footprints allowed)
		)
		(placement
			(enabled no)
			(sheetname "")
		)
		(fill
			(thermal_gap 0.5)
			(thermal_bridge_width 0.5)
			(island_removal_mode 0)
		)
		(polygon
			(pts
				(arc
					(start 220.840554 -260.583934)
					(mid 220.330141 -260.07314)
					(end 219.819474 -260.58368)
				)
				(xy 219.819474 -260.717284) (xy 220.06179 -260.717284)
				(arc
					(start 220.086428 -260.692392)
					(mid 220.518631 -260.395063)
					(end 220.221302 -260.827266)
				)
				(xy 220.14053 -260.907784) (xy 219.819474 -260.907784) (xy 219.819474 -261.072884) (xy 220.141038 -261.072884)
				(arc
					(start 220.221302 -261.152894)
					(mid 220.518631 -261.585097)
					(end 220.086428 -261.287768)
				)
				(xy 220.062298 -261.263384) (xy 219.819474 -261.263384)
				(arc
					(start 219.819474 -261.39648)
					(mid 220.330014 -261.90702)
					(end 220.840554 -261.39648)
				)
			)
		)
	)
	(zone
		(layer "In5.Cu")
		(hatch none 0.5)
		(connect_pads
			(clearance 0)
		)
		(min_thickness 0.25)
		(keepout
			(tracks not_allowed)
			(vias allowed)
			(pads allowed)
			(copperpour not_allowed)
			(footprints allowed)
		)
		(placement
			(enabled no)
			(sheetname "")
		)
		(fill
			(thermal_gap 0.5)
			(thermal_bridge_width 0.5)
			(island_removal_mode 0)
		)
		(polygon
			(pts
				(arc
					(start 220.840554 -376.384058)
					(mid 220.330141 -375.873264)
					(end 219.819474 -376.383804)
				)
				(xy 219.819474 -376.517154) (xy 220.062044 -376.517154)
				(arc
					(start 220.086428 -376.492516)
					(mid 220.518631 -376.195187)
					(end 220.221302 -376.62739)
				)
				(xy 220.140784 -376.707654) (xy 219.819474 -376.707654) (xy 219.819474 -376.872754) (xy 220.140784 -376.872754)
				(arc
					(start 220.221302 -376.953018)
					(mid 220.518631 -377.385221)
					(end 220.086428 -377.087892)
				)
				(xy 220.062044 -377.063254) (xy 219.819474 -377.063254)
				(arc
					(start 219.819474 -377.196604)
					(mid 220.330014 -377.707144)
					(end 220.840554 -377.196604)
				)
			)
		)
	)
	(zone
		(layer "In5.Cu")
		(hatch none 0.5)
		(connect_pads
			(clearance 0)
		)
		(min_thickness 0.25)
		(keepout
			(tracks not_allowed)
			(vias allowed)
			(pads allowed)
			(copperpour not_allowed)
			(footprints allowed)
		)
		(placement
			(enabled no)
			(sheetname "")
		)
		(fill
			(thermal_gap 0.5)
			(thermal_bridge_width 0.5)
			(island_removal_mode 0)
		)
		(polygon
			(pts
				(arc
					(start 7.502906 -288.336228)
					(mid 6.992493 -287.825434)
					(end 6.481826 -288.335974)
				)
				(arc
					(start 6.481826 -289.148774)
					(mid 6.992366 -289.659314)
					(end 7.502906 -289.148774)
				)
				(xy 7.502906 -289.015424) (xy 7.260336 -289.015424)
				(arc
					(start 7.235952 -289.040062)
					(mid 6.803749 -289.337391)
					(end 7.101078 -288.905188)
				)
				(xy 7.181596 -288.824924) (xy 7.502906 -288.824924) (xy 7.502906 -288.659824) (xy 7.181596 -288.659824)
				(arc
					(start 7.101078 -288.57956)
					(mid 6.803749 -288.147357)
					(end 7.235952 -288.444686)
				)
				(xy 7.260336 -288.469324) (xy 7.502906 -288.469324)
			)
		)
	)
	(zone
		(layer "In5.Cu")
		(hatch none 0.5)
		(connect_pads
			(clearance 0)
		)
		(min_thickness 0.25)
		(keepout
			(tracks not_allowed)
			(vias allowed)
			(pads allowed)
			(copperpour not_allowed)
			(footprints allowed)
		)
		(placement
			(enabled no)
			(sheetname "")
		)
		(fill
			(thermal_gap 0.5)
			(thermal_bridge_width 0.5)
			(island_removal_mode 0)
		)
		(polygon
			(pts
				(arc
					(start 27.18054 -222.203518)
					(mid 26.67 -221.692978)
					(end 26.15946 -222.203518)
				)
				(arc
					(start 26.15946 -223.016064)
					(mid 26.669873 -223.526858)
					(end 27.18054 -223.016318)
				)
				(xy 27.18054 -222.882714) (xy 26.938224 -222.882714)
				(arc
					(start 26.913586 -222.907606)
					(mid 26.481383 -223.204935)
					(end 26.778712 -222.772732)
				)
				(xy 26.859484 -222.692214) (xy 27.18054 -222.692214) (xy 27.18054 -222.527114) (xy 26.858976 -222.527114)
				(arc
					(start 26.778712 -222.447104)
					(mid 26.481383 -222.014901)
					(end 26.913586 -222.31223)
				)
				(xy 26.937716 -222.336614) (xy 27.18054 -222.336614)
			)
		)
	)
	(zone
		(layer "In5.Cu")
		(hatch none 0.5)
		(connect_pads
			(clearance 0)
		)
		(min_thickness 0.25)
		(keepout
			(tracks not_allowed)
			(vias allowed)
			(pads allowed)
			(copperpour not_allowed)
			(footprints allowed)
		)
		(placement
			(enabled no)
			(sheetname "")
		)
		(fill
			(thermal_gap 0.5)
			(thermal_bridge_width 0.5)
			(island_removal_mode 0)
		)
		(polygon
			(pts
				(arc
					(start 35.84067 -67.383914)
					(mid 35.330257 -66.87312)
					(end 34.81959 -67.38366)
				)
				(xy 34.81959 -67.51701) (xy 35.06216 -67.51701)
				(arc
					(start 35.086544 -67.492372)
					(mid 35.518747 -67.195043)
					(end 35.221418 -67.627246)
				)
				(xy 35.1409 -67.70751) (xy 34.81959 -67.70751) (xy 34.81959 -67.87261) (xy 35.1409 -67.87261)
				(arc
					(start 35.221418 -67.952874)
					(mid 35.518747 -68.385077)
					(end 35.086544 -68.087748)
				)
				(xy 35.06216 -68.06311) (xy 34.81959 -68.06311)
				(arc
					(start 34.81959 -68.19646)
					(mid 35.33013 -68.707)
					(end 35.84067 -68.19646)
				)
			)
		)
	)
	(zone
		(layer "In5.Cu")
		(hatch none 0.5)
		(connect_pads
			(clearance 0)
		)
		(min_thickness 0.25)
		(keepout
			(tracks not_allowed)
			(vias allowed)
			(pads allowed)
			(copperpour not_allowed)
			(footprints allowed)
		)
		(placement
			(enabled no)
			(sheetname "")
		)
		(fill
			(thermal_gap 0.5)
			(thermal_bridge_width 0.5)
			(island_removal_mode 0)
		)
		(polygon
			(pts
				(arc
					(start 7.502906 -230.33609)
					(mid 6.992493 -229.825296)
					(end 6.481826 -230.335836)
				)
				(arc
					(start 6.481826 -231.148636)
					(mid 6.992366 -231.659176)
					(end 7.502906 -231.148636)
				)
				(xy 7.502906 -231.015286) (xy 7.260336 -231.015286)
				(arc
					(start 7.235952 -231.039924)
					(mid 6.803749 -231.337253)
					(end 7.101078 -230.90505)
				)
				(xy 7.181596 -230.824786) (xy 7.502906 -230.824786) (xy 7.502906 -230.659686) (xy 7.181596 -230.659686)
				(arc
					(start 7.101078 -230.579422)
					(mid 6.803749 -230.147219)
					(end 7.235952 -230.444548)
				)
				(xy 7.260336 -230.469186) (xy 7.502906 -230.469186)
			)
		)
	)
	(zone
		(layer "In5.Cu")
		(hatch none 0.5)
		(connect_pads
			(clearance 0)
		)
		(min_thickness 0.25)
		(keepout
			(tracks not_allowed)
			(vias allowed)
			(pads allowed)
			(copperpour not_allowed)
			(footprints allowed)
		)
		(placement
			(enabled no)
			(sheetname "")
		)
		(fill
			(thermal_gap 0.5)
			(thermal_bridge_width 0.5)
			(island_removal_mode 0)
		)
		(polygon
			(pts
				(arc
					(start 27.18054 -227.00361)
					(mid 26.67 -226.49307)
					(end 26.15946 -227.00361)
				)
				(arc
					(start 26.15946 -227.816156)
					(mid 26.669873 -228.32695)
					(end 27.18054 -227.81641)
				)
				(xy 27.18054 -227.682806) (xy 26.938224 -227.682806)
				(arc
					(start 26.913586 -227.707698)
					(mid 26.481383 -228.005027)
					(end 26.778712 -227.572824)
				)
				(xy 26.859484 -227.492306) (xy 27.18054 -227.492306) (xy 27.18054 -227.327206) (xy 26.858976 -227.327206)
				(arc
					(start 26.778712 -227.247196)
					(mid 26.481383 -226.814993)
					(end 26.913586 -227.112322)
				)
				(xy 26.937716 -227.136706) (xy 27.18054 -227.136706)
			)
		)
	)
	(zone
		(layer "In5.Cu")
		(hatch none 0.5)
		(connect_pads
			(clearance 0)
		)
		(min_thickness 0.25)
		(keepout
			(tracks not_allowed)
			(vias allowed)
			(pads allowed)
			(copperpour not_allowed)
			(footprints allowed)
		)
		(placement
			(enabled no)
			(sheetname "")
		)
		(fill
			(thermal_gap 0.5)
			(thermal_bridge_width 0.5)
			(island_removal_mode 0)
		)
		(polygon
			(pts
				(arc
					(start 27.18054 -119.20347)
					(mid 26.67 -118.69293)
					(end 26.15946 -119.20347)
				)
				(arc
					(start 26.15946 -120.016016)
					(mid 26.669873 -120.52681)
					(end 27.18054 -120.01627)
				)
				(xy 27.18054 -119.882666) (xy 26.938224 -119.882666)
				(arc
					(start 26.913586 -119.907558)
					(mid 26.481383 -120.204887)
					(end 26.778712 -119.772684)
				)
				(xy 26.859484 -119.692166) (xy 27.18054 -119.692166) (xy 27.18054 -119.527066) (xy 26.858976 -119.527066)
				(arc
					(start 26.778712 -119.447056)
					(mid 26.481383 -119.014853)
					(end 26.913586 -119.312182)
				)
				(xy 26.937716 -119.336566) (xy 27.18054 -119.336566)
			)
		)
	)
	(zone
		(layer "In5.Cu")
		(hatch none 0.5)
		(connect_pads
			(clearance 0)
		)
		(min_thickness 0.25)
		(keepout
			(tracks not_allowed)
			(vias allowed)
			(pads allowed)
			(copperpour not_allowed)
			(footprints allowed)
		)
		(placement
			(enabled no)
			(sheetname "")
		)
		(fill
			(thermal_gap 0.5)
			(thermal_bridge_width 0.5)
			(island_removal_mode 0)
		)
		(polygon
			(pts
				(arc
					(start 7.502906 -431.184558)
					(mid 6.992493 -430.673764)
					(end 6.481826 -431.184304)
				)
				(arc
					(start 6.481826 -431.997104)
					(mid 6.992366 -432.507644)
					(end 7.502906 -431.997104)
				)
				(xy 7.502906 -431.863754) (xy 7.260336 -431.863754)
				(arc
					(start 7.235952 -431.888392)
					(mid 6.803749 -432.185721)
					(end 7.101078 -431.753518)
				)
				(xy 7.181596 -431.673254) (xy 7.502906 -431.673254) (xy 7.502906 -431.508154) (xy 7.181596 -431.508154)
				(arc
					(start 7.101078 -431.42789)
					(mid 6.803749 -430.995687)
					(end 7.235952 -431.293016)
				)
				(xy 7.260336 -431.317654) (xy 7.502906 -431.317654)
			)
		)
	)
	(zone
		(layer "In5.Cu")
		(hatch none 0.5)
		(connect_pads
			(clearance 0)
		)
		(min_thickness 0.25)
		(keepout
			(tracks not_allowed)
			(vias allowed)
			(pads allowed)
			(copperpour not_allowed)
			(footprints allowed)
		)
		(placement
			(enabled no)
			(sheetname "")
		)
		(fill
			(thermal_gap 0.5)
			(thermal_bridge_width 0.5)
			(island_removal_mode 0)
		)
		(polygon
			(pts
				(arc
					(start 7.502906 -217.485468)
					(mid 6.992493 -216.974674)
					(end 6.481826 -217.485214)
				)
				(arc
					(start 6.481826 -218.298014)
					(mid 6.992366 -218.808554)
					(end 7.502906 -218.298014)
				)
				(xy 7.502906 -218.164664) (xy 7.260336 -218.164664)
				(arc
					(start 7.235952 -218.189302)
					(mid 6.803749 -218.486631)
					(end 7.101078 -218.054428)
				)
				(xy 7.181596 -217.974164) (xy 7.502906 -217.974164) (xy 7.502906 -217.809064) (xy 7.181596 -217.809064)
				(arc
					(start 7.101078 -217.7288)
					(mid 6.803749 -217.296597)
					(end 7.235952 -217.593926)
				)
				(xy 7.260336 -217.618564) (xy 7.502906 -217.618564)
			)
		)
	)
	(zone
		(layer "In5.Cu")
		(hatch none 0.5)
		(connect_pads
			(clearance 0)
		)
		(min_thickness 0.25)
		(keepout
			(tracks not_allowed)
			(vias allowed)
			(pads allowed)
			(copperpour not_allowed)
			(footprints allowed)
		)
		(placement
			(enabled no)
			(sheetname "")
		)
		(fill
			(thermal_gap 0.5)
			(thermal_bridge_width 0.5)
			(island_removal_mode 0)
		)
		(polygon
			(pts
				(arc
					(start 7.502906 -337.187032)
					(mid 6.992493 -336.676238)
					(end 6.481826 -337.186778)
				)
				(arc
					(start 6.481826 -337.999578)
					(mid 6.992366 -338.510118)
					(end 7.502906 -337.999578)
				)
				(xy 7.502906 -337.866228) (xy 7.260336 -337.866228)
				(arc
					(start 7.235952 -337.890866)
					(mid 6.803749 -338.188195)
					(end 7.101078 -337.755992)
				)
				(xy 7.181596 -337.675728) (xy 7.502906 -337.675728) (xy 7.502906 -337.510628) (xy 7.181596 -337.510628)
				(arc
					(start 7.101078 -337.430364)
					(mid 6.803749 -336.998161)
					(end 7.235952 -337.29549)
				)
				(xy 7.260336 -337.320128) (xy 7.502906 -337.320128)
			)
		)
	)
	(zone
		(layer "In5.Cu")
		(hatch none 0.5)
		(connect_pads
			(clearance 0)
		)
		(min_thickness 0.25)
		(keepout
			(tracks not_allowed)
			(vias allowed)
			(pads allowed)
			(copperpour not_allowed)
			(footprints allowed)
		)
		(placement
			(enabled no)
			(sheetname "")
		)
		(fill
			(thermal_gap 0.5)
			(thermal_bridge_width 0.5)
			(island_removal_mode 0)
		)
		(polygon
			(pts
				(arc
					(start 35.84067 -479.383852)
					(mid 35.33013 -478.873312)
					(end 34.81959 -479.383852)
				)
				(xy 34.81959 -479.517202) (xy 35.06216 -479.517202)
				(arc
					(start 35.086544 -479.492564)
					(mid 35.518747 -479.195235)
					(end 35.221418 -479.627438)
				)
				(xy 35.1409 -479.707702) (xy 34.81959 -479.707702) (xy 34.81959 -479.872802) (xy 35.1409 -479.872802)
				(arc
					(start 35.221418 -479.953066)
					(mid 35.518747 -480.385269)
					(end 35.086544 -480.08794)
				)
				(xy 35.06216 -480.063302) (xy 34.81959 -480.063302)
				(arc
					(start 34.81959 -480.196398)
					(mid 35.330003 -480.707192)
					(end 35.84067 -480.196652)
				)
			)
		)
	)
	(zone
		(layer "In5.Cu")
		(hatch none 0.5)
		(connect_pads
			(clearance 0)
		)
		(min_thickness 0.25)
		(keepout
			(tracks not_allowed)
			(vias allowed)
			(pads allowed)
			(copperpour not_allowed)
			(footprints allowed)
		)
		(placement
			(enabled no)
			(sheetname "")
		)
		(fill
			(thermal_gap 0.5)
			(thermal_bridge_width 0.5)
			(island_removal_mode 0)
		)
		(polygon
			(pts
				(arc
					(start 27.18054 -334.803496)
					(mid 26.67 -334.292956)
					(end 26.15946 -334.803496)
				)
				(arc
					(start 26.15946 -335.616042)
					(mid 26.669873 -336.126836)
					(end 27.18054 -335.616296)
				)
				(xy 27.18054 -335.482946) (xy 26.93797 -335.482946)
				(arc
					(start 26.913586 -335.507584)
					(mid 26.481383 -335.804913)
					(end 26.778712 -335.37271)
				)
				(xy 26.85923 -335.292446) (xy 27.18054 -335.292446) (xy 27.18054 -335.127346) (xy 26.85923 -335.127346)
				(arc
					(start 26.778712 -335.047082)
					(mid 26.481383 -334.614879)
					(end 26.913586 -334.912208)
				)
				(xy 26.93797 -334.936846) (xy 27.18054 -334.936846)
			)
		)
	)
	(zone
		(layer "In5.Cu")
		(hatch none 0.5)
		(connect_pads
			(clearance 0)
		)
		(min_thickness 0.25)
		(keepout
			(tracks not_allowed)
			(vias allowed)
			(pads allowed)
			(copperpour not_allowed)
			(footprints allowed)
		)
		(placement
			(enabled no)
			(sheetname "")
		)
		(fill
			(thermal_gap 0.5)
			(thermal_bridge_width 0.5)
			(island_removal_mode 0)
		)
		(polygon
			(pts
				(arc
					(start 220.840554 -363.583982)
					(mid 220.330141 -363.073188)
					(end 219.819474 -363.583728)
				)
				(xy 219.819474 -363.717332) (xy 220.06179 -363.717332)
				(arc
					(start 220.086428 -363.69244)
					(mid 220.518631 -363.395111)
					(end 220.221302 -363.827314)
				)
				(xy 220.14053 -363.907832) (xy 219.819474 -363.907832) (xy 219.819474 -364.072932) (xy 220.141038 -364.072932)
				(arc
					(start 220.221302 -364.152942)
					(mid 220.518631 -364.585145)
					(end 220.086428 -364.287816)
				)
				(xy 220.062298 -364.263432) (xy 219.819474 -364.263432)
				(arc
					(start 219.819474 -364.396528)
					(mid 220.330014 -364.907068)
					(end 220.840554 -364.396528)
				)
			)
		)
	)
	(zone
		(net "VDD_DIFF_3")
		(layer "In5.Cu")
		(hatch none 0.5)
		(connect_pads
			(clearance 0.5)
		)
		(min_thickness 0.25)
		(fill yes
			(thermal_gap 0.5)
			(thermal_bridge_width 0.5)
			(island_removal_mode 0)
		)
		(polygon
			(pts
				(xy 82.423 -221.742) (xy 99.314 -221.742) (xy 104.267 -216.789) (xy 104.267 -208.28) (xy 99.06 -203.073)
				(xy 81.661 -203.073) (xy 78.74 -205.994) (xy 78.74 -218.059)
			)
		)
	)
	(zone
		(layer "In5.Cu")
		(hatch none 0.5)
		(connect_pads
			(clearance 0)
		)
		(min_thickness 0.25)
		(keepout
			(tracks not_allowed)
			(vias allowed)
			(pads allowed)
			(copperpour not_allowed)
			(footprints allowed)
		)
		(placement
			(enabled no)
			(sheetname "")
		)
		(fill
			(thermal_gap 0.5)
			(thermal_bridge_width 0.5)
			(island_removal_mode 0)
		)
		(polygon
			(pts
				(xy 7.502906 -278.88819)
				(arc
					(start 7.502906 -278.786844)
					(mid 6.992493 -278.27605)
					(end 6.481826 -278.78659)
				)
				(arc
					(start 6.481826 -279.59939)
					(mid 6.992366 -280.10993)
					(end 7.502906 -279.59939)
				)
				(xy 7.502906 -279.442926) (xy 7.40918 -279.459436) (xy 7.402322 -279.46604) (xy 7.371334 -279.46604)
				(xy 7.3406 -279.471374) (xy 7.33298 -279.46604) (xy 7.260336 -279.46604)
				(arc
					(start 7.235952 -279.490678)
					(mid 6.803749 -279.788007)
					(end 7.101078 -279.355804)
				)
				(xy 7.181596 -279.27554) (xy 7.35457 -279.27554) (xy 7.502906 -279.249378) (xy 7.502906 -279.081738)
				(xy 7.377938 -279.103836) (xy 7.37108 -279.11044) (xy 7.340092 -279.11044) (xy 7.309358 -279.115774)
				(xy 7.301738 -279.11044) (xy 7.181596 -279.11044)
				(arc
					(start 7.101078 -279.030176)
					(mid 6.803749 -278.597973)
					(end 7.235952 -278.895302)
				)
				(xy 7.260336 -278.91994) (xy 7.323328 -278.91994)
			)
		)
	)
	(zone
		(net "GND")
		(layer "In6.Cu")
		(hatch none 0.5)
		(connect_pads
			(clearance 0.5)
		)
		(min_thickness 0.25)
		(fill yes
			(thermal_gap 0.5)
			(thermal_bridge_width 0.5)
			(island_removal_mode 0)
		)
		(polygon
			(pts
				(arc
					(start 0.999998 -0.763016)
					(mid 0.832426 -0.832426)
					(end 0.763016 -0.999998)
				)
				(xy 0.763016 -186.42584) (xy 0.816102 -186.478926)
				(arc
					(start 4.400042 -186.478926)
					(mid 6.263132 -188.342016)
					(end 4.400042 -190.205106)
				)
				(xy 0.816102 -190.205106) (xy 0.763016 -190.258192) (xy 0.763016 -312.425842) (xy 0.816102 -312.478928)
				(arc
					(start 4.400042 -312.478928)
					(mid 6.263132 -314.342018)
					(end 4.400042 -316.205108)
				)
				(xy 0.816102 -316.205108) (xy 0.763016 -316.258194) (xy 0.763016 -418.425884) (xy 0.816102 -418.47897)
				(arc
					(start 4.400042 -418.47897)
					(mid 6.263132 -420.34206)
					(end 4.400042 -422.204896)
				)
				(xy 0.816356 -422.204896) (xy 0.763016 -422.258236)
				(arc
					(start 0.763016 -505.000006)
					(mid 0.832426 -505.167578)
					(end 0.999998 -505.236988)
				)
				(arc
					(start 262.50011 -505.236988)
					(mid 262.667682 -505.167578)
					(end 262.737092 -505.000006)
				)
				(xy 262.737092 -428.396146) (xy 262.18388 -427.842934)
				(arc
					(start 261.2898 -427.842934)
					(mid 259.767467 -427.212363)
					(end 259.136896 -425.69003)
				)
				(xy 259.136896 -411.80131) (xy 258.583684 -411.248098)
				(arc
					(start 252.394974 -411.248098)
					(mid 251.097034 -409.950158)
					(end 252.394974 -408.651964)
				)
				(xy 258.583684 -408.651964) (xy 259.136896 -408.098752)
				(arc
					(start 259.136896 -364.309914)
					(mid 259.767541 -362.787655)
					(end 261.2898 -362.15701)
				)
				(xy 262.18388 -362.15701) (xy 262.737092 -361.603798)
				(arc
					(start 262.737092 -0.999998)
					(mid 262.667682 -0.832426)
					(end 262.50011 -0.763016)
				)
				(xy 37.667692 -0.763016)
				(arc
					(start 36.343336 -3.365754)
					(mid 36.283478 -3.527891)
					(end 36.263072 -3.69951)
				)
				(arc
					(start 36.263072 -4.500118)
					(mid 34.000186 -6.763004)
					(end 31.737046 -4.500118)
				)
				(arc
					(start 31.737046 -3.700018)
					(mid 31.716858 -3.528435)
					(end 31.65729 -3.366262)
				)
				(xy 31.657036 -3.366262) (xy 30.332426 -0.763016)
			)
		)
		(polygon
			(pts
				(arc
					(start 37.33927 -491.231428)
					(mid 36.72713 -490.619288)
					(end 36.11499 -491.231428)
				)
				(arc
					(start 36.11499 -492.349282)
					(mid 36.727257 -492.961168)
					(end 37.33927 -492.349028)
				)
			)
		)
		(polygon
			(pts
				(arc
					(start 222.339154 -491.231174)
					(mid 221.726887 -490.619288)
					(end 221.114874 -491.231428)
				)
				(arc
					(start 221.114874 -492.349028)
					(mid 221.727014 -492.961168)
					(end 222.339154 -492.349028)
				)
			)
		)
		(polygon
			(pts
				(arc
					(start 35.84067 -488.983782)
					(mid 35.33013 -488.473242)
					(end 34.81959 -488.983782)
				)
				(arc
					(start 34.81959 -489.796836)
					(mid 35.330257 -490.307122)
					(end 35.84067 -489.796582)
				)
			)
		)
		(polygon
			(pts
				(arc
					(start 220.840554 -488.983528)
					(mid 220.329887 -488.473242)
					(end 219.819474 -488.983782)
				)
				(arc
					(start 219.819474 -489.796582)
					(mid 220.330014 -490.307122)
					(end 220.840554 -489.796582)
				)
			)
		)
		(polygon
			(pts
				(arc
					(start 222.339154 -486.431082)
					(mid 221.726887 -485.819196)
					(end 221.114874 -486.431336)
				)
				(arc
					(start 221.114874 -487.548936)
					(mid 221.727014 -488.161076)
					(end 222.339154 -487.548936)
				)
			)
		)
		(polygon
			(pts
				(arc
					(start 37.33927 -486.431082)
					(mid 36.727003 -485.819196)
					(end 36.11499 -486.431336)
				)
				(arc
					(start 36.11499 -487.548936)
					(mid 36.72713 -488.161076)
					(end 37.33927 -487.548936)
				)
			)
		)
		(polygon
			(pts
				(arc
					(start 35.84067 -484.18369)
					(mid 35.33013 -483.67315)
					(end 34.81959 -484.18369)
				)
				(arc
					(start 34.81959 -484.996744)
					(mid 35.330257 -485.50703)
					(end 35.84067 -484.99649)
				)
			)
		)
		(polygon
			(pts
				(arc
					(start 220.840554 -484.183436)
					(mid 220.329887 -483.67315)
					(end 219.819474 -484.18369)
				)
				(arc
					(start 219.819474 -484.99649)
					(mid 220.330014 -485.50703)
					(end 220.840554 -484.99649)
				)
			)
		)
		(polygon
			(pts
				(arc
					(start 37.33927 -481.631244)
					(mid 36.72713 -481.019104)
					(end 36.11499 -481.631244)
				)
				(arc
					(start 36.11499 -482.749098)
					(mid 36.727257 -483.360984)
					(end 37.33927 -482.748844)
				)
			)
		)
		(polygon
			(pts
				(arc
					(start 222.339154 -481.63099)
					(mid 221.726887 -481.019104)
					(end 221.114874 -481.631244)
				)
				(arc
					(start 221.114874 -482.748844)
					(mid 221.727014 -483.360984)
					(end 222.339154 -482.748844)
				)
			)
		)
		(polygon
			(pts
				(arc
					(start 35.84067 -479.383852)
					(mid 35.33013 -478.873312)
					(end 34.81959 -479.383852)
				)
				(arc
					(start 34.81959 -480.196906)
					(mid 35.330257 -480.707192)
					(end 35.84067 -480.196652)
				)
			)
		)
		(polygon
			(pts
				(arc
					(start 220.840554 -479.383598)
					(mid 220.329887 -478.873312)
					(end 219.819474 -479.383852)
				)
				(arc
					(start 219.819474 -480.196652)
					(mid 220.330014 -480.707192)
					(end 220.840554 -480.196652)
				)
			)
		)
		(polygon
			(pts
				(arc
					(start 233.897424 -472.579446)
					(mid 233.386884 -472.068906)
					(end 232.876344 -472.579446)
				)
				(arc
					(start 232.876344 -473.3925)
					(mid 233.387011 -473.902786)
					(end 233.897424 -473.392246)
				)
			)
		)
		(polygon
			(pts
				(arc
					(start 48.89754 -472.579192)
					(mid 48.386873 -472.068906)
					(end 47.87646 -472.579446)
				)
				(arc
					(start 47.87646 -473.392246)
					(mid 48.387 -473.902786)
					(end 48.89754 -473.392246)
				)
			)
		)
		(polygon
			(pts
				(arc
					(start 230.720138 -472.300808)
					(mid 231.230424 -471.790141)
					(end 230.719884 -471.279728)
				)
				(arc
					(start 229.907084 -471.279728)
					(mid 229.396544 -471.790268)
					(end 229.907084 -472.300808)
				)
			)
		)
		(polygon
			(pts
				(arc
					(start 45.720254 -472.300808)
					(mid 46.23054 -471.790141)
					(end 45.72 -471.279728)
				)
				(arc
					(start 44.9072 -471.279728)
					(mid 44.39666 -471.790268)
					(end 44.9072 -472.300808)
				)
			)
		)
		(polygon
			(pts
				(arc
					(start 37.33927 -468.831422)
					(mid 36.72713 -468.219282)
					(end 36.11499 -468.831422)
				)
				(arc
					(start 36.11499 -469.949276)
					(mid 36.727257 -470.561162)
					(end 37.33927 -469.949022)
				)
			)
		)
		(polygon
			(pts
				(arc
					(start 222.339154 -468.831168)
					(mid 221.726887 -468.219282)
					(end 221.114874 -468.831422)
				)
				(arc
					(start 221.114874 -469.949022)
					(mid 221.727014 -470.561162)
					(end 222.339154 -469.949022)
				)
			)
		)
		(polygon
			(pts
				(arc
					(start 35.84067 -466.583776)
					(mid 35.33013 -466.073236)
					(end 34.81959 -466.583776)
				)
				(arc
					(start 34.81959 -467.39683)
					(mid 35.330257 -467.907116)
					(end 35.84067 -467.396576)
				)
			)
		)
		(polygon
			(pts
				(arc
					(start 220.840554 -466.583522)
					(mid 220.329887 -466.073236)
					(end 219.819474 -466.583776)
				)
				(arc
					(start 219.819474 -467.396576)
					(mid 220.330014 -467.907116)
					(end 220.840554 -467.396576)
				)
			)
		)
		(polygon
			(pts
				(arc
					(start 27.18054 -450.603366)
					(mid 26.669873 -450.09308)
					(end 26.15946 -450.60362)
				)
				(arc
					(start 26.15946 -451.41642)
					(mid 26.67 -451.92696)
					(end 27.18054 -451.41642)
				)
			)
		)
		(polygon
			(pts
				(arc
					(start 7.2898 -449.978272)
					(mid 7.80034 -449.467732)
					(end 7.2898 -448.957192)
				)
				(arc
					(start 6.476746 -448.957192)
					(mid 5.96646 -449.467859)
					(end 6.477 -449.978272)
				)
			)
		)
		(polygon
			(pts
				(arc
					(start 25.88514 -448.05092)
					(mid 25.272873 -447.439034)
					(end 24.66086 -448.051174)
				)
				(arc
					(start 24.66086 -449.168774)
					(mid 25.273 -449.780914)
					(end 25.88514 -449.168774)
				)
			)
		)
		(polygon
			(pts
				(xy 3.494532 -446.887854) (xy 1.005332 -446.887854) (xy 1.005332 -448.195954) (xy 3.494532 -448.195954)
			)
		)
		(polygon
			(pts
				(arc
					(start 7.502906 -446.384172)
					(mid 6.992366 -445.873632)
					(end 6.481826 -446.384172)
				)
				(arc
					(start 6.481826 -447.197226)
					(mid 6.992493 -447.707512)
					(end 7.502906 -447.196972)
				)
			)
		)
		(polygon
			(pts
				(xy 3.494532 -444.487808) (xy 1.005332 -444.487808) (xy 1.005332 -445.795908) (xy 3.494532 -445.795908)
			)
		)
		(polygon
			(pts
				(arc
					(start 5.59054 -444.735204)
					(mid 5.08 -444.224664)
					(end 4.56946 -444.735204)
				)
				(arc
					(start 4.56946 -445.548258)
					(mid 5.080127 -446.058544)
					(end 5.59054 -445.548004)
				)
			)
		)
		(polygon
			(pts
				(arc
					(start 17.78254 -444.603378)
					(mid 17.272 -444.092838)
					(end 16.76146 -444.603378)
				)
				(arc
					(start 16.76146 -445.416432)
					(mid 17.272127 -445.926718)
					(end 17.78254 -445.416178)
				)
			)
		)
		(polygon
			(pts
				(arc
					(start 32.26054 -444.584582)
					(mid 31.749873 -444.074296)
					(end 31.23946 -444.584836)
				)
				(arc
					(start 31.23946 -445.397636)
					(mid 31.75 -445.908176)
					(end 32.26054 -445.397636)
				)
			)
		)
		(polygon
			(pts
				(arc
					(start 7.502906 -443.18428)
					(mid 6.992366 -442.67374)
					(end 6.481826 -443.18428)
				)
				(arc
					(start 6.481826 -443.997334)
					(mid 6.992493 -444.50762)
					(end 7.502906 -443.99708)
				)
			)
		)
		(polygon
			(pts
				(xy 3.494532 -441.287916) (xy 1.005332 -441.287916) (xy 1.005332 -442.596016) (xy 3.494532 -442.596016)
			)
		)
		(polygon
			(pts
				(arc
					(start 5.59054 -441.535312)
					(mid 5.08 -441.024772)
					(end 4.56946 -441.535312)
				)
				(arc
					(start 4.56946 -442.348366)
					(mid 5.080127 -442.858652)
					(end 5.59054 -442.348112)
				)
			)
		)
		(polygon
			(pts
				(arc
					(start 7.502906 -439.984134)
					(mid 6.992366 -439.473594)
					(end 6.481826 -439.984134)
				)
				(arc
					(start 6.481826 -440.797188)
					(mid 6.992493 -441.307474)
					(end 7.502906 -440.796934)
				)
			)
		)
		(polygon
			(pts
				(xy 3.494532 -438.088024) (xy 1.005332 -438.088024) (xy 1.005332 -439.39587) (xy 3.494532 -439.39587)
			)
		)
		(polygon
			(pts
				(arc
					(start 5.59054 -438.335166)
					(mid 5.08 -437.824626)
					(end 4.56946 -438.335166)
				)
				(arc
					(start 4.56946 -439.14822)
					(mid 5.080127 -439.658506)
					(end 5.59054 -439.147966)
				)
			)
		)
		(polygon
			(pts
				(arc
					(start 27.18054 -437.80329)
					(mid 26.669873 -437.293004)
					(end 26.15946 -437.803544)
				)
				(arc
					(start 26.15946 -438.616344)
					(mid 26.67 -439.126884)
					(end 27.18054 -438.616344)
				)
			)
		)
		(polygon
			(pts
				(arc
					(start 7.502906 -436.784242)
					(mid 6.992366 -436.273702)
					(end 6.481826 -436.784242)
				)
				(arc
					(start 6.481826 -437.597296)
					(mid 6.992493 -438.107582)
					(end 7.502906 -437.597042)
				)
			)
		)
		(polygon
			(pts
				(xy 3.494532 -434.887878) (xy 1.005332 -434.887878) (xy 1.005332 -436.195978) (xy 3.494532 -436.195978)
			)
		)
		(polygon
			(pts
				(arc
					(start 25.88514 -435.251098)
					(mid 25.272873 -434.639212)
					(end 24.66086 -435.251352)
				)
				(arc
					(start 24.66086 -436.368952)
					(mid 25.273 -436.981092)
					(end 25.88514 -436.368952)
				)
			)
		)
		(polygon
			(pts
				(arc
					(start 5.59054 -435.135274)
					(mid 5.08 -434.624734)
					(end 4.56946 -435.135274)
				)
				(arc
					(start 4.56946 -435.948328)
					(mid 5.080127 -436.458614)
					(end 5.59054 -435.948074)
				)
			)
		)
		(polygon
			(pts
				(arc
					(start 27.18054 -433.003452)
					(mid 26.669873 -432.493166)
					(end 26.15946 -433.003706)
				)
				(arc
					(start 26.15946 -433.816506)
					(mid 26.67 -434.327046)
					(end 27.18054 -433.816506)
				)
			)
		)
		(polygon
			(pts
				(arc
					(start 7.502906 -431.18405)
					(mid 6.992239 -430.673764)
					(end 6.481826 -431.184304)
				)
				(arc
					(start 6.481826 -431.997104)
					(mid 6.992366 -432.507644)
					(end 7.502906 -431.997104)
				)
			)
		)
		(polygon
			(pts
				(arc
					(start 72.90054 -431.139346)
					(mid 72.389873 -430.62906)
					(end 71.87946 -431.1396)
				)
				(arc
					(start 71.87946 -431.9524)
					(mid 72.39 -432.46294)
					(end 72.90054 -431.9524)
				)
			)
		)
		(polygon
			(pts
				(arc
					(start 25.88514 -430.451006)
					(mid 25.272873 -429.83912)
					(end 24.66086 -430.45126)
				)
				(arc
					(start 24.66086 -431.56886)
					(mid 25.273 -432.181)
					(end 25.88514 -431.56886)
				)
			)
		)
		(polygon
			(pts
				(arc
					(start 75.0824 -430.63414)
					(mid 75.59294 -430.1236)
					(end 75.0824 -429.61306)
				)
				(arc
					(start 74.269346 -429.61306)
					(mid 73.75906 -430.123727)
					(end 74.2696 -430.63414)
				)
			)
		)
		(polygon
			(pts
				(xy 3.494532 -429.28794) (xy 1.005332 -429.28794) (xy 1.005332 -430.595786) (xy 3.494532 -430.595786)
			)
		)
		(polygon
			(pts
				(arc
					(start 5.59054 -429.534828)
					(mid 5.079873 -429.024542)
					(end 4.56946 -429.535082)
				)
				(arc
					(start 4.56946 -430.347882)
					(mid 5.08 -430.858422)
					(end 5.59054 -430.347882)
				)
			)
		)
		(polygon
			(pts
				(arc
					(start 27.18054 -428.20336)
					(mid 26.669873 -427.693074)
					(end 26.15946 -428.203614)
				)
				(arc
					(start 26.15946 -429.016414)
					(mid 26.67 -429.526954)
					(end 27.18054 -429.016414)
				)
			)
		)
		(polygon
			(pts
				(arc
					(start 7.502906 -427.983904)
					(mid 6.992239 -427.473618)
					(end 6.481826 -427.984158)
				)
				(arc
					(start 6.481826 -428.796958)
					(mid 6.992366 -429.307498)
					(end 7.502906 -428.796958)
				)
			)
		)
		(polygon
			(pts
				(xy 3.494532 -426.087794) (xy 1.005332 -426.087794) (xy 1.005332 -427.395894) (xy 3.494532 -427.395894)
			)
		)
		(polygon
			(pts
				(arc
					(start 5.59054 -426.334936)
					(mid 5.079873 -425.82465)
					(end 4.56946 -426.33519)
				)
				(arc
					(start 4.56946 -427.14799)
					(mid 5.08 -427.65853)
					(end 5.59054 -427.14799)
				)
			)
		)
		(polygon
			(pts
				(arc
					(start 25.88514 -425.650914)
					(mid 25.272873 -425.039028)
					(end 24.66086 -425.651168)
				)
				(arc
					(start 24.66086 -426.768768)
					(mid 25.273 -427.380908)
					(end 25.88514 -426.768768)
				)
			)
		)
		(polygon
			(pts
				(arc
					(start 7.502906 -424.784012)
					(mid 6.992239 -424.273726)
					(end 6.481826 -424.784266)
				)
				(arc
					(start 6.481826 -425.597066)
					(mid 6.992366 -426.107606)
					(end 7.502906 -425.597066)
				)
			)
		)
		(polygon
			(pts
				(xy 3.494532 -422.887902) (xy 1.005332 -422.887902) (xy 1.005332 -424.196002) (xy 3.494532 -424.196002)
			)
		)
		(polygon
			(pts
				(arc
					(start 5.59054 -423.135044)
					(mid 5.079873 -422.624758)
					(end 4.56946 -423.135298)
				)
				(arc
					(start 4.56946 -423.948098)
					(mid 5.08 -424.458638)
					(end 5.59054 -423.948098)
				)
			)
		)
		(polygon
			(pts
				(xy 3.494532 -416.487864) (xy 1.005332 -416.487864) (xy 1.005332 -417.795964) (xy 3.494532 -417.795964)
			)
		)
		(polygon
			(pts
				(arc
					(start 5.59054 -416.735006)
					(mid 5.079873 -416.22472)
					(end 4.56946 -416.73526)
				)
				(arc
					(start 4.56946 -417.54806)
					(mid 5.08 -418.0586)
					(end 5.59054 -417.54806)
				)
			)
		)
		(polygon
			(pts
				(arc
					(start 7.502906 -415.135568)
					(mid 6.992239 -414.625282)
					(end 6.481826 -415.135822)
				)
				(arc
					(start 6.481826 -415.948622)
					(mid 6.992366 -416.459162)
					(end 7.502906 -415.948622)
				)
			)
		)
		(polygon
			(pts
				(xy 3.494532 -413.287972) (xy 1.005332 -413.287972) (xy 1.005332 -414.595818) (xy 3.494532 -414.595818)
			)
		)
		(polygon
			(pts
				(arc
					(start 5.59054 -413.535114)
					(mid 5.08 -413.024574)
					(end 4.56946 -413.535114)
				)
				(arc
					(start 4.56946 -414.348168)
					(mid 5.080127 -414.858454)
					(end 5.59054 -414.347914)
				)
			)
		)
		(polygon
			(pts
				(arc
					(start 7.502906 -411.935676)
					(mid 6.992366 -411.425136)
					(end 6.481826 -411.935676)
				)
				(arc
					(start 6.481826 -412.74873)
					(mid 6.992493 -413.259016)
					(end 7.502906 -412.748476)
				)
			)
		)
		(polygon
			(pts
				(xy 3.494532 -410.087826) (xy 1.005332 -410.087826) (xy 1.005332 -411.395926) (xy 3.494532 -411.395926)
			)
		)
		(polygon
			(pts
				(arc
					(start 5.59054 -410.335222)
					(mid 5.08 -409.824682)
					(end 4.56946 -410.335222)
				)
				(arc
					(start 4.56946 -411.148276)
					(mid 5.080127 -411.658562)
					(end 5.59054 -411.148022)
				)
			)
		)
		(polygon
			(pts
				(arc
					(start 7.502906 -408.735784)
					(mid 6.992366 -408.225244)
					(end 6.481826 -408.735784)
				)
				(arc
					(start 6.481826 -409.548838)
					(mid 6.992493 -410.059124)
					(end 7.502906 -409.548584)
				)
			)
		)
		(polygon
			(pts
				(xy 3.494532 -406.887934) (xy 1.005332 -406.887934) (xy 1.005332 -408.19578) (xy 3.494532 -408.19578)
			)
		)
		(polygon
			(pts
				(arc
					(start 5.59054 -407.135076)
					(mid 5.08 -406.624536)
					(end 4.56946 -407.135076)
				)
				(arc
					(start 4.56946 -407.94813)
					(mid 5.080127 -408.458416)
					(end 5.59054 -407.947876)
				)
			)
		)
		(polygon
			(pts
				(arc
					(start 7.502906 -405.535638)
					(mid 6.992366 -405.025098)
					(end 6.481826 -405.535638)
				)
				(arc
					(start 6.481826 -406.348692)
					(mid 6.992493 -406.858978)
					(end 7.502906 -406.348438)
				)
			)
		)
		(polygon
			(pts
				(xy 3.494532 -403.687788) (xy 1.005332 -403.687788) (xy 1.005332 -404.995888) (xy 3.494532 -404.995888)
			)
		)
		(polygon
			(pts
				(arc
					(start 5.59054 -403.935184)
					(mid 5.08 -403.424644)
					(end 4.56946 -403.935184)
				)
				(arc
					(start 4.56946 -404.748238)
					(mid 5.080127 -405.258524)
					(end 5.59054 -404.747984)
				)
			)
		)
		(polygon
			(pts
				(arc
					(start 7.502906 -402.335746)
					(mid 6.992366 -401.825206)
					(end 6.481826 -402.335746)
				)
				(arc
					(start 6.481826 -403.1488)
					(mid 6.992493 -403.659086)
					(end 7.502906 -403.148546)
				)
			)
		)
		(polygon
			(pts
				(xy 3.494532 -398.08785) (xy 1.005332 -398.08785) (xy 1.005332 -399.39595) (xy 3.494532 -399.39595)
			)
		)
		(polygon
			(pts
				(arc
					(start 5.59054 -398.334992)
					(mid 5.079873 -397.824706)
					(end 4.56946 -398.335246)
				)
				(arc
					(start 4.56946 -399.148046)
					(mid 5.08 -399.658586)
					(end 5.59054 -399.148046)
				)
			)
		)
		(polygon
			(pts
				(arc
					(start 7.502906 -396.735554)
					(mid 6.992239 -396.225268)
					(end 6.481826 -396.735808)
				)
				(arc
					(start 6.481826 -397.548608)
					(mid 6.992366 -398.059148)
					(end 7.502906 -397.548608)
				)
			)
		)
		(polygon
			(pts
				(xy 3.494532 -394.887958) (xy 1.005332 -394.887958) (xy 1.005332 -396.195804) (xy 3.494532 -396.195804)
			)
		)
		(polygon
			(pts
				(arc
					(start 5.59054 -395.134846)
					(mid 5.079873 -394.62456)
					(end 4.56946 -395.1351)
				)
				(arc
					(start 4.56946 -395.9479)
					(mid 5.08 -396.45844)
					(end 5.59054 -395.9479)
				)
			)
		)
		(polygon
			(pts
				(arc
					(start 7.502906 -393.535408)
					(mid 6.992239 -393.025122)
					(end 6.481826 -393.535662)
				)
				(arc
					(start 6.481826 -394.348462)
					(mid 6.992366 -394.859002)
					(end 7.502906 -394.348462)
				)
			)
		)
		(polygon
			(pts
				(xy 3.494532 -391.687812) (xy 1.005332 -391.687812) (xy 1.005332 -392.995912) (xy 3.494532 -392.995912)
			)
		)
		(polygon
			(pts
				(arc
					(start 5.59054 -391.934954)
					(mid 5.079873 -391.424668)
					(end 4.56946 -391.935208)
				)
				(arc
					(start 4.56946 -392.748008)
					(mid 5.08 -393.258548)
					(end 5.59054 -392.748008)
				)
			)
		)
		(polygon
			(pts
				(arc
					(start 7.502906 -390.335516)
					(mid 6.992239 -389.82523)
					(end 6.481826 -390.33577)
				)
				(arc
					(start 6.481826 -391.14857)
					(mid 6.992366 -391.65911)
					(end 7.502906 -391.14857)
				)
			)
		)
		(polygon
			(pts
				(xy 3.494532 -388.48792) (xy 1.005332 -388.48792) (xy 1.005332 -389.79602) (xy 3.494532 -389.79602)
			)
		)
		(polygon
			(pts
				(arc
					(start 5.59054 -388.735062)
					(mid 5.079873 -388.224776)
					(end 4.56946 -388.735316)
				)
				(arc
					(start 4.56946 -389.548116)
					(mid 5.08 -390.058656)
					(end 5.59054 -389.548116)
				)
			)
		)
		(polygon
			(pts
				(arc
					(start 222.339154 -388.231126)
					(mid 221.726887 -387.61924)
					(end 221.114874 -388.23138)
				)
				(arc
					(start 221.114874 -389.34898)
					(mid 221.727014 -389.96112)
					(end 222.339154 -389.34898)
				)
			)
		)
		(polygon
			(pts
				(arc
					(start 37.33927 -388.231126)
					(mid 36.727003 -387.61924)
					(end 36.11499 -388.23138)
				)
				(arc
					(start 36.11499 -389.34898)
					(mid 36.72713 -389.96112)
					(end 37.33927 -389.34898)
				)
			)
		)
		(polygon
			(pts
				(arc
					(start 7.502906 -387.13537)
					(mid 6.992239 -386.625084)
					(end 6.481826 -387.135624)
				)
				(arc
					(start 6.481826 -387.948424)
					(mid 6.992366 -388.458964)
					(end 7.502906 -387.948424)
				)
			)
		)
		(polygon
			(pts
				(arc
					(start 220.840554 -385.98348)
					(mid 220.329887 -385.473194)
					(end 219.819474 -385.983734)
				)
				(arc
					(start 219.819474 -386.796534)
					(mid 220.330014 -387.307074)
					(end 220.840554 -386.796534)
				)
			)
		)
		(polygon
			(pts
				(arc
					(start 35.84067 -385.98348)
					(mid 35.330003 -385.473194)
					(end 34.81959 -385.983734)
				)
				(arc
					(start 34.81959 -386.796534)
					(mid 35.33013 -387.307074)
					(end 35.84067 -386.796534)
				)
			)
		)
		(polygon
			(pts
				(arc
					(start 9.195308 -386.113782)
					(mid 9.705594 -385.603115)
					(end 9.195054 -385.092702)
				)
				(arc
					(start 8.382254 -385.092702)
					(mid 7.871714 -385.603242)
					(end 8.382254 -386.113782)
				)
			)
		)
		(polygon
			(pts
				(xy 3.494532 -384.487928) (xy 1.005332 -384.487928) (xy 1.005332 -385.795774) (xy 3.494532 -385.795774)
			)
		)
		(polygon
			(pts
				(arc
					(start 222.339154 -383.431034)
					(mid 221.726887 -382.819148)
					(end 221.114874 -383.431288)
				)
				(arc
					(start 221.114874 -384.548888)
					(mid 221.727014 -385.161028)
					(end 222.339154 -384.548888)
				)
			)
		)
		(polygon
			(pts
				(arc
					(start 37.33927 -383.431034)
					(mid 36.727003 -382.819148)
					(end 36.11499 -383.431288)
				)
				(arc
					(start 36.11499 -384.548888)
					(mid 36.72713 -385.161028)
					(end 37.33927 -384.548888)
				)
			)
		)
		(polygon
			(pts
				(arc
					(start 220.840554 -381.183388)
					(mid 220.329887 -380.673102)
					(end 219.819474 -381.183642)
				)
				(arc
					(start 219.819474 -381.996442)
					(mid 220.330014 -382.506982)
					(end 220.840554 -381.996442)
				)
			)
		)
		(polygon
			(pts
				(arc
					(start 35.84067 -381.183388)
					(mid 35.330003 -380.673102)
					(end 34.81959 -381.183642)
				)
				(arc
					(start 34.81959 -381.996442)
					(mid 35.33013 -382.506982)
					(end 35.84067 -381.996442)
				)
			)
		)
		(polygon
			(pts
				(arc
					(start 222.339154 -378.630942)
					(mid 221.726887 -378.019056)
					(end 221.114874 -378.631196)
				)
				(arc
					(start 221.114874 -379.748796)
					(mid 221.727014 -380.360936)
					(end 222.339154 -379.748796)
				)
			)
		)
		(polygon
			(pts
				(arc
					(start 37.33927 -378.630942)
					(mid 36.727003 -378.019056)
					(end 36.11499 -378.631196)
				)
				(arc
					(start 36.11499 -379.748796)
					(mid 36.72713 -380.360936)
					(end 37.33927 -379.748796)
				)
			)
		)
		(polygon
			(pts
				(arc
					(start 220.840554 -376.38355)
					(mid 220.329887 -375.873264)
					(end 219.819474 -376.383804)
				)
				(arc
					(start 219.819474 -377.196604)
					(mid 220.330014 -377.707144)
					(end 220.840554 -377.196604)
				)
			)
		)
		(polygon
			(pts
				(arc
					(start 35.84067 -376.38355)
					(mid 35.330003 -375.873264)
					(end 34.81959 -376.383804)
				)
				(arc
					(start 34.81959 -377.196604)
					(mid 35.33013 -377.707144)
					(end 35.84067 -377.196604)
				)
			)
		)
		(polygon
			(pts
				(arc
					(start 233.897424 -369.579398)
					(mid 233.386884 -369.068858)
					(end 232.876344 -369.579398)
				)
				(arc
					(start 232.876344 -370.392452)
					(mid 233.387011 -370.902738)
					(end 233.897424 -370.392198)
				)
			)
		)
		(polygon
			(pts
				(arc
					(start 48.89754 -369.579144)
					(mid 48.386873 -369.068858)
					(end 47.87646 -369.579398)
				)
				(arc
					(start 47.87646 -370.392198)
					(mid 48.387 -370.902738)
					(end 48.89754 -370.392198)
				)
			)
		)
		(polygon
			(pts
				(arc
					(start 230.720138 -369.30076)
					(mid 231.230424 -368.790093)
					(end 230.719884 -368.27968)
				)
				(arc
					(start 229.907084 -368.27968)
					(mid 229.396544 -368.79022)
					(end 229.907084 -369.30076)
				)
			)
		)
		(polygon
			(pts
				(arc
					(start 45.72 -369.30076)
					(mid 46.23054 -368.79022)
					(end 45.72 -368.27968)
				)
				(arc
					(start 44.906946 -368.27968)
					(mid 44.39666 -368.790347)
					(end 44.9072 -369.30076)
				)
			)
		)
		(polygon
			(pts
				(arc
					(start 222.339154 -365.83112)
					(mid 221.726887 -365.219234)
					(end 221.114874 -365.831374)
				)
				(arc
					(start 221.114874 -366.948974)
					(mid 221.727014 -367.561114)
					(end 222.339154 -366.948974)
				)
			)
		)
		(polygon
			(pts
				(arc
					(start 37.33927 -365.83112)
					(mid 36.727003 -365.219234)
					(end 36.11499 -365.831374)
				)
				(arc
					(start 36.11499 -366.948974)
					(mid 36.72713 -367.561114)
					(end 37.33927 -366.948974)
				)
			)
		)
		(polygon
			(pts
				(arc
					(start 220.840554 -363.583474)
					(mid 220.329887 -363.073188)
					(end 219.819474 -363.583728)
				)
				(arc
					(start 219.819474 -364.396528)
					(mid 220.330014 -364.907068)
					(end 220.840554 -364.396528)
				)
			)
		)
		(polygon
			(pts
				(arc
					(start 35.84067 -363.583474)
					(mid 35.330003 -363.073188)
					(end 34.81959 -363.583728)
				)
				(arc
					(start 34.81959 -364.396528)
					(mid 35.33013 -364.907068)
					(end 35.84067 -364.396528)
				)
			)
		)
		(polygon
			(pts
				(xy 3.494532 -357.688134) (xy 1.005332 -357.688134) (xy 1.005332 -358.996234) (xy 3.494532 -358.996234)
			)
		)
		(polygon
			(pts
				(arc
					(start 5.59054 -357.935276)
					(mid 5.079873 -357.42499)
					(end 4.56946 -357.93553)
				)
				(arc
					(start 4.56946 -358.74833)
					(mid 5.08 -359.25887)
					(end 5.59054 -358.74833)
				)
			)
		)
		(polygon
			(pts
				(arc
					(start 7.502906 -356.335838)
					(mid 6.992366 -355.825298)
					(end 6.481826 -356.335838)
				)
				(arc
					(start 6.481826 -357.148892)
					(mid 6.992493 -357.659178)
					(end 7.502906 -357.148638)
				)
			)
		)
		(polygon
			(pts
				(xy 3.494532 -354.487988) (xy 1.005332 -354.487988) (xy 1.005332 -355.796088) (xy 3.494532 -355.796088)
			)
		)
		(polygon
			(pts
				(arc
					(start 5.59054 -354.73513)
					(mid 5.079873 -354.224844)
					(end 4.56946 -354.735384)
				)
				(arc
					(start 4.56946 -355.548184)
					(mid 5.08 -356.058724)
					(end 5.59054 -355.548184)
				)
			)
		)
		(polygon
			(pts
				(arc
					(start 7.502906 -353.135692)
					(mid 6.992239 -352.625406)
					(end 6.481826 -353.135946)
				)
				(arc
					(start 6.481826 -353.948746)
					(mid 6.992366 -354.459286)
					(end 7.502906 -353.948746)
				)
			)
		)
		(polygon
			(pts
				(xy 3.494532 -351.288096) (xy 1.005332 -351.288096) (xy 1.005332 -352.596196) (xy 3.494532 -352.596196)
			)
		)
		(polygon
			(pts
				(arc
					(start 5.59054 -351.535238)
					(mid 5.079873 -351.024952)
					(end 4.56946 -351.535492)
				)
				(arc
					(start 4.56946 -352.348292)
					(mid 5.08 -352.858832)
					(end 5.59054 -352.348292)
				)
			)
		)
		(polygon
			(pts
				(arc
					(start 7.502906 -349.9358)
					(mid 6.992366 -349.42526)
					(end 6.481826 -349.9358)
				)
				(arc
					(start 6.481826 -350.748854)
					(mid 6.992493 -351.25914)
					(end 7.502906 -350.7486)
				)
			)
		)
		(polygon
			(pts
				(xy 3.494532 -348.088204) (xy 1.005332 -348.088204) (xy 1.005332 -349.39605) (xy 3.494532 -349.39605)
			)
		)
		(polygon
			(pts
				(arc
					(start 5.59054 -348.335092)
					(mid 5.079873 -347.824806)
					(end 4.56946 -348.335346)
				)
				(arc
					(start 4.56946 -349.148146)
					(mid 5.08 -349.658686)
					(end 5.59054 -349.148146)
				)
			)
		)
		(polygon
			(pts
				(arc
					(start 27.18054 -347.603572)
					(mid 26.67 -347.093032)
					(end 26.15946 -347.603572)
				)
				(arc
					(start 26.15946 -348.416626)
					(mid 26.670127 -348.926912)
					(end 27.18054 -348.416372)
				)
			)
		)
		(polygon
			(pts
				(arc
					(start 7.502906 -346.735908)
					(mid 6.992366 -346.225368)
					(end 6.481826 -346.735908)
				)
				(arc
					(start 6.481826 -347.548962)
					(mid 6.992493 -348.059248)
					(end 7.502906 -347.548708)
				)
			)
		)
		(polygon
			(pts
				(xy 3.494532 -344.888058) (xy 1.005332 -344.888058) (xy 1.005332 -346.196158) (xy 3.494532 -346.196158)
			)
		)
		(polygon
			(pts
				(arc
					(start 5.59054 -345.1352)
					(mid 5.079873 -344.624914)
					(end 4.56946 -345.135454)
				)
				(arc
					(start 4.56946 -345.948254)
					(mid 5.08 -346.458794)
					(end 5.59054 -345.948254)
				)
			)
		)
		(polygon
			(pts
				(arc
					(start 25.88514 -345.050872)
					(mid 25.272873 -344.438986)
					(end 24.66086 -345.051126)
				)
				(arc
					(start 24.66086 -346.168726)
					(mid 25.273 -346.780866)
					(end 25.88514 -346.168726)
				)
			)
		)
		(polygon
			(pts
				(arc
					(start 7.502906 -343.586562)
					(mid 6.992239 -343.076276)
					(end 6.481826 -343.586816)
				)
				(arc
					(start 6.481826 -344.399616)
					(mid 6.992366 -344.910156)
					(end 7.502906 -344.399616)
				)
			)
		)
		(polygon
			(pts
				(xy 3.494532 -341.688166) (xy 1.005332 -341.688166) (xy 1.005332 -342.996012) (xy 3.494532 -342.996012)
			)
		)
		(polygon
			(pts
				(arc
					(start 5.59054 -341.935054)
					(mid 5.079873 -341.424768)
					(end 4.56946 -341.935308)
				)
				(arc
					(start 4.56946 -342.748108)
					(mid 5.08 -343.258648)
					(end 5.59054 -342.748108)
				)
			)
		)
		(polygon
			(pts
				(arc
					(start 17.78254 -341.60333)
					(mid 17.272 -341.09279)
					(end 16.76146 -341.60333)
				)
				(arc
					(start 16.76146 -342.416384)
					(mid 17.272127 -342.92667)
					(end 17.78254 -342.41613)
				)
			)
		)
		(polygon
			(pts
				(arc
					(start 33.40354 -341.58428)
					(mid 32.892873 -341.073994)
					(end 32.38246 -341.584534)
				)
				(arc
					(start 32.38246 -342.397334)
					(mid 32.893 -342.907874)
					(end 33.40354 -342.397334)
				)
			)
		)
		(polygon
			(pts
				(arc
					(start 7.502906 -340.386416)
					(mid 6.992239 -339.87613)
					(end 6.481826 -340.38667)
				)
				(arc
					(start 6.481826 -341.19947)
					(mid 6.992366 -341.71001)
					(end 7.502906 -341.19947)
				)
			)
		)
		(polygon
			(pts
				(xy 3.494532 -338.48802) (xy 1.005332 -338.48802) (xy 1.005332 -339.79612) (xy 3.494532 -339.79612)
			)
		)
		(polygon
			(pts
				(arc
					(start 5.59054 -338.735162)
					(mid 5.079873 -338.224876)
					(end 4.56946 -338.735416)
				)
				(arc
					(start 4.56946 -339.548216)
					(mid 5.08 -340.058756)
					(end 5.59054 -339.548216)
				)
			)
		)
		(polygon
			(pts
				(arc
					(start 7.502906 -337.186524)
					(mid 6.992239 -336.676238)
					(end 6.481826 -337.186778)
				)
				(arc
					(start 6.481826 -337.999578)
					(mid 6.992366 -338.510118)
					(end 7.502906 -337.999578)
				)
			)
		)
		(polygon
			(pts
				(xy 3.494532 -335.288128) (xy 1.005332 -335.288128) (xy 1.005332 -336.596228) (xy 3.494532 -336.596228)
			)
		)
		(polygon
			(pts
				(arc
					(start 5.59054 -335.53527)
					(mid 5.079873 -335.024984)
					(end 4.56946 -335.535524)
				)
				(arc
					(start 4.56946 -336.348324)
					(mid 5.08 -336.858864)
					(end 5.59054 -336.348324)
				)
			)
		)
		(polygon
			(pts
				(arc
					(start 27.18054 -334.803496)
					(mid 26.67 -334.292956)
					(end 26.15946 -334.803496)
				)
				(arc
					(start 26.15946 -335.61655)
					(mid 26.670127 -336.126836)
					(end 27.18054 -335.616296)
				)
			)
		)
		(polygon
			(pts
				(arc
					(start 7.502906 -333.986378)
					(mid 6.992239 -333.476092)
					(end 6.481826 -333.986632)
				)
				(arc
					(start 6.481826 -334.799432)
					(mid 6.992366 -335.309972)
					(end 7.502906 -334.799432)
				)
			)
		)
		(polygon
			(pts
				(arc
					(start 25.88514 -332.251304)
					(mid 25.273 -331.639164)
					(end 24.66086 -332.251304)
				)
				(arc
					(start 24.66086 -333.369158)
					(mid 25.273127 -333.981044)
					(end 25.88514 -333.368904)
				)
			)
		)
		(polygon
			(pts
				(xy 3.494532 -329.68819) (xy 1.005332 -329.68819) (xy 1.005332 -330.996036) (xy 3.494532 -330.996036)
			)
		)
		(polygon
			(pts
				(arc
					(start 27.18054 -330.003658)
					(mid 26.67 -329.493118)
					(end 26.15946 -330.003658)
				)
				(arc
					(start 26.15946 -330.816712)
					(mid 26.670127 -331.326998)
					(end 27.18054 -330.816458)
				)
			)
		)
		(polygon
			(pts
				(arc
					(start 5.59054 -329.935078)
					(mid 5.079873 -329.424792)
					(end 4.56946 -329.935332)
				)
				(arc
					(start 4.56946 -330.748132)
					(mid 5.08 -331.258672)
					(end 5.59054 -330.748132)
				)
			)
		)
		(polygon
			(pts
				(arc
					(start 7.502906 -328.335894)
					(mid 6.992366 -327.825354)
					(end 6.481826 -328.335894)
				)
				(arc
					(start 6.481826 -329.148948)
					(mid 6.992493 -329.659234)
					(end 7.502906 -329.148694)
				)
			)
		)
		(polygon
			(pts
				(arc
					(start 25.88514 -327.451212)
					(mid 25.273 -326.839072)
					(end 24.66086 -327.451212)
				)
				(arc
					(start 24.66086 -328.569066)
					(mid 25.273127 -329.180952)
					(end 25.88514 -328.568812)
				)
			)
		)
		(polygon
			(pts
				(xy 3.494532 -326.488044) (xy 1.005332 -326.488044) (xy 1.005332 -327.796144) (xy 3.494532 -327.796144)
			)
		)
		(polygon
			(pts
				(arc
					(start 5.59054 -326.735186)
					(mid 5.079873 -326.2249)
					(end 4.56946 -326.73544)
				)
				(arc
					(start 4.56946 -327.54824)
					(mid 5.08 -328.05878)
					(end 5.59054 -327.54824)
				)
			)
		)
		(polygon
			(pts
				(arc
					(start 27.18054 -325.203566)
					(mid 26.67 -324.693026)
					(end 26.15946 -325.203566)
				)
				(arc
					(start 26.15946 -326.01662)
					(mid 26.670127 -326.526906)
					(end 27.18054 -326.016366)
				)
			)
		)
		(polygon
			(pts
				(arc
					(start 7.502906 -325.136002)
					(mid 6.992366 -324.625462)
					(end 6.481826 -325.136002)
				)
				(arc
					(start 6.481826 -325.949056)
					(mid 6.992493 -326.459342)
					(end 7.502906 -325.948802)
				)
			)
		)
		(polygon
			(pts
				(xy 3.494532 -323.288152) (xy 1.005332 -323.288152) (xy 1.005332 -324.595998) (xy 3.494532 -324.595998)
			)
		)
		(polygon
			(pts
				(arc
					(start 5.59054 -323.53504)
					(mid 5.079873 -323.024754)
					(end 4.56946 -323.535294)
				)
				(arc
					(start 4.56946 -324.348094)
					(mid 5.08 -324.858634)
					(end 5.59054 -324.348094)
				)
			)
		)
		(polygon
			(pts
				(arc
					(start 25.88514 -322.65112)
					(mid 25.273 -322.03898)
					(end 24.66086 -322.65112)
				)
				(arc
					(start 24.66086 -323.768974)
					(mid 25.273127 -324.38086)
					(end 25.88514 -323.76872)
				)
			)
		)
		(polygon
			(pts
				(arc
					(start 7.502906 -321.935856)
					(mid 6.992366 -321.425316)
					(end 6.481826 -321.935856)
				)
				(arc
					(start 6.481826 -322.74891)
					(mid 6.992493 -323.259196)
					(end 7.502906 -322.748656)
				)
			)
		)
		(polygon
			(pts
				(xy 3.494532 -320.088006) (xy 1.005332 -320.088006) (xy 1.005332 -321.396106) (xy 3.494532 -321.396106)
			)
		)
		(polygon
			(pts
				(arc
					(start 5.59054 -320.335148)
					(mid 5.079873 -319.824862)
					(end 4.56946 -320.335402)
				)
				(arc
					(start 4.56946 -321.148202)
					(mid 5.08 -321.658742)
					(end 5.59054 -321.148202)
				)
			)
		)
		(polygon
			(pts
				(arc
					(start 7.502906 -318.735964)
					(mid 6.992366 -318.225424)
					(end 6.481826 -318.735964)
				)
				(arc
					(start 6.481826 -319.549018)
					(mid 6.992493 -320.059304)
					(end 7.502906 -319.548764)
				)
			)
		)
		(polygon
			(pts
				(xy 3.494532 -316.888114) (xy 1.005332 -316.888114) (xy 1.005332 -318.196214) (xy 3.494532 -318.196214)
			)
		)
		(polygon
			(pts
				(arc
					(start 5.59054 -317.135256)
					(mid 5.079873 -316.62497)
					(end 4.56946 -317.13551)
				)
				(arc
					(start 4.56946 -317.94831)
					(mid 5.08 -318.45885)
					(end 5.59054 -317.94831)
				)
			)
		)
		(polygon
			(pts
				(arc
					(start 7.502906 -310.73598)
					(mid 6.992366 -310.22544)
					(end 6.481826 -310.73598)
				)
				(arc
					(start 6.481826 -311.549034)
					(mid 6.992493 -312.05932)
					(end 7.502906 -311.54878)
				)
			)
		)
		(polygon
			(pts
				(xy 3.494532 -308.88813) (xy 1.005332 -308.88813) (xy 1.005332 -310.19623) (xy 3.494532 -310.19623)
			)
		)
		(polygon
			(pts
				(arc
					(start 5.59054 -309.135272)
					(mid 5.079873 -308.624986)
					(end 4.56946 -309.135526)
				)
				(arc
					(start 4.56946 -309.948326)
					(mid 5.08 -310.458866)
					(end 5.59054 -309.948326)
				)
			)
		)
		(polygon
			(pts
				(arc
					(start 7.502906 -307.535834)
					(mid 6.992366 -307.025294)
					(end 6.481826 -307.535834)
				)
				(arc
					(start 6.481826 -308.348888)
					(mid 6.992493 -308.859174)
					(end 7.502906 -308.348634)
				)
			)
		)
		(polygon
			(pts
				(xy 3.494532 -305.687984) (xy 1.005332 -305.687984) (xy 1.005332 -306.996084) (xy 3.494532 -306.996084)
			)
		)
		(polygon
			(pts
				(arc
					(start 5.59054 -305.935126)
					(mid 5.079873 -305.42484)
					(end 4.56946 -305.93538)
				)
				(arc
					(start 4.56946 -306.74818)
					(mid 5.08 -307.25872)
					(end 5.59054 -306.74818)
				)
			)
		)
		(polygon
			(pts
				(arc
					(start 7.502906 -304.335942)
					(mid 6.992366 -303.825402)
					(end 6.481826 -304.335942)
				)
				(arc
					(start 6.481826 -305.148996)
					(mid 6.992493 -305.659282)
					(end 7.502906 -305.148742)
				)
			)
		)
		(polygon
			(pts
				(xy 3.494532 -302.488092) (xy 1.005332 -302.488092) (xy 1.005332 -303.796192) (xy 3.494532 -303.796192)
			)
		)
		(polygon
			(pts
				(arc
					(start 5.59054 -302.735234)
					(mid 5.079873 -302.224948)
					(end 4.56946 -302.735488)
				)
				(arc
					(start 4.56946 -303.548288)
					(mid 5.08 -304.058828)
					(end 5.59054 -303.548288)
				)
			)
		)
		(polygon
			(pts
				(arc
					(start 7.502906 -301.135796)
					(mid 6.992366 -300.625256)
					(end 6.481826 -301.135796)
				)
				(arc
					(start 6.481826 -301.94885)
					(mid 6.992493 -302.459136)
					(end 7.502906 -301.948596)
				)
			)
		)
		(polygon
			(pts
				(xy 3.494532 -299.2882) (xy 1.005332 -299.2882) (xy 1.005332 -300.596046) (xy 3.494532 -300.596046)
			)
		)
		(polygon
			(pts
				(arc
					(start 5.59054 -299.535088)
					(mid 5.079873 -299.024802)
					(end 4.56946 -299.535342)
				)
				(arc
					(start 4.56946 -300.348142)
					(mid 5.08 -300.858682)
					(end 5.59054 -300.348142)
				)
			)
		)
		(polygon
			(pts
				(arc
					(start 7.502906 -297.935904)
					(mid 6.992366 -297.425364)
					(end 6.481826 -297.935904)
				)
				(arc
					(start 6.481826 -298.748958)
					(mid 6.992493 -299.259244)
					(end 7.502906 -298.748704)
				)
			)
		)
		(polygon
			(pts
				(xy 3.494532 -296.088054) (xy 1.005332 -296.088054) (xy 1.005332 -297.396154) (xy 3.494532 -297.396154)
			)
		)
		(polygon
			(pts
				(arc
					(start 5.59054 -296.335196)
					(mid 5.079873 -295.82491)
					(end 4.56946 -296.33545)
				)
				(arc
					(start 4.56946 -297.14825)
					(mid 5.08 -297.65879)
					(end 5.59054 -297.14825)
				)
			)
		)
		(polygon
			(pts
				(arc
					(start 7.502906 -294.736012)
					(mid 6.992366 -294.225472)
					(end 6.481826 -294.736012)
				)
				(arc
					(start 6.481826 -295.549066)
					(mid 6.992493 -296.059352)
					(end 7.502906 -295.548812)
				)
			)
		)
		(polygon
			(pts
				(xy 3.494532 -292.888162) (xy 1.005332 -292.888162) (xy 1.005332 -294.196008) (xy 3.494532 -294.196008)
			)
		)
		(polygon
			(pts
				(arc
					(start 5.59054 -293.13505)
					(mid 5.079873 -292.624764)
					(end 4.56946 -293.135304)
				)
				(arc
					(start 4.56946 -293.948104)
					(mid 5.08 -294.458644)
					(end 5.59054 -293.948104)
				)
			)
		)
		(polygon
			(pts
				(arc
					(start 7.502906 -291.535866)
					(mid 6.992366 -291.025326)
					(end 6.481826 -291.535866)
				)
				(arc
					(start 6.481826 -292.34892)
					(mid 6.992493 -292.859206)
					(end 7.502906 -292.348666)
				)
			)
		)
		(polygon
			(pts
				(xy 3.494532 -289.688016) (xy 1.005332 -289.688016) (xy 1.005332 -290.996116) (xy 3.494532 -290.996116)
			)
		)
		(polygon
			(pts
				(arc
					(start 5.59054 -289.935158)
					(mid 5.079873 -289.424872)
					(end 4.56946 -289.935412)
				)
				(arc
					(start 4.56946 -290.748212)
					(mid 5.08 -291.258752)
					(end 5.59054 -290.748212)
				)
			)
		)
		(polygon
			(pts
				(arc
					(start 7.502906 -288.33572)
					(mid 6.992239 -287.825434)
					(end 6.481826 -288.335974)
				)
				(arc
					(start 6.481826 -289.148774)
					(mid 6.992366 -289.659314)
					(end 7.502906 -289.148774)
				)
			)
		)
		(polygon
			(pts
				(arc
					(start 222.339154 -285.231078)
					(mid 221.726887 -284.619192)
					(end 221.114874 -285.231332)
				)
				(arc
					(start 221.114874 -286.348932)
					(mid 221.727014 -286.961072)
					(end 222.339154 -286.348932)
				)
			)
		)
		(polygon
			(pts
				(arc
					(start 37.33927 -285.231078)
					(mid 36.727003 -284.619192)
					(end 36.11499 -285.231332)
				)
				(arc
					(start 36.11499 -286.348932)
					(mid 36.72713 -286.961072)
					(end 37.33927 -286.348932)
				)
			)
		)
		(polygon
			(pts
				(xy 3.494532 -283.288232) (xy 1.005332 -283.288232) (xy 1.005332 -284.596078) (xy 3.494532 -284.596078)
			)
		)
		(polygon
			(pts
				(arc
					(start 5.59054 -283.53512)
					(mid 5.079873 -283.024834)
					(end 4.56946 -283.535374)
				)
				(arc
					(start 4.56946 -284.348174)
					(mid 5.08 -284.858714)
					(end 5.59054 -284.348174)
				)
			)
		)
		(polygon
			(pts
				(arc
					(start 220.840554 -282.983432)
					(mid 220.329887 -282.473146)
					(end 219.819474 -282.983686)
				)
				(arc
					(start 219.819474 -283.796486)
					(mid 220.330014 -284.307026)
					(end 220.840554 -283.796486)
				)
			)
		)
		(polygon
			(pts
				(arc
					(start 35.84067 -282.983432)
					(mid 35.330003 -282.473146)
					(end 34.81959 -282.983686)
				)
				(arc
					(start 34.81959 -283.796486)
					(mid 35.33013 -284.307026)
					(end 35.84067 -283.796486)
				)
			)
		)
		(polygon
			(pts
				(arc
					(start 7.502906 -281.986482)
					(mid 6.992239 -281.476196)
					(end 6.481826 -281.986736)
				)
				(arc
					(start 6.481826 -282.799536)
					(mid 6.992366 -283.310076)
					(end 7.502906 -282.799536)
				)
			)
		)
		(polygon
			(pts
				(xy 3.494532 -280.088086) (xy 1.005332 -280.088086) (xy 1.005332 -281.396186) (xy 3.494532 -281.396186)
			)
		)
		(polygon
			(pts
				(arc
					(start 5.59054 -280.335228)
					(mid 5.079873 -279.824942)
					(end 4.56946 -280.335482)
				)
				(arc
					(start 4.56946 -281.148282)
					(mid 5.08 -281.658822)
					(end 5.59054 -281.148282)
				)
			)
		)
		(polygon
			(pts
				(arc
					(start 222.339154 -280.430986)
					(mid 221.726887 -279.8191)
					(end 221.114874 -280.43124)
				)
				(arc
					(start 221.114874 -281.54884)
					(mid 221.727014 -282.16098)
					(end 222.339154 -281.54884)
				)
			)
		)
		(polygon
			(pts
				(arc
					(start 37.33927 -280.430986)
					(mid 36.727003 -279.8191)
					(end 36.11499 -280.43124)
				)
				(arc
					(start 36.11499 -281.54884)
					(mid 36.72713 -282.16098)
					(end 37.33927 -281.54884)
				)
			)
		)
		(polygon
			(pts
				(arc
					(start 7.502906 -278.786336)
					(mid 6.992239 -278.27605)
					(end 6.481826 -278.78659)
				)
				(arc
					(start 6.481826 -279.59939)
					(mid 6.992366 -280.10993)
					(end 7.502906 -279.59939)
				)
			)
		)
		(polygon
			(pts
				(arc
					(start 220.840554 -278.18334)
					(mid 220.329887 -277.673054)
					(end 219.819474 -278.183594)
				)
				(arc
					(start 219.819474 -278.996394)
					(mid 220.330014 -279.506934)
					(end 220.840554 -278.996394)
				)
			)
		)
		(polygon
			(pts
				(arc
					(start 35.84067 -278.18334)
					(mid 35.330003 -277.673054)
					(end 34.81959 -278.183594)
				)
				(arc
					(start 34.81959 -278.996394)
					(mid 35.33013 -279.506934)
					(end 35.84067 -278.996394)
				)
			)
		)
		(polygon
			(pts
				(arc
					(start 222.339154 -275.630894)
					(mid 221.726887 -275.019008)
					(end 221.114874 -275.631148)
				)
				(arc
					(start 221.114874 -276.748748)
					(mid 221.727014 -277.360888)
					(end 222.339154 -276.748748)
				)
			)
		)
		(polygon
			(pts
				(arc
					(start 37.33927 -275.630894)
					(mid 36.727003 -275.019008)
					(end 36.11499 -275.631148)
				)
				(arc
					(start 36.11499 -276.748748)
					(mid 36.72713 -277.360888)
					(end 37.33927 -276.748748)
				)
			)
		)
		(polygon
			(pts
				(arc
					(start 220.840554 -273.383502)
					(mid 220.329887 -272.873216)
					(end 219.819474 -273.383756)
				)
				(arc
					(start 219.819474 -274.196556)
					(mid 220.330014 -274.707096)
					(end 220.840554 -274.196556)
				)
			)
		)
		(polygon
			(pts
				(arc
					(start 35.84067 -273.383502)
					(mid 35.330003 -272.873216)
					(end 34.81959 -273.383756)
				)
				(arc
					(start 34.81959 -274.196556)
					(mid 35.33013 -274.707096)
					(end 35.84067 -274.196556)
				)
			)
		)
		(polygon
			(pts
				(arc
					(start 233.897424 -266.57935)
					(mid 233.386884 -266.06881)
					(end 232.876344 -266.57935)
				)
				(arc
					(start 232.876344 -267.392404)
					(mid 233.387011 -267.90269)
					(end 233.897424 -267.39215)
				)
			)
		)
		(polygon
			(pts
				(arc
					(start 48.89754 -266.579096)
					(mid 48.386873 -266.06881)
					(end 47.87646 -266.57935)
				)
				(arc
					(start 47.87646 -267.39215)
					(mid 48.387 -267.90269)
					(end 48.89754 -267.39215)
				)
			)
		)
		(polygon
			(pts
				(arc
					(start 230.720138 -266.300712)
					(mid 231.230424 -265.790045)
					(end 230.719884 -265.279632)
				)
				(arc
					(start 229.907084 -265.279632)
					(mid 229.396544 -265.790172)
					(end 229.907084 -266.300712)
				)
			)
		)
		(polygon
			(pts
				(arc
					(start 45.72 -266.300712)
					(mid 46.23054 -265.790172)
					(end 45.72 -265.279632)
				)
				(arc
					(start 44.906946 -265.279632)
					(mid 44.39666 -265.790299)
					(end 44.9072 -266.300712)
				)
			)
		)
		(polygon
			(pts
				(arc
					(start 222.339154 -262.831072)
					(mid 221.726887 -262.219186)
					(end 221.114874 -262.831326)
				)
				(arc
					(start 221.114874 -263.948926)
					(mid 221.727014 -264.561066)
					(end 222.339154 -263.948926)
				)
			)
		)
		(polygon
			(pts
				(arc
					(start 37.33927 -262.831072)
					(mid 36.727003 -262.219186)
					(end 36.11499 -262.831326)
				)
				(arc
					(start 36.11499 -263.948926)
					(mid 36.72713 -264.561066)
					(end 37.33927 -263.948926)
				)
			)
		)
		(polygon
			(pts
				(arc
					(start 220.840554 -260.583426)
					(mid 220.329887 -260.07314)
					(end 219.819474 -260.58368)
				)
				(arc
					(start 219.819474 -261.39648)
					(mid 220.330014 -261.90702)
					(end 220.840554 -261.39648)
				)
			)
		)
		(polygon
			(pts
				(arc
					(start 35.84067 -260.583426)
					(mid 35.330003 -260.07314)
					(end 34.81959 -260.58368)
				)
				(arc
					(start 34.81959 -261.39648)
					(mid 35.33013 -261.90702)
					(end 35.84067 -261.39648)
				)
			)
		)
		(polygon
			(pts
				(arc
					(start 27.18054 -244.603524)
					(mid 26.67 -244.092984)
					(end 26.15946 -244.603524)
				)
				(arc
					(start 26.15946 -245.416578)
					(mid 26.670127 -245.926864)
					(end 27.18054 -245.416324)
				)
			)
		)
		(polygon
			(pts
				(arc
					(start 25.88514 -242.051078)
					(mid 25.273 -241.438938)
					(end 24.66086 -242.051078)
				)
				(arc
					(start 24.66086 -243.168932)
					(mid 25.273127 -243.780818)
					(end 25.88514 -243.168678)
				)
			)
		)
		(polygon
			(pts
				(arc
					(start 17.78254 -238.603282)
					(mid 17.272 -238.092742)
					(end 16.76146 -238.603282)
				)
				(arc
					(start 16.76146 -239.416336)
					(mid 17.272127 -239.926622)
					(end 17.78254 -239.416082)
				)
			)
		)
		(polygon
			(pts
				(arc
					(start 42.92854 -238.584232)
					(mid 42.417873 -238.073946)
					(end 41.90746 -238.584486)
				)
				(arc
					(start 41.90746 -239.397286)
					(mid 42.418 -239.907826)
					(end 42.92854 -239.397286)
				)
			)
		)
		(polygon
			(pts
				(xy 3.494532 -231.688132) (xy 1.005332 -231.688132) (xy 1.005332 -232.996232) (xy 3.494532 -232.996232)
			)
		)
		(polygon
			(pts
				(arc
					(start 5.59054 -231.935274)
					(mid 5.079873 -231.424988)
					(end 4.56946 -231.935528)
				)
				(arc
					(start 4.56946 -232.748328)
					(mid 5.08 -233.258868)
					(end 5.59054 -232.748328)
				)
			)
		)
		(polygon
			(pts
				(arc
					(start 27.18054 -231.803448)
					(mid 26.67 -231.292908)
					(end 26.15946 -231.803448)
				)
				(arc
					(start 26.15946 -232.616502)
					(mid 26.670127 -233.126788)
					(end 27.18054 -232.616248)
				)
			)
		)
		(polygon
			(pts
				(arc
					(start 7.502906 -230.335582)
					(mid 6.992239 -229.825296)
					(end 6.481826 -230.335836)
				)
				(arc
					(start 6.481826 -231.148636)
					(mid 6.992366 -231.659176)
					(end 7.502906 -231.148636)
				)
			)
		)
		(polygon
			(pts
				(arc
					(start 25.88514 -229.251256)
					(mid 25.273 -228.639116)
					(end 24.66086 -229.251256)
				)
				(arc
					(start 24.66086 -230.36911)
					(mid 25.273127 -230.980996)
					(end 25.88514 -230.368856)
				)
			)
		)
		(polygon
			(pts
				(xy 3.494532 -228.487986) (xy 1.005332 -228.487986) (xy 1.005332 -229.796086) (xy 3.494532 -229.796086)
			)
		)
		(polygon
			(pts
				(arc
					(start 5.59054 -228.735128)
					(mid 5.079873 -228.224842)
					(end 4.56946 -228.735382)
				)
				(arc
					(start 4.56946 -229.548182)
					(mid 5.08 -230.058722)
					(end 5.59054 -229.548182)
				)
			)
		)
		(polygon
			(pts
				(arc
					(start 7.502906 -227.13569)
					(mid 6.992239 -226.625404)
					(end 6.481826 -227.135944)
				)
				(arc
					(start 6.481826 -227.948744)
					(mid 6.992366 -228.459284)
					(end 7.502906 -227.948744)
				)
			)
		)
		(polygon
			(pts
				(arc
					(start 27.18054 -227.00361)
					(mid 26.67 -226.49307)
					(end 26.15946 -227.00361)
				)
				(arc
					(start 26.15946 -227.816664)
					(mid 26.670127 -228.32695)
					(end 27.18054 -227.81641)
				)
			)
		)
		(polygon
			(pts
				(arc
					(start 25.88514 -224.451164)
					(mid 25.273 -223.839024)
					(end 24.66086 -224.451164)
				)
				(arc
					(start 24.66086 -225.569018)
					(mid 25.273127 -226.180904)
					(end 25.88514 -225.568764)
				)
			)
		)
		(polygon
			(pts
				(arc
					(start 7.502906 -223.897444)
					(mid 6.992239 -223.387158)
					(end 6.481826 -223.897698)
				)
				(arc
					(start 6.481826 -224.710498)
					(mid 6.992366 -225.221038)
					(end 7.502906 -224.710498)
				)
			)
		)
		(polygon
			(pts
				(xy 3.494532 -222.088202) (xy 1.005332 -222.088202) (xy 1.005332 -223.396048) (xy 3.494532 -223.396048)
			)
		)
		(polygon
			(pts
				(arc
					(start 5.59054 -222.33509)
					(mid 5.079873 -221.824804)
					(end 4.56946 -222.335344)
				)
				(arc
					(start 4.56946 -223.148144)
					(mid 5.08 -223.658684)
					(end 5.59054 -223.148144)
				)
			)
		)
		(polygon
			(pts
				(arc
					(start 27.18054 -222.203518)
					(mid 26.67 -221.692978)
					(end 26.15946 -222.203518)
				)
				(arc
					(start 26.15946 -223.016572)
					(mid 26.670127 -223.526858)
					(end 27.18054 -223.016318)
				)
			)
		)
		(polygon
			(pts
				(arc
					(start 7.502906 -220.685106)
					(mid 6.992366 -220.174566)
					(end 6.481826 -220.685106)
				)
				(arc
					(start 6.481826 -221.49816)
					(mid 6.992493 -222.008446)
					(end 7.502906 -221.497906)
				)
			)
		)
		(polygon
			(pts
				(arc
					(start 25.88514 -219.650818)
					(mid 25.272873 -219.038932)
					(end 24.66086 -219.651072)
				)
				(arc
					(start 24.66086 -220.768672)
					(mid 25.273 -221.380812)
					(end 25.88514 -220.768672)
				)
			)
		)
		(polygon
			(pts
				(xy 3.494532 -218.888056) (xy 1.005332 -218.888056) (xy 1.005332 -220.196156) (xy 3.494532 -220.196156)
			)
		)
		(polygon
			(pts
				(arc
					(start 5.59054 -219.135198)
					(mid 5.079873 -218.624912)
					(end 4.56946 -219.135452)
				)
				(arc
					(start 4.56946 -219.948252)
					(mid 5.08 -220.458792)
					(end 5.59054 -219.948252)
				)
			)
		)
		(polygon
			(pts
				(arc
					(start 7.502906 -217.48496)
					(mid 6.992239 -216.974674)
					(end 6.481826 -217.485214)
				)
				(arc
					(start 6.481826 -218.298014)
					(mid 6.992366 -218.808554)
					(end 7.502906 -218.298014)
				)
			)
		)
		(polygon
			(pts
				(xy 3.494532 -215.688164) (xy 1.005332 -215.688164) (xy 1.005332 -216.99601) (xy 3.494532 -216.99601)
			)
		)
		(polygon
			(pts
				(arc
					(start 5.59054 -215.935052)
					(mid 5.079873 -215.424766)
					(end 4.56946 -215.935306)
				)
				(arc
					(start 4.56946 -216.748106)
					(mid 5.08 -217.258646)
					(end 5.59054 -216.748106)
				)
			)
		)
		(polygon
			(pts
				(arc
					(start 7.502906 -214.284814)
					(mid 6.992239 -213.774528)
					(end 6.481826 -214.285068)
				)
				(arc
					(start 6.481826 -215.097868)
					(mid 6.992366 -215.608408)
					(end 7.502906 -215.097868)
				)
			)
		)
		(polygon
			(pts
				(xy 3.494532 -212.488018) (xy 1.005332 -212.488018) (xy 1.005332 -213.796118) (xy 3.494532 -213.796118)
			)
		)
		(polygon
			(pts
				(arc
					(start 5.59054 -212.73516)
					(mid 5.079873 -212.224874)
					(end 4.56946 -212.735414)
				)
				(arc
					(start 4.56946 -213.548214)
					(mid 5.08 -214.058754)
					(end 5.59054 -213.548214)
				)
			)
		)
		(polygon
			(pts
				(arc
					(start 7.502906 -211.135722)
					(mid 6.992239 -210.625436)
					(end 6.481826 -211.135976)
				)
				(arc
					(start 6.481826 -211.948776)
					(mid 6.992366 -212.459316)
					(end 7.502906 -211.948776)
				)
			)
		)
		(polygon
			(pts
				(xy 3.494532 -209.288126) (xy 1.005332 -209.288126) (xy 1.005332 -210.596226) (xy 3.494532 -210.596226)
			)
		)
		(polygon
			(pts
				(arc
					(start 5.59054 -209.535268)
					(mid 5.079873 -209.024982)
					(end 4.56946 -209.535522)
				)
				(arc
					(start 4.56946 -210.348322)
					(mid 5.08 -210.858862)
					(end 5.59054 -210.348322)
				)
			)
		)
		(polygon
			(pts
				(arc
					(start 7.502906 -207.935576)
					(mid 6.992239 -207.42529)
					(end 6.481826 -207.93583)
				)
				(arc
					(start 6.481826 -208.74863)
					(mid 6.992366 -209.25917)
					(end 7.502906 -208.74863)
				)
			)
		)
		(polygon
			(pts
				(xy 3.494532 -206.088234) (xy 1.005332 -206.088234) (xy 1.005332 -207.39608) (xy 3.494532 -207.39608)
			)
		)
		(polygon
			(pts
				(arc
					(start 5.59054 -206.335122)
					(mid 5.079873 -205.824836)
					(end 4.56946 -206.335376)
				)
				(arc
					(start 4.56946 -207.148176)
					(mid 5.08 -207.658716)
					(end 5.59054 -207.148176)
				)
			)
		)
		(polygon
			(pts
				(arc
					(start 7.502906 -204.735684)
					(mid 6.992239 -204.225398)
					(end 6.481826 -204.735938)
				)
				(arc
					(start 6.481826 -205.548738)
					(mid 6.992366 -206.059278)
					(end 7.502906 -205.548738)
				)
			)
		)
		(polygon
			(pts
				(xy 3.494532 -202.888088) (xy 1.005332 -202.888088) (xy 1.005332 -204.196188) (xy 3.494532 -204.196188)
			)
		)
		(polygon
			(pts
				(arc
					(start 5.59054 -203.13523)
					(mid 5.079873 -202.624944)
					(end 4.56946 -203.135484)
				)
				(arc
					(start 4.56946 -203.948284)
					(mid 5.08 -204.458824)
					(end 5.59054 -203.948284)
				)
			)
		)
		(polygon
			(pts
				(arc
					(start 7.502906 -201.535538)
					(mid 6.992239 -201.025252)
					(end 6.481826 -201.535792)
				)
				(arc
					(start 6.481826 -202.348592)
					(mid 6.992366 -202.859132)
					(end 7.502906 -202.348592)
				)
			)
		)
		(polygon
			(pts
				(xy 3.494532 -199.688196) (xy 1.005332 -199.688196) (xy 1.005332 -200.996042) (xy 3.494532 -200.996042)
			)
		)
		(polygon
			(pts
				(arc
					(start 5.59054 -199.935084)
					(mid 5.079873 -199.424798)
					(end 4.56946 -199.935338)
				)
				(arc
					(start 4.56946 -200.748138)
					(mid 5.08 -201.258678)
					(end 5.59054 -200.748138)
				)
			)
		)
		(polygon
			(pts
				(arc
					(start 7.502906 -195.9356)
					(mid 6.992239 -195.425314)
					(end 6.481826 -195.935854)
				)
				(arc
					(start 6.481826 -196.748654)
					(mid 6.992366 -197.259194)
					(end 7.502906 -196.748654)
				)
			)
		)
		(polygon
			(pts
				(xy 3.494532 -194.088004) (xy 1.005332 -194.088004) (xy 1.005332 -195.396104) (xy 3.494532 -195.396104)
			)
		)
		(polygon
			(pts
				(arc
					(start 5.59054 -194.335146)
					(mid 5.079873 -193.82486)
					(end 4.56946 -194.3354)
				)
				(arc
					(start 4.56946 -195.1482)
					(mid 5.08 -195.65874)
					(end 5.59054 -195.1482)
				)
			)
		)
		(polygon
			(pts
				(arc
					(start 7.502906 -192.735708)
					(mid 6.992239 -192.225422)
					(end 6.481826 -192.735962)
				)
				(arc
					(start 6.481826 -193.548762)
					(mid 6.992366 -194.059302)
					(end 7.502906 -193.548762)
				)
			)
		)
		(polygon
			(pts
				(xy 3.494532 -190.888112) (xy 1.005332 -190.888112) (xy 1.005332 -192.196212) (xy 3.494532 -192.196212)
			)
		)
		(polygon
			(pts
				(arc
					(start 5.59054 -191.135254)
					(mid 5.079873 -190.624968)
					(end 4.56946 -191.135508)
				)
				(arc
					(start 4.56946 -191.948308)
					(mid 5.08 -192.458848)
					(end 5.59054 -191.948308)
				)
			)
		)
		(polygon
			(pts
				(arc
					(start 7.502906 -184.735724)
					(mid 6.992239 -184.225438)
					(end 6.481826 -184.735978)
				)
				(arc
					(start 6.481826 -185.548778)
					(mid 6.992366 -186.059318)
					(end 7.502906 -185.548778)
				)
			)
		)
		(polygon
			(pts
				(xy 3.494532 -182.888128) (xy 1.005332 -182.888128) (xy 1.005332 -184.196228) (xy 3.494532 -184.196228)
			)
		)
		(polygon
			(pts
				(arc
					(start 5.59054 -183.13527)
					(mid 5.079873 -182.624984)
					(end 4.56946 -183.135524)
				)
				(arc
					(start 4.56946 -183.948324)
					(mid 5.08 -184.458864)
					(end 5.59054 -183.948324)
				)
			)
		)
		(polygon
			(pts
				(arc
					(start 222.339154 -182.23103)
					(mid 221.726887 -181.619144)
					(end 221.114874 -182.231284)
				)
				(arc
					(start 221.114874 -183.348884)
					(mid 221.727014 -183.961024)
					(end 222.339154 -183.348884)
				)
			)
		)
		(polygon
			(pts
				(arc
					(start 37.33927 -182.23103)
					(mid 36.727003 -181.619144)
					(end 36.11499 -182.231284)
				)
				(arc
					(start 36.11499 -183.348884)
					(mid 36.72713 -183.961024)
					(end 37.33927 -183.348884)
				)
			)
		)
		(polygon
			(pts
				(arc
					(start 7.502906 -181.535578)
					(mid 6.992239 -181.025292)
					(end 6.481826 -181.535832)
				)
				(arc
					(start 6.481826 -182.348632)
					(mid 6.992366 -182.859172)
					(end 7.502906 -182.348632)
				)
			)
		)
		(polygon
			(pts
				(xy 3.494532 -179.687982) (xy 1.005332 -179.687982) (xy 1.005332 -180.996082) (xy 3.494532 -180.996082)
			)
		)
		(polygon
			(pts
				(arc
					(start 220.840554 -179.983384)
					(mid 220.329887 -179.473098)
					(end 219.819474 -179.983638)
				)
				(arc
					(start 219.819474 -180.796438)
					(mid 220.330014 -181.306978)
					(end 220.840554 -180.796438)
				)
			)
		)
		(polygon
			(pts
				(arc
					(start 35.84067 -179.983384)
					(mid 35.330003 -179.473098)
					(end 34.81959 -179.983638)
				)
				(arc
					(start 34.81959 -180.796438)
					(mid 35.33013 -181.306978)
					(end 35.84067 -180.796438)
				)
			)
		)
		(polygon
			(pts
				(arc
					(start 5.59054 -179.935124)
					(mid 5.079873 -179.424838)
					(end 4.56946 -179.935378)
				)
				(arc
					(start 4.56946 -180.748178)
					(mid 5.08 -181.258718)
					(end 5.59054 -180.748178)
				)
			)
		)
		(polygon
			(pts
				(arc
					(start 7.502906 -178.386486)
					(mid 6.992239 -177.8762)
					(end 6.481826 -178.38674)
				)
				(arc
					(start 6.481826 -179.19954)
					(mid 6.992366 -179.71008)
					(end 7.502906 -179.19954)
				)
			)
		)
		(polygon
			(pts
				(arc
					(start 222.339154 -177.430938)
					(mid 221.726887 -176.819052)
					(end 221.114874 -177.431192)
				)
				(arc
					(start 221.114874 -178.548792)
					(mid 221.727014 -179.160932)
					(end 222.339154 -178.548792)
				)
			)
		)
		(polygon
			(pts
				(arc
					(start 37.33927 -177.430938)
					(mid 36.727003 -176.819052)
					(end 36.11499 -177.431192)
				)
				(arc
					(start 36.11499 -178.548792)
					(mid 36.72713 -179.160932)
					(end 37.33927 -178.548792)
				)
			)
		)
		(polygon
			(pts
				(xy 3.494532 -176.48809) (xy 1.005332 -176.48809) (xy 1.005332 -177.79619) (xy 3.494532 -177.79619)
			)
		)
		(polygon
			(pts
				(arc
					(start 5.59054 -176.735232)
					(mid 5.079873 -176.224946)
					(end 4.56946 -176.735486)
				)
				(arc
					(start 4.56946 -177.548286)
					(mid 5.08 -178.058826)
					(end 5.59054 -177.548286)
				)
			)
		)
		(polygon
			(pts
				(arc
					(start 7.502906 -175.18634)
					(mid 6.992239 -174.676054)
					(end 6.481826 -175.186594)
				)
				(arc
					(start 6.481826 -175.999394)
					(mid 6.992366 -176.509934)
					(end 7.502906 -175.999394)
				)
			)
		)
		(polygon
			(pts
				(arc
					(start 220.840554 -175.183292)
					(mid 220.329887 -174.673006)
					(end 219.819474 -175.183546)
				)
				(arc
					(start 219.819474 -175.996346)
					(mid 220.330014 -176.506886)
					(end 220.840554 -175.996346)
				)
			)
		)
		(polygon
			(pts
				(arc
					(start 35.84067 -175.183292)
					(mid 35.330003 -174.673006)
					(end 34.81959 -175.183546)
				)
				(arc
					(start 34.81959 -175.996346)
					(mid 35.33013 -176.506886)
					(end 35.84067 -175.996346)
				)
			)
		)
		(polygon
			(pts
				(xy 3.494532 -173.288198) (xy 1.005332 -173.288198) (xy 1.005332 -174.596044) (xy 3.494532 -174.596044)
			)
		)
		(polygon
			(pts
				(arc
					(start 5.59054 -173.535086)
					(mid 5.079873 -173.0248)
					(end 4.56946 -173.53534)
				)
				(arc
					(start 4.56946 -174.34814)
					(mid 5.08 -174.85868)
					(end 5.59054 -174.34814)
				)
			)
		)
		(polygon
			(pts
				(arc
					(start 222.339154 -172.630846)
					(mid 221.726887 -172.01896)
					(end 221.114874 -172.6311)
				)
				(arc
					(start 221.114874 -173.7487)
					(mid 221.727014 -174.36084)
					(end 222.339154 -173.7487)
				)
			)
		)
		(polygon
			(pts
				(arc
					(start 37.33927 -172.630846)
					(mid 36.727003 -172.01896)
					(end 36.11499 -172.6311)
				)
				(arc
					(start 36.11499 -173.7487)
					(mid 36.72713 -174.36084)
					(end 37.33927 -173.7487)
				)
			)
		)
		(polygon
			(pts
				(arc
					(start 7.502906 -171.986448)
					(mid 6.992239 -171.476162)
					(end 6.481826 -171.986702)
				)
				(arc
					(start 6.481826 -172.799502)
					(mid 6.992366 -173.310042)
					(end 7.502906 -172.799502)
				)
			)
		)
		(polygon
			(pts
				(xy 3.494532 -170.088052) (xy 1.005332 -170.088052) (xy 1.005332 -171.396152) (xy 3.494532 -171.396152)
			)
		)
		(polygon
			(pts
				(arc
					(start 220.840554 -170.383454)
					(mid 220.329887 -169.873168)
					(end 219.819474 -170.383708)
				)
				(arc
					(start 219.819474 -171.196508)
					(mid 220.330014 -171.707048)
					(end 220.840554 -171.196508)
				)
			)
		)
		(polygon
			(pts
				(arc
					(start 35.84067 -170.383454)
					(mid 35.330003 -169.873168)
					(end 34.81959 -170.383708)
				)
				(arc
					(start 34.81959 -171.196508)
					(mid 35.33013 -171.707048)
					(end 35.84067 -171.196508)
				)
			)
		)
		(polygon
			(pts
				(arc
					(start 5.59054 -170.335194)
					(mid 5.079873 -169.824908)
					(end 4.56946 -170.335448)
				)
				(arc
					(start 4.56946 -171.148248)
					(mid 5.08 -171.658788)
					(end 5.59054 -171.148248)
				)
			)
		)
		(polygon
			(pts
				(arc
					(start 7.502906 -168.786556)
					(mid 6.992239 -168.27627)
					(end 6.481826 -168.78681)
				)
				(arc
					(start 6.481826 -169.59961)
					(mid 6.992366 -170.11015)
					(end 7.502906 -169.59961)
				)
			)
		)
		(polygon
			(pts
				(xy 3.494532 -166.88816) (xy 1.005332 -166.88816) (xy 1.005332 -168.196006) (xy 3.494532 -168.196006)
			)
		)
		(polygon
			(pts
				(arc
					(start 5.59054 -167.135048)
					(mid 5.079873 -166.624762)
					(end 4.56946 -167.135302)
				)
				(arc
					(start 4.56946 -167.948102)
					(mid 5.08 -168.458642)
					(end 5.59054 -167.948102)
				)
			)
		)
		(polygon
			(pts
				(xy 3.494532 -163.688014) (xy 1.005332 -163.688014) (xy 1.005332 -164.996114) (xy 3.494532 -164.996114)
			)
		)
		(polygon
			(pts
				(arc
					(start 5.59054 -163.935156)
					(mid 5.079873 -163.42487)
					(end 4.56946 -163.93541)
				)
				(arc
					(start 4.56946 -164.74821)
					(mid 5.08 -165.25875)
					(end 5.59054 -164.74821)
				)
			)
		)
		(polygon
			(pts
				(arc
					(start 233.897424 -163.579302)
					(mid 233.386884 -163.068762)
					(end 232.876344 -163.579302)
				)
				(arc
					(start 232.876344 -164.392356)
					(mid 233.387011 -164.902642)
					(end 233.897424 -164.392102)
				)
			)
		)
		(polygon
			(pts
				(arc
					(start 48.89754 -163.579048)
					(mid 48.386873 -163.068762)
					(end 47.87646 -163.579302)
				)
				(arc
					(start 47.87646 -164.392102)
					(mid 48.387 -164.902642)
					(end 48.89754 -164.392102)
				)
			)
		)
		(polygon
			(pts
				(arc
					(start 230.720138 -163.300664)
					(mid 231.230424 -162.789997)
					(end 230.719884 -162.279584)
				)
				(arc
					(start 229.907084 -162.279584)
					(mid 229.396544 -162.790124)
					(end 229.907084 -163.300664)
				)
			)
		)
		(polygon
			(pts
				(arc
					(start 45.72 -163.300664)
					(mid 46.23054 -162.790124)
					(end 45.72 -162.279584)
				)
				(arc
					(start 44.906946 -162.279584)
					(mid 44.39666 -162.790251)
					(end 44.9072 -163.300664)
				)
			)
		)
		(polygon
			(pts
				(arc
					(start 7.502906 -162.386518)
					(mid 6.992239 -161.876232)
					(end 6.481826 -162.386772)
				)
				(arc
					(start 6.481826 -163.199572)
					(mid 6.992366 -163.710112)
					(end 7.502906 -163.199572)
				)
			)
		)
		(polygon
			(pts
				(xy 3.494532 -160.488122) (xy 1.005332 -160.488122) (xy 1.005332 -161.796222) (xy 3.494532 -161.796222)
			)
		)
		(polygon
			(pts
				(arc
					(start 5.59054 -160.735264)
					(mid 5.079873 -160.224978)
					(end 4.56946 -160.735518)
				)
				(arc
					(start 4.56946 -161.548318)
					(mid 5.08 -162.058858)
					(end 5.59054 -161.548318)
				)
			)
		)
		(polygon
			(pts
				(arc
					(start 222.339154 -159.831024)
					(mid 221.726887 -159.219138)
					(end 221.114874 -159.831278)
				)
				(arc
					(start 221.114874 -160.948878)
					(mid 221.727014 -161.561018)
					(end 222.339154 -160.948878)
				)
			)
		)
		(polygon
			(pts
				(arc
					(start 37.33927 -159.831024)
					(mid 36.727003 -159.219138)
					(end 36.11499 -159.831278)
				)
				(arc
					(start 36.11499 -160.948878)
					(mid 36.72713 -161.561018)
					(end 37.33927 -160.948878)
				)
			)
		)
		(polygon
			(pts
				(arc
					(start 7.502906 -159.186372)
					(mid 6.992239 -158.676086)
					(end 6.481826 -159.186626)
				)
				(arc
					(start 6.481826 -159.999426)
					(mid 6.992366 -160.509966)
					(end 7.502906 -159.999426)
				)
			)
		)
		(polygon
			(pts
				(xy 3.494532 -157.28823) (xy 1.005332 -157.28823) (xy 1.005332 -158.596076) (xy 3.494532 -158.596076)
			)
		)
		(polygon
			(pts
				(arc
					(start 220.840554 -157.583378)
					(mid 220.329887 -157.073092)
					(end 219.819474 -157.583632)
				)
				(arc
					(start 219.819474 -158.396432)
					(mid 220.330014 -158.906972)
					(end 220.840554 -158.396432)
				)
			)
		)
		(polygon
			(pts
				(arc
					(start 35.84067 -157.583378)
					(mid 35.330003 -157.073092)
					(end 34.81959 -157.583632)
				)
				(arc
					(start 34.81959 -158.396432)
					(mid 35.33013 -158.906972)
					(end 35.84067 -158.396432)
				)
			)
		)
		(polygon
			(pts
				(arc
					(start 5.59054 -157.535118)
					(mid 5.079873 -157.024832)
					(end 4.56946 -157.535372)
				)
				(arc
					(start 4.56946 -158.348172)
					(mid 5.08 -158.858712)
					(end 5.59054 -158.348172)
				)
			)
		)
		(polygon
			(pts
				(arc
					(start 7.502906 -155.97378)
					(mid 6.992239 -155.463494)
					(end 6.481826 -155.974034)
				)
				(arc
					(start 6.481826 -156.786834)
					(mid 6.992366 -157.297374)
					(end 7.502906 -156.786834)
				)
			)
		)
		(polygon
			(pts
				(xy 3.494532 -154.088084) (xy 1.005332 -154.088084) (xy 1.005332 -155.396184) (xy 3.494532 -155.396184)
			)
		)
		(polygon
			(pts
				(arc
					(start 5.59054 -154.335226)
					(mid 5.079873 -153.82494)
					(end 4.56946 -154.33548)
				)
				(arc
					(start 4.56946 -155.14828)
					(mid 5.08 -155.65882)
					(end 5.59054 -155.14828)
				)
			)
		)
		(polygon
			(pts
				(arc
					(start 7.502906 -152.786334)
					(mid 6.992239 -152.276048)
					(end 6.481826 -152.786588)
				)
				(arc
					(start 6.481826 -153.599388)
					(mid 6.992366 -154.109928)
					(end 7.502906 -153.599388)
				)
			)
		)
		(polygon
			(pts
				(arc
					(start 27.18054 -141.603476)
					(mid 26.67 -141.092936)
					(end 26.15946 -141.603476)
				)
				(arc
					(start 26.15946 -142.41653)
					(mid 26.670127 -142.926816)
					(end 27.18054 -142.416276)
				)
			)
		)
		(polygon
			(pts
				(arc
					(start 25.88514 -139.050776)
					(mid 25.272873 -138.43889)
					(end 24.66086 -139.05103)
				)
				(arc
					(start 24.66086 -140.16863)
					(mid 25.273 -140.78077)
					(end 25.88514 -140.16863)
				)
			)
		)
		(polygon
			(pts
				(arc
					(start 32.00654 -135.603488)
					(mid 31.495873 -135.093202)
					(end 30.98546 -135.603742)
				)
				(arc
					(start 30.98546 -136.416542)
					(mid 31.496 -136.927082)
					(end 32.00654 -136.416542)
				)
			)
		)
		(polygon
			(pts
				(arc
					(start 17.78254 -135.603234)
					(mid 17.272 -135.092694)
					(end 16.76146 -135.603234)
				)
				(arc
					(start 16.76146 -136.416288)
					(mid 17.272127 -136.926574)
					(end 17.78254 -136.416034)
				)
			)
		)
		(polygon
			(pts
				(arc
					(start 27.18054 -128.8034)
					(mid 26.67 -128.29286)
					(end 26.15946 -128.8034)
				)
				(arc
					(start 26.15946 -129.616454)
					(mid 26.670127 -130.12674)
					(end 27.18054 -129.6162)
				)
			)
		)
		(polygon
			(pts
				(arc
					(start 25.88514 -126.251208)
					(mid 25.273 -125.639068)
					(end 24.66086 -126.251208)
				)
				(arc
					(start 24.66086 -127.369062)
					(mid 25.273127 -127.980948)
					(end 25.88514 -127.368808)
				)
			)
		)
		(polygon
			(pts
				(arc
					(start 27.18054 -124.003562)
					(mid 26.67 -123.493022)
					(end 26.15946 -124.003562)
				)
				(arc
					(start 26.15946 -124.816616)
					(mid 26.670127 -125.326902)
					(end 27.18054 -124.816362)
				)
			)
		)
		(polygon
			(pts
				(arc
					(start 25.88514 -121.451116)
					(mid 25.273 -120.838976)
					(end 24.66086 -121.451116)
				)
				(arc
					(start 24.66086 -122.56897)
					(mid 25.273127 -123.180856)
					(end 25.88514 -122.568716)
				)
			)
		)
		(polygon
			(pts
				(arc
					(start 27.18054 -119.20347)
					(mid 26.67 -118.69293)
					(end 26.15946 -119.20347)
				)
				(arc
					(start 26.15946 -120.016524)
					(mid 26.670127 -120.52681)
					(end 27.18054 -120.01627)
				)
			)
		)
		(polygon
			(pts
				(arc
					(start 25.88514 -116.65077)
					(mid 25.272873 -116.038884)
					(end 24.66086 -116.651024)
				)
				(arc
					(start 24.66086 -117.768624)
					(mid 25.273 -118.380764)
					(end 25.88514 -117.768624)
				)
			)
		)
		(polygon
			(pts
				(arc
					(start 222.339154 -79.230982)
					(mid 221.726887 -78.619096)
					(end 221.114874 -79.231236)
				)
				(arc
					(start 221.114874 -80.348836)
					(mid 221.727014 -80.960976)
					(end 222.339154 -80.348836)
				)
			)
		)
		(polygon
			(pts
				(arc
					(start 37.33927 -79.230982)
					(mid 36.727003 -78.619096)
					(end 36.11499 -79.231236)
				)
				(arc
					(start 36.11499 -80.348836)
					(mid 36.72713 -80.960976)
					(end 37.33927 -80.348836)
				)
			)
		)
		(polygon
			(pts
				(arc
					(start 220.840554 -76.983336)
					(mid 220.329887 -76.47305)
					(end 219.819474 -76.98359)
				)
				(arc
					(start 219.819474 -77.79639)
					(mid 220.330014 -78.30693)
					(end 220.840554 -77.79639)
				)
			)
		)
		(polygon
			(pts
				(arc
					(start 35.84067 -76.983336)
					(mid 35.330003 -76.47305)
					(end 34.81959 -76.98359)
				)
				(arc
					(start 34.81959 -77.79639)
					(mid 35.33013 -78.30693)
					(end 35.84067 -77.79639)
				)
			)
		)
		(polygon
			(pts
				(arc
					(start 222.339154 -74.43089)
					(mid 221.726887 -73.819004)
					(end 221.114874 -74.431144)
				)
				(arc
					(start 221.114874 -75.548744)
					(mid 221.727014 -76.160884)
					(end 222.339154 -75.548744)
				)
			)
		)
		(polygon
			(pts
				(arc
					(start 37.33927 -74.43089)
					(mid 36.727003 -73.819004)
					(end 36.11499 -74.431144)
				)
				(arc
					(start 36.11499 -75.548744)
					(mid 36.72713 -76.160884)
					(end 37.33927 -75.548744)
				)
			)
		)
		(polygon
			(pts
				(arc
					(start 220.840554 -72.183244)
					(mid 220.329887 -71.672958)
					(end 219.819474 -72.183498)
				)
				(arc
					(start 219.819474 -72.996298)
					(mid 220.330014 -73.506838)
					(end 220.840554 -72.996298)
				)
			)
		)
		(polygon
			(pts
				(arc
					(start 35.84067 -72.183244)
					(mid 35.330003 -71.672958)
					(end 34.81959 -72.183498)
				)
				(arc
					(start 34.81959 -72.996298)
					(mid 35.33013 -73.506838)
					(end 35.84067 -72.996298)
				)
			)
		)
		(polygon
			(pts
				(arc
					(start 222.339154 -69.630798)
					(mid 221.726887 -69.018912)
					(end 221.114874 -69.631052)
				)
				(arc
					(start 221.114874 -70.748652)
					(mid 221.727014 -71.360792)
					(end 222.339154 -70.748652)
				)
			)
		)
		(polygon
			(pts
				(arc
					(start 37.33927 -69.630798)
					(mid 36.727003 -69.018912)
					(end 36.11499 -69.631052)
				)
				(arc
					(start 36.11499 -70.748652)
					(mid 36.72713 -71.360792)
					(end 37.33927 -70.748652)
				)
			)
		)
		(polygon
			(pts
				(arc
					(start 220.840554 -67.383406)
					(mid 220.329887 -66.87312)
					(end 219.819474 -67.38366)
				)
				(arc
					(start 219.819474 -68.19646)
					(mid 220.330014 -68.707)
					(end 220.840554 -68.19646)
				)
			)
		)
		(polygon
			(pts
				(arc
					(start 35.84067 -67.383406)
					(mid 35.330003 -66.87312)
					(end 34.81959 -67.38366)
				)
				(arc
					(start 34.81959 -68.19646)
					(mid 35.33013 -68.707)
					(end 35.84067 -68.19646)
				)
			)
		)
		(polygon
			(pts
				(arc
					(start 233.897424 -60.579254)
					(mid 233.386884 -60.068714)
					(end 232.876344 -60.579254)
				)
				(arc
					(start 232.876344 -61.392308)
					(mid 233.387011 -61.902594)
					(end 233.897424 -61.392054)
				)
			)
		)
		(polygon
			(pts
				(arc
					(start 48.89754 -60.579)
					(mid 48.386873 -60.068714)
					(end 47.87646 -60.579254)
				)
				(arc
					(start 47.87646 -61.392054)
					(mid 48.387 -61.902594)
					(end 48.89754 -61.392054)
				)
			)
		)
		(polygon
			(pts
				(arc
					(start 230.720138 -60.300616)
					(mid 231.230424 -59.789949)
					(end 230.719884 -59.279536)
				)
				(arc
					(start 229.907084 -59.279536)
					(mid 229.396544 -59.790076)
					(end 229.907084 -60.300616)
				)
			)
		)
		(polygon
			(pts
				(arc
					(start 45.72 -60.300616)
					(mid 46.23054 -59.790076)
					(end 45.72 -59.279536)
				)
				(arc
					(start 44.906946 -59.279536)
					(mid 44.39666 -59.790203)
					(end 44.9072 -60.300616)
				)
			)
		)
		(polygon
			(pts
				(arc
					(start 222.339154 -56.830976)
					(mid 221.726887 -56.21909)
					(end 221.114874 -56.83123)
				)
				(arc
					(start 221.114874 -57.94883)
					(mid 221.727014 -58.56097)
					(end 222.339154 -57.94883)
				)
			)
		)
		(polygon
			(pts
				(arc
					(start 37.33927 -56.830976)
					(mid 36.727003 -56.21909)
					(end 36.11499 -56.83123)
				)
				(arc
					(start 36.11499 -57.94883)
					(mid 36.72713 -58.56097)
					(end 37.33927 -57.94883)
				)
			)
		)
		(polygon
			(pts
				(arc
					(start 220.840554 -54.58333)
					(mid 220.329887 -54.073044)
					(end 219.819474 -54.583584)
				)
				(arc
					(start 219.819474 -55.396384)
					(mid 220.330014 -55.906924)
					(end 220.840554 -55.396384)
				)
			)
		)
		(polygon
			(pts
				(arc
					(start 35.84067 -54.58333)
					(mid 35.330003 -54.073044)
					(end 34.81959 -54.583584)
				)
				(arc
					(start 34.81959 -55.396384)
					(mid 35.33013 -55.906924)
					(end 35.84067 -55.396384)
				)
			)
		)
		(polygon
			(pts
				(arc
					(start 27.18054 -38.603428)
					(mid 26.67 -38.092888)
					(end 26.15946 -38.603428)
				)
				(arc
					(start 26.15946 -39.416482)
					(mid 26.670127 -39.926768)
					(end 27.18054 -39.416228)
				)
			)
		)
		(polygon
			(pts
				(arc
					(start 25.88514 -36.050982)
					(mid 25.273 -35.438842)
					(end 24.66086 -36.050982)
				)
				(arc
					(start 24.66086 -37.168836)
					(mid 25.273127 -37.780722)
					(end 25.88514 -37.168582)
				)
			)
		)
		(polygon
			(pts
				(arc
					(start 32.00654 -32.602932)
					(mid 31.495873 -32.092646)
					(end 30.98546 -32.603186)
				)
				(arc
					(start 30.98546 -33.415986)
					(mid 31.496 -33.926526)
					(end 32.00654 -33.415986)
				)
			)
		)
		(polygon
			(pts
				(arc
					(start 17.78254 -32.602932)
					(mid 17.271873 -32.092646)
					(end 16.76146 -32.603186)
				)
				(arc
					(start 16.76146 -33.415986)
					(mid 17.272 -33.926526)
					(end 17.78254 -33.415986)
				)
			)
		)
		(polygon
			(pts
				(arc
					(start 27.18054 -25.803352)
					(mid 26.67 -25.292812)
					(end 26.15946 -25.803352)
				)
				(arc
					(start 26.15946 -26.616406)
					(mid 26.670127 -27.126692)
					(end 27.18054 -26.616152)
				)
			)
		)
		(polygon
			(pts
				(arc
					(start 25.88514 -23.25116)
					(mid 25.273 -22.63902)
					(end 24.66086 -23.25116)
				)
				(arc
					(start 24.66086 -24.369014)
					(mid 25.273127 -24.9809)
					(end 25.88514 -24.36876)
				)
			)
		)
		(polygon
			(pts
				(arc
					(start 27.18054 -21.003514)
					(mid 26.67 -20.492974)
					(end 26.15946 -21.003514)
				)
				(arc
					(start 26.15946 -21.816568)
					(mid 26.670127 -22.326854)
					(end 27.18054 -21.816314)
				)
			)
		)
		(polygon
			(pts
				(arc
					(start 25.88514 -18.451068)
					(mid 25.273 -17.838928)
					(end 24.66086 -18.451068)
				)
				(arc
					(start 24.66086 -19.568922)
					(mid 25.273127 -20.180808)
					(end 25.88514 -19.568668)
				)
			)
		)
		(polygon
			(pts
				(arc
					(start 27.18054 -16.203422)
					(mid 26.67 -15.692882)
					(end 26.15946 -16.203422)
				)
				(arc
					(start 26.15946 -17.016476)
					(mid 26.670127 -17.526762)
					(end 27.18054 -17.016222)
				)
			)
		)
		(polygon
			(pts
				(arc
					(start 25.88514 -13.676122)
					(mid 25.272873 -13.064236)
					(end 24.66086 -13.676376)
				)
				(arc
					(start 24.66086 -14.793976)
					(mid 25.273 -15.406116)
					(end 25.88514 -14.793976)
				)
			)
		)
	)
	(zone
		(layer "Cmts.User")
		(hatch none 0.5)
		(connect_pads
			(clearance 0.5)
		)
		(min_thickness 0.25)
		(fill
			(thermal_gap 0.5)
			(thermal_bridge_width 0.5)
			(island_removal_mode 0)
		)
		(polygon
			(pts
				(xy 121.285 -531.5204) (xy 121.285 43.053) (xy 318.8716 43.053) (xy 318.8716 -531.5204)
			)
		)
	)
	(zone
		(layer "Cmts.User")
		(hatch none 0.5)
		(connect_pads
			(clearance 0)
		)
		(min_thickness 0.25)
		(keepout
			(tracks allowed)
			(vias allowed)
			(pads allowed)
			(copperpour allowed)
			(footprints allowed)
		)
		(placement
			(enabled no)
			(sheetname "")
		)
		(fill
			(thermal_gap 0.5)
			(thermal_bridge_width 0.5)
			(island_removal_mode 0)
		)
		(polygon
			(pts
				(xy 5.8166 -450.2658) (xy 5.8166 -448.8434) (xy 8.001 -448.8434) (xy 8.001 -450.2658)
			)
		)
	)
	(zone
		(layer "Cmts.User")
		(hatch none 0.5)
		(connect_pads
			(clearance 0)
		)
		(min_thickness 0.25)
		(keepout
			(tracks allowed)
			(vias allowed)
			(pads allowed)
			(copperpour allowed)
			(footprints allowed)
		)
		(placement
			(enabled no)
			(sheetname "")
		)
		(fill
			(thermal_gap 0.5)
			(thermal_bridge_width 0.5)
			(island_removal_mode 0)
		)
		(polygon
			(pts
				(xy 7.7216 -386.2578) (xy 7.7216 -384.8354) (xy 9.906 -384.8354) (xy 9.906 -386.2578)
			)
		)
	)
)
